(kicad_pcb (version 20221018) (generator pcbnew)

  (general
    (thickness 1.62)
  )

  (paper "A4")
  (title_block
    (title "ECP5 - Datacenter Secure Control Module (DC-SCM)")
    (date "2024-07-01")
    (rev "1.2.1")
  )

  (layers
    (0 "F.Cu" signal)
    (1 "In1.Cu" power)
    (2 "In2.Cu" signal)
    (3 "In3.Cu" power)
    (4 "In4.Cu" power)
    (5 "In5.Cu" signal)
    (6 "In6.Cu" power)
    (31 "B.Cu" signal)
    (32 "B.Adhes" user "B.Adhesive")
    (33 "F.Adhes" user "F.Adhesive")
    (34 "B.Paste" user)
    (35 "F.Paste" user)
    (36 "B.SilkS" user "B.Silkscreen")
    (37 "F.SilkS" user "F.Silkscreen")
    (38 "B.Mask" user)
    (39 "F.Mask" user)
    (40 "Dwgs.User" user "User.Drawings")
    (41 "Cmts.User" user "User.Comments")
    (42 "Eco1.User" user "User.Eco1")
    (43 "Eco2.User" user "User.Eco2")
    (44 "Edge.Cuts" user)
    (45 "Margin" user)
    (46 "B.CrtYd" user "B.Courtyard")
    (47 "F.CrtYd" user "F.Courtyard")
    (48 "B.Fab" user)
    (49 "F.Fab" user)
  )

  (setup
    (stackup
      (layer "F.SilkS" (type "Top Silk Screen") (color "White"))
      (layer "F.Paste" (type "Top Solder Paste"))
      (layer "F.Mask" (type "Top Solder Mask") (color "Black") (thickness 0.01))
      (layer "F.Cu" (type "copper") (thickness 0.035))
      (layer "dielectric 1" (type "prepreg") (color "FR4 natural") (thickness 0.12) (material "PR2116") (epsilon_r 3.9) (loss_tangent 0))
      (layer "In1.Cu" (type "copper") (thickness 0.035))
      (layer "dielectric 2" (type "core") (color "FR4 natural") (thickness 0.2) (material "FR4") (epsilon_r 3.9) (loss_tangent 0.02))
      (layer "In2.Cu" (type "copper") (thickness 0.035))
      (layer "dielectric 3" (type "prepreg") (color "FR4 natural") (thickness 0.24) (material "PR2116") (epsilon_r 3.9) (loss_tangent 0.02))
      (layer "In3.Cu" (type "copper") (thickness 0.035))
      (layer "dielectric 4" (type "core") (color "FR4 natural") (thickness 0.2) (material "PR2116") (epsilon_r 3.9) (loss_tangent 0.02))
      (layer "In4.Cu" (type "copper") (thickness 0.035))
      (layer "dielectric 5" (type "prepreg") (color "FR4 natural") (thickness 0.24) (material "PR2116") (epsilon_r 3.9) (loss_tangent 0.02))
      (layer "In5.Cu" (type "copper") (thickness 0.035))
      (layer "dielectric 6" (type "core") (color "FR4 natural") (thickness 0.2) (material "FR4") (epsilon_r 3.9) (loss_tangent 0.02))
      (layer "In6.Cu" (type "copper") (thickness 0.035))
      (layer "dielectric 7" (type "prepreg") (color "FR4 natural") (thickness 0.12) (material "PR2116") (epsilon_r 3.9) (loss_tangent 0.02))
      (layer "B.Cu" (type "copper") (thickness 0.035))
      (layer "B.Mask" (type "Bottom Solder Mask") (color "Black") (thickness 0.01))
      (layer "B.Paste" (type "Bottom Solder Paste"))
      (layer "B.SilkS" (type "Bottom Silk Screen") (color "White"))
      (copper_finish "None")
      (dielectric_constraints no)
    )
    (pad_to_mask_clearance 0.05)
    (grid_origin 73.41 173.285)
    (pcbplotparams
      (layerselection 0x0001000_7fffff80)
      (plot_on_all_layers_selection 0x0000000_00000000)
      (disableapertmacros false)
      (usegerberextensions false)
      (usegerberattributes true)
      (usegerberadvancedattributes true)
      (creategerberjobfile true)
      (dashed_line_dash_ratio 12.000000)
      (dashed_line_gap_ratio 3.000000)
      (svgprecision 6)
      (plotframeref false)
      (viasonmask false)
      (mode 1)
      (useauxorigin false)
      (hpglpennumber 1)
      (hpglpenspeed 20)
      (hpglpendiameter 15.000000)
      (dxfpolygonmode true)
      (dxfimperialunits true)
      (dxfusepcbnewfont true)
      (psnegative false)
      (psa4output false)
      (plotreference true)
      (plotvalue true)
      (plotinvisibletext false)
      (sketchpadsonfab false)
      (subtractmaskfromsilk false)
      (outputformat 1)
      (mirror false)
      (drillshape 0)
      (scaleselection 1)
      (outputdirectory "")
    )
  )

  (net 0 "")
  (net 1 "GND")
  (net 2 "VCC3V3")
  (net 3 "VCC1V35")
  (net 4 "/Ethernet/AVDDH")
  (net 5 "/FPGA power supply/VCCHTX0")
  (net 6 "/FPGA power supply/VCCHTX1")
  (net 7 "Net-(J1-TRCT1)")
  (net 8 "Net-(J1-TRCT2)")
  (net 9 "/Ethernet/AVDDL")
  (net 10 "/Ethernet/AVDDL_PLL")
  (net 11 "VCC5V0")
  (net 12 "VCC1V0")
  (net 13 "Net-(J1-TRCT3)")
  (net 14 "Net-(J1-TRCT4)")
  (net 15 "VCC12V")
  (net 16 "Net-(J2-PET0_P)")
  (net 17 "Net-(J2-PET1_P)")
  (net 18 "Net-(J2-PET2_P)")
  (net 19 "JTAG_TDI")
  (net 20 "JTAG_TDO")
  (net 21 "JTAG_TCK")
  (net 22 "JTAG_TMS")
  (net 23 "I2C[5]_SDA")
  (net 24 "I2C[5]_SCL")
  (net 25 "I2C[3]_SCL")
  (net 26 "I2C[7]_SCL")
  (net 27 "I2C[3]_SDA")
  (net 28 "I2C[1]_SCL")
  (net 29 "I2C[1]_SDA")
  (net 30 "I2C[7]_SDA")
  (net 31 "I2C[2]_SDA")
  (net 32 "I2C[2]_SCL")
  (net 33 "I2C[4]_SDA")
  (net 34 "I2C[6]_SCL")
  (net 35 "I2C[6]_SDA")
  (net 36 "I2C[4]_SCL")
  (net 37 "I2C[0]_SCL")
  (net 38 "I2C[0]_SDA")
  (net 39 "UART1_SCM_RX")
  (net 40 "I2C[11]_SCL")
  (net 41 "UART0_SCM_TX")
  (net 42 "I2C[11]_SDA")
  (net 43 "I2C[9]_SCL")
  (net 44 "I2C[9]_SDA")
  (net 45 "UART0_SCM_RX")
  (net 46 "UART1_SCM_TX")
  (net 47 "I2C[10]_SDA")
  (net 48 "I2C[10]_SCL")
  (net 49 "I2C[12]_SDA")
  (net 50 "I2C[12]_SCL")
  (net 51 "I2C[8]_SCL")
  (net 52 "I2C[8]_SDA")
  (net 53 "SPI0_CS_N")
  (net 54 "SPI0_CLK")
  (net 55 "SPI0_MOSI")
  (net 56 "SPI0_MISO")
  (net 57 "P12V_AUX")
  (net 58 "PRSNT0_N")
  (net 59 "ESPI_CLK")
  (net 60 "ESPI_CS0_N")
  (net 61 "ESPI_ALERT_N")
  (net 62 "ESPI_RESET_N")
  (net 63 "ESPI_IO0")
  (net 64 "ESPI_IO1")
  (net 65 "ESPI_IO2")
  (net 66 "ESPI_IO3")
  (net 67 "ESPI_CS1_N")
  (net 68 "QSPI0_CLK")
  (net 69 "QSPI0_CS0_N")
  (net 70 "QSPI0_D0")
  (net 71 "QSPI0_D1")
  (net 72 "QSPI0_D2")
  (net 73 "QSPI0_D3")
  (net 74 "NCSI_CLK")
  (net 75 "NCSI_CRS_DV")
  (net 76 "NCSI_TXEN")
  (net 77 "NCSI_TXD0")
  (net 78 "NCSI_TXD1")
  (net 79 "NCSI_RXER")
  (net 80 "NCSI_RXD0")
  (net 81 "NCSI_RXD1")
  (net 82 "SGPIO0_DO")
  (net 83 "SGPIO0_CLK")
  (net 84 "SGPIO0_DI")
  (net 85 "SGPIO0_LD")
  (net 86 "SGPIO1_DO")
  (net 87 "SGPIO1_DI")
  (net 88 "SGPIO1_LD")
  (net 89 "SGPIO_RESET_N")
  (net 90 "SGPIO_INTR_N")
  (net 91 "QSPI0_CS1_N")
  (net 92 "QSPI1_CLK")
  (net 93 "QSPI1_CS0_N")
  (net 94 "QSPI1_D0")
  (net 95 "QSPI1_D1")
  (net 96 "QSPI1_D2")
  (net 97 "QSPI1_D3")
  (net 98 "USB2_DP")
  (net 99 "USB2_DN")
  (net 100 "USB1_DP")
  (net 101 "USB1_DN")
  (net 102 "VIRTUAL_RESEAT")
  (net 103 "CLK_100M_PCIE_DP")
  (net 104 "CLK_100M_PCIE_DN")
  (net 105 "PCIE_BMC_TX_DP")
  (net 106 "PCIE_BMC_TX_DN")
  (net 107 "PCIE_BMC_RX_DP")
  (net 108 "PCIE_BMC_RX_DN")
  (net 109 "HPM_FW_RECOVERY")
  (net 110 "HPM_STBY_RDY")
  (net 111 "HPM_STBY_EN")
  (net 112 "HPM_STBY_RST_N")
  (net 113 "SYS_PWRBTN_N")
  (net 114 "SYS_PWROK")
  (net 115 "DBP_PREQ_N")
  (net 116 "DBP_PRDY_N")
  (net 117 "RST_PLTRST_BUF_N")
  (net 118 "SPARE1")
  (net 119 "RoT_CPU_RST_N")
  (net 120 "CHASI#")
  (net 121 "SPARE0")
  (net 122 "IRQ_N")
  (net 123 "PRSNT1_N")
  (net 124 "QSPIB_CLK")
  (net 125 "QSPIB1_D0")
  (net 126 "QSPIB1_D1")
  (net 127 "QSPIB1_D2")
  (net 128 "QSPIB1_D3")
  (net 129 "QSPIB1_CS_N")
  (net 130 "QSPIB2_D0")
  (net 131 "QSPIB2_D1")
  (net 132 "QSPIB2_D2")
  (net 133 "QSPIB2_D3")
  (net 134 "QSPIB2_CS_N")
  (net 135 "QSPIA_CLK")
  (net 136 "QSPIA1_D0")
  (net 137 "QSPIA1_D1")
  (net 138 "QSPIA1_D2")
  (net 139 "QSPIA1_D3")
  (net 140 "QSPIA1_CS_N")
  (net 141 "QSPIA2_D0")
  (net 142 "QSPIA2_D1")
  (net 143 "QSPIA2_D2")
  (net 144 "QSPIA2_D3")
  (net 145 "QSPIA2_CS_N")
  (net 146 "/Ethernet/ETH3_P")
  (net 147 "/Ethernet/ETH2_P")
  (net 148 "/Ethernet/ETH1_P")
  (net 149 "/Ethernet/ETH4_P")
  (net 150 "/Ethernet/ETH2_N")
  (net 151 "/Ethernet/ETH1_N")
  (net 152 "/Ethernet/ETH3_N")
  (net 153 "/Ethernet/ETH4_N")
  (net 154 "RGMII_RXD0")
  (net 155 "RGMII_RXD1")
  (net 156 "RGMII_RXD2")
  (net 157 "RGMII_RXD3")
  (net 158 "RGMII_RX_DV")
  (net 159 "RGMII_RX_CLK")
  (net 160 "RGMII_REF_CLK")
  (net 161 "ETH_MDC")
  (net 162 "ETH_MDIO")
  (net 163 "ETH_~{RESET}")
  (net 164 "/Ethernet/ETH_LED1")
  (net 165 "/Ethernet/ETH_LED2")
  (net 166 "/DDR3/DDR3_VTT")
  (net 167 "I3C[0]_SDA_3V3")
  (net 168 "I3C[0]_SCL_3V3")
  (net 169 "I3C[1]_SDA_3V3")
  (net 170 "I3C[1]_SCL_3V3")
  (net 171 "I3C[2]_SDA_3V3")
  (net 172 "I3C[2]_SCL_3V3")
  (net 173 "I3C[3]_SDA_3V3")
  (net 174 "I3C[3]_SCL_3V3")
  (net 175 "DDR3_DQS1+")
  (net 176 "DDR3_DQS1-")
  (net 177 "DDR3_DQS0-")
  (net 178 "DDR3_DM0")
  (net 179 "DDR3_DQ15")
  (net 180 "DDR3_DQ13")
  (net 181 "DDR3_DQ14")
  (net 182 "DDR3_DQ9")
  (net 183 "DDR3_DQS0+")
  (net 184 "DDR3_DM1")
  (net 185 "DDR3_DQ12")
  (net 186 "DDR3_DQ10")
  (net 187 "DDR3_DQ11")
  (net 188 "DDR3_DQ7")
  (net 189 "DDR3_DQ5")
  (net 190 "DDR3_DQ2")
  (net 191 "DDR3_DQ1")
  (net 192 "DDR3_DQ4")
  (net 193 "DDR3_DQ3")
  (net 194 "DDR3_DQ6")
  (net 195 "DDR3_DQ8")
  (net 196 "DDR3_DQ0")
  (net 197 "ETH_INT_N")
  (net 198 "RGMII_TXD1")
  (net 199 "RGMII_TXD2")
  (net 200 "RGMII_TX_CLK")
  (net 201 "RGMII_TXD3")
  (net 202 "RGMII_TXD0")
  (net 203 "I3C[3]_SDA_1V0")
  (net 204 "I3C[3]_SCL_1V0")
  (net 205 "I3C[0]_SDA_1V0")
  (net 206 "I3C[0]_SCL_1V0")
  (net 207 "I3C[1]_SDA_1V0")
  (net 208 "I3C[1]_SCL_1V0")
  (net 209 "I3C[2]_SDA_1V0")
  (net 210 "I3C[2]_SCL_1V0")
  (net 211 "VCC1V2")
  (net 212 "Net-(J2-PET3_P)")
  (net 213 "Net-(J2-PET0_N)")
  (net 214 "Net-(J2-PET1_N)")
  (net 215 "Net-(J2-PET2_N)")
  (net 216 "Net-(J2-PET3_N)")
  (net 217 "DDR3_VREF")
  (net 218 "VCC1V8")
  (net 219 "Net-(U6-VDDIM)")
  (net 220 "Net-(U7-EN)")
  (net 221 "Net-(U8-VDDA1.8)")
  (net 222 "/Power supply/3V3_PG")
  (net 223 "/Power supply/1V8_PG")
  (net 224 "/Power supply/1V35_PG")
  (net 225 "VCC2V5")
  (net 226 "Net-(U9-VDDA1.8)")
  (net 227 "Net-(C71-Pad1)")
  (net 228 "Net-(C94-Pad1)")
  (net 229 "Net-(U12-TADJ)")
  (net 230 "/Power supply/VCCAUX_EN")
  (net 231 "/Power supply/VCCIO_EN")
  (net 232 "Net-(U13-AVIN)")
  (net 233 "Net-(C102-Pad2)")
  (net 234 "Net-(L1-Pad1)")
  (net 235 "/Power supply/1V2_PG")
  (net 236 "/Power supply/2V5_PG")
  (net 237 "DDR3_A13")
  (net 238 "DDR3_A11")
  (net 239 "DDR3_A9")
  (net 240 "DDR3_A7")
  (net 241 "DDR3_A2")
  (net 242 "DDR3_A6")
  (net 243 "DDR3_A8")
  (net 244 "DDR3_A14")
  (net 245 "DDR3_A4")
  (net 246 "DDR3_A0")
  (net 247 "DDR3_A1")
  (net 248 "DDR3_A12")
  (net 249 "DDR3_BA1")
  (net 250 "DDR3_A10")
  (net 251 "DDR3_WE")
  (net 252 "DDR3_BA2")
  (net 253 "DDR3_A5")
  (net 254 "DDR3_CAS")
  (net 255 "DDR3_A3")
  (net 256 "DDR3_BA0")
  (net 257 "DDR3_CS")
  (net 258 "DDR3_RAS")
  (net 259 "DDR3_ODT")
  (net 260 "DDR3_CKE")
  (net 261 "DDR3_CLK+")
  (net 262 "DDR3_CLK-")
  (net 263 "DDR3_RESET")
  (net 264 "CLK_PCIE_x4_DP")
  (net 265 "Net-(D6-C)")
  (net 266 "CLK_PCIE_x4_DN")
  (net 267 "Net-(U13-COMP)")
  (net 268 "PROGRAM_N")
  (net 269 "INIT_N")
  (net 270 "/Power supply/5V0_PG")
  (net 271 "ROT_QSPI_CS_N")
  (net 272 "ROT_QSPI_SCK")
  (net 273 "ROT_QSPI_DQ3")
  (net 274 "ROT_QSPI_DQ2")
  (net 275 "ROT_QSPI_DQ1")
  (net 276 "ROT_QSPI_DQ0")
  (net 277 "SGPIO1_CLK")
  (net 278 "DONE")
  (net 279 "MMC_DAT0")
  (net 280 "MMC_DAT1")
  (net 281 "MMC_DAT2")
  (net 282 "MMC_DAT3")
  (net 283 "MMC_DAT4")
  (net 284 "MMC_DAT5")
  (net 285 "MMC_DAT6")
  (net 286 "MMC_DAT7")
  (net 287 "MMC_CMD")
  (net 288 "MMC_CLK")
  (net 289 "Net-(U13-FB)")
  (net 290 "Net-(C110-Pad2)")
  (net 291 "Net-(U17-FB)")
  (net 292 "Net-(U18-FB)")
  (net 293 "USR_LED0")
  (net 294 "USR_LED1")
  (net 295 "USR_LED2")
  (net 296 "RGMII_TX_EN")
  (net 297 "unconnected-(D2-Pad11)")
  (net 298 "unconnected-(D2-Pad12)")
  (net 299 "Net-(U19-FB)")
  (net 300 "Net-(U20-FB)")
  (net 301 "Net-(U16-FB)")
  (net 302 "/FPGA power supply/VCCA0")
  (net 303 "/FPGA power supply/VCCA1")
  (net 304 "/FPGA power supply/VCCAUX")
  (net 305 "Net-(U11-REFIN)")
  (net 306 "Net-(U14-V_{PLL})")
  (net 307 "Net-(U14-V_{PHY})")
  (net 308 "Net-(D1-C)")
  (net 309 "Net-(D3-C)")
  (net 310 "Net-(D3-A)")
  (net 311 "Net-(D4-C)")
  (net 312 "Net-(D4-A)")
  (net 313 "Net-(D5-C)")
  (net 314 "Net-(D5-A)")
  (net 315 "Net-(D7-A)")
  (net 316 "Net-(D8-A)")
  (net 317 "ULPI2_RESET")
  (net 318 "ULPI2_NXT")
  (net 319 "ULPI_DIR")
  (net 320 "ULPI2_STP")
  (net 321 "ULPI2_CLKO")
  (net 322 "ULPI2_D7")
  (net 323 "ULPI2_D6")
  (net 324 "ULPI2_D5")
  (net 325 "ULPI2_D4")
  (net 326 "ULPI2_D3")
  (net 327 "ULPI2_D2")
  (net 328 "ULPI2_D1")
  (net 329 "ULPI2_D0")
  (net 330 "ULPI1_RESET")
  (net 331 "ULPI1_NXT")
  (net 332 "ULPI1_DIR")
  (net 333 "ULPI1_STP")
  (net 334 "ULPI1_CLKO")
  (net 335 "ULPI1_D7")
  (net 336 "ULPI1_D6")
  (net 337 "ULPI1_D5")
  (net 338 "ULPI1_D4")
  (net 339 "ULPI1_D3")
  (net 340 "ULPI1_D2")
  (net 341 "ULPI1_D1")
  (net 342 "ULPI1_D0")
  (net 343 "Net-(D9-A)")
  (net 344 "Net-(D10-A)")
  (net 345 "Net-(D11-A)")
  (net 346 "Net-(D12-A)")
  (net 347 "Net-(D13-A)")
  (net 348 "Net-(D14-A)")
  (net 349 "Net-(D15-C)")
  (net 350 "Net-(D15-A)")
  (net 351 "unconnected-(J2-NC-Pad6)")
  (net 352 "Net-(C106-Pad2)")
  (net 353 "unconnected-(J2-NC-Pad8)")
  (net 354 "Net-(C108-Pad2)")
  (net 355 "Net-(C118-Pad2)")
  (net 356 "Net-(C119-Pad2)")
  (net 357 "Net-(C120-Pad2)")
  (net 358 "Net-(C121-Pad2)")
  (net 359 "Net-(C122-Pad2)")
  (net 360 "unconnected-(J2-NC-Pad20)")
  (net 361 "unconnected-(J2-NC-Pad22)")
  (net 362 "unconnected-(J2-NC-Pad24)")
  (net 363 "unconnected-(J2-NC-Pad26)")
  (net 364 "Net-(R95-Pad2)")
  (net 365 "unconnected-(J2-NC-Pad28)")
  (net 366 "/Power supply/VCCA0_EN")
  (net 367 "GCLK100")
  (net 368 "Net-(C108-Pad1)")
  (net 369 "unconnected-(J2-NC-Pad30)")
  (net 370 "unconnected-(J2-NC-Pad32)")
  (net 371 "unconnected-(J2-NC-Pad34)")
  (net 372 "unconnected-(J2-NC-Pad36)")
  (net 373 "unconnected-(J2-NC-Pad38)")
  (net 374 "unconnected-(J2-SMB_CLK-Pad40)")
  (net 375 "unconnected-(J2-SMB_DATA-Pad42)")
  (net 376 "Net-(J2-ALERT)")
  (net 377 "MMC_RSTN")
  (net 378 "unconnected-(J2-NC-Pad46)")
  (net 379 "unconnected-(J2-NC-Pad48)")
  (net 380 "Net-(J2-~{CLKREQ})")
  (net 381 "Net-(J2-~{PEWAKE})")
  (net 382 "unconnected-(J2-NC-Pad56)")
  (net 383 "unconnected-(J2-NC-Pad58)")
  (net 384 "unconnected-(J2-NC-Pad67)")
  (net 385 "1V0_PG")
  (net 386 "unconnected-(J2-SUSCLK-Pad68)")
  (net 387 "unconnected-(J2-NC-Pad69)")
  (net 388 "Net-(J6-ID)")
  (net 389 "Net-(U17-SW)")
  (net 390 "Net-(U18-SW)")
  (net 391 "Net-(U19-SW)")
  (net 392 "Net-(U20-SW)")
  (net 393 "Net-(U16-SW)")
  (net 394 "Net-(Q10-D)")
  (net 395 "Net-(Q11-D)")
  (net 396 "Net-(Q12-D)")
  (net 397 "Net-(Q13-D)")
  (net 398 "Net-(Q14-D)")
  (net 399 "Net-(Q15-D)")
  (net 400 "Net-(Q16-D)")
  (net 401 "Net-(Q17-G)")
  (net 402 "Net-(U1-ISET)")
  (net 403 "Net-(U6-CLK)")
  (net 404 "Net-(U8-VBUS)")
  (net 405 "Net-(U8-RBIAS)")
  (net 406 "Net-(U9-VBUS)")
  (net 407 "Net-(U9-RBIAS)")
  (net 408 "Net-(U11-PGOOD)")
  (net 409 "ROT_RDY\\ROT_GPIO0")
  (net 410 "PIRQ#")
  (net 411 "RST")
  (net 412 "GPIO")
  (net 413 "PP")
  (net 414 "3V0_BAT")
  (net 415 "VBUS")
  (net 416 "DBG_USB_D_N")
  (net 417 "DBG_USB_D_P")
  (net 418 "Net-(U10-ZQ)")
  (net 419 "Net-(U12-FLAG1)")
  (net 420 "Net-(U12-FLAG2)")
  (net 421 "unconnected-(J5-PadB27)")
  (net 422 "Net-(U12-FLAG3)")
  (net 423 "Net-(U13-FADJ)")
  (net 424 "unconnected-(J5-PadB28)")
  (net 425 "unconnected-(J9-Pad12)")
  (net 426 "unconnected-(J9-Pad14)")
  (net 427 "Net-(U21I-PB4A)")
  (net 428 "Net-(U21I-PB4B)")
  (net 429 "Net-(U21I-PB6B)")
  (net 430 "DDR3_VTT_EN")
  (net 431 "Net-(U21I-PB6A)")
  (net 432 "Net-(U14-~{RESET})")
  (net 433 "Net-(U14-REF)")
  (net 434 "Net-(U14-DDBUS7)")
  (net 435 "Net-(U14-~{PWR_{EN}})")
  (net 436 "Net-(U14-~{SUSPEND})")
  (net 437 "Net-(U6-DS)")
  (net 438 "unconnected-(U1-NC-Pad13)")
  (net 439 "unconnected-(U1-LDO_O-Pad43)")
  (net 440 "unconnected-(U1-XO-Pad45)")
  (net 441 "unconnected-(U1-NC-Pad47)")
  (net 442 "unconnected-(U6-NC-PadA1)")
  (net 443 "unconnected-(U6-NC-PadA2)")
  (net 444 "unconnected-(U6-NC-PadA9)")
  (net 445 "unconnected-(U6-NC-PadA10)")
  (net 446 "unconnected-(U6-NC-PadB1)")
  (net 447 "unconnected-(U6-NC-PadB10)")
  (net 448 "unconnected-(U6-VSF1-PadD2)")
  (net 449 "unconnected-(U6-VSF2-PadD3)")
  (net 450 "unconnected-(U6-VSF3-PadD4)")
  (net 451 "unconnected-(U6-VSF4-PadD5)")
  (net 452 "unconnected-(U6-VSF5-PadD6)")
  (net 453 "unconnected-(U6-VSF6-PadD7)")
  (net 454 "unconnected-(U6-VSF7-PadD8)")
  (net 455 "unconnected-(U6-VSF8-PadD9)")
  (net 456 "unconnected-(U6-RFU-PadE2)")
  (net 457 "unconnected-(U6-RFU-PadE3)")
  (net 458 "unconnected-(U6-RFU-PadE5)")
  (net 459 "unconnected-(U6-RFU-PadE6)")
  (net 460 "unconnected-(U6-RFU-PadE7)")
  (net 461 "unconnected-(U6-RFU-PadE8)")
  (net 462 "unconnected-(U6-RFU-PadE9)")
  (net 463 "unconnected-(U6-RFU-PadH4)")
  (net 464 "unconnected-(U6-RFU-PadH5)")
  (net 465 "unconnected-(U6-RFU-PadH6)")
  (net 466 "unconnected-(U6-RFU-PadH7)")
  (net 467 "unconnected-(U6-RFU-PadJ2)")
  (net 468 "unconnected-(U6-RFU-PadJ3)")
  (net 469 "unconnected-(U6-RFU-PadJ4)")
  (net 470 "unconnected-(U6-RFU-PadJ6)")
  (net 471 "unconnected-(U6-RFU-PadJ7)")
  (net 472 "unconnected-(U6-RFU-PadJ8)")
  (net 473 "unconnected-(U6-RFU-PadJ9)")
  (net 474 "unconnected-(U6-RFU-PadK4)")
  (net 475 "unconnected-(U6-RFU-PadK6)")
  (net 476 "unconnected-(U6-RFU-PadK7)")
  (net 477 "unconnected-(U6-RFU-PadL5)")
  (net 478 "unconnected-(U6-RFU-PadL6)")
  (net 479 "unconnected-(U6-RFU-PadM2)")
  (net 480 "unconnected-(U6-RFU-PadM3)")
  (net 481 "unconnected-(U6-RFU-PadM6)")
  (net 482 "unconnected-(U6-RFU-PadM8)")
  (net 483 "unconnected-(U6-RFU-PadM9)")
  (net 484 "unconnected-(U6-RFU-PadN4)")
  (net 485 "unconnected-(U6-RFU-PadN5)")
  (net 486 "unconnected-(U6-RFU-PadN6)")
  (net 487 "unconnected-(U6-RFU-PadN7)")
  (net 488 "unconnected-(U6-RFU-PadP4)")
  (net 489 "unconnected-(U6-RFU-PadP7)")
  (net 490 "unconnected-(U6-NC-PadT1)")
  (net 491 "unconnected-(U6-NC-PadT10)")
  (net 492 "unconnected-(U6-NC-PadU1)")
  (net 493 "unconnected-(U6-NC-PadU2)")
  (net 494 "unconnected-(U6-NC-PadU9)")
  (net 495 "unconnected-(U6-NC-PadU10)")
  (net 496 "unconnected-(U8-CPEN-Pad3)")
  (net 497 "unconnected-(U8-ID-Pad5)")
  (net 498 "unconnected-(U8-EXTVBUS-Pad10)")
  (net 499 "unconnected-(U8-XO-Pad27)")
  (net 500 "unconnected-(U9-CPEN-Pad3)")
  (net 501 "unconnected-(U9-ID-Pad5)")
  (net 502 "unconnected-(U9-EXTVBUS-Pad10)")
  (net 503 "unconnected-(U9-XO-Pad27)")
  (net 504 "unconnected-(U10-NC{slash}ODT1-PadJ1)")
  (net 505 "unconnected-(U10-NC{slash}CKE1-PadJ9)")
  (net 506 "unconnected-(U10-NC{slash}~{CS1}-PadL1)")
  (net 507 "unconnected-(U10-NC{slash}ZQ1-PadL9)")
  (net 508 "unconnected-(U10-NC{slash}A15-PadM7)")
  (net 509 "unconnected-(U13-SS-Pad2)")
  (net 510 "unconnected-(U14-EECS-Pad1)")
  (net 511 "/Interfaces/FTDI_CLK")
  (net 512 "unconnected-(U14-OSCO-Pad4)")
  (net 513 "unconnected-(U14-ADBUS4-Pad17)")
  (net 514 "unconnected-(U14-ADBUS5-Pad18)")
  (net 515 "unconnected-(U14-ADBUS6-Pad19)")
  (net 516 "unconnected-(U14-ADBUS7-Pad20)")
  (net 517 "unconnected-(U14-BDBUS0-Pad22)")
  (net 518 "unconnected-(U14-BDBUS1-Pad23)")
  (net 519 "unconnected-(U14-BDBUS2-Pad24)")
  (net 520 "unconnected-(U14-BDBUS3-Pad25)")
  (net 521 "unconnected-(U14-BDBUS4-Pad26)")
  (net 522 "unconnected-(U14-BDBUS5-Pad27)")
  (net 523 "unconnected-(U14-BDBUS6-Pad28)")
  (net 524 "unconnected-(U14-BDBUS7-Pad29)")
  (net 525 "unconnected-(U14-CDBUS0-Pad32)")
  (net 526 "unconnected-(U14-CDBUS1-Pad33)")
  (net 527 "unconnected-(U14-CDBUS2-Pad34)")
  (net 528 "unconnected-(U14-CDBUS3-Pad35)")
  (net 529 "unconnected-(U14-CDBUS4-Pad37)")
  (net 530 "unconnected-(U14-CDBUS5-Pad38)")
  (net 531 "unconnected-(U14-CDBUS6-Pad39)")
  (net 532 "unconnected-(U14-CDBUS7-Pad40)")
  (net 533 "unconnected-(U14-DDBUS0-Pad42)")
  (net 534 "unconnected-(U14-DDBUS1-Pad46)")
  (net 535 "unconnected-(U14-DDBUS2-Pad47)")
  (net 536 "unconnected-(U14-DDBUS3-Pad48)")
  (net 537 "unconnected-(U14-DDBUS4-Pad49)")
  (net 538 "unconnected-(U14-DDBUS5-Pad51)")
  (net 539 "unconnected-(U14-DDBUS6-Pad52)")
  (net 540 "unconnected-(U14-EEDATA-Pad55)")
  (net 541 "unconnected-(U14-EECLK-Pad56)")
  (net 542 "unconnected-(U16-NC-Pad4)")
  (net 543 "unconnected-(U17-NC-Pad4)")
  (net 544 "unconnected-(U18-NC-Pad4)")
  (net 545 "unconnected-(U19-NC-Pad4)")
  (net 546 "unconnected-(U20-NC-Pad4)")
  (net 547 "unconnected-(U21B-PT13B-PadA7)")
  (net 548 "unconnected-(U21B-PT24B-PadA9)")
  (net 549 "unconnected-(U21B-PT31B-PadA10)")
  (net 550 "unconnected-(U21B-PT38B-PadA11)")
  (net 551 "unconnected-(U21B-PT42B-PadA13)")
  (net 552 "unconnected-(U21B-PT54B-PadA15)")
  (net 553 "unconnected-(U21C-PT71A-PadA18)")
  (net 554 "unconnected-(U21E-PR74C-PadAB26)")
  (net 555 "unconnected-(U21A-NC-PadAC4)")
  (net 556 "unconnected-(U21E-PR77C-PadAC26)")
  (net 557 "unconnected-(U21E-PR74D-PadAC27)")
  (net 558 "unconnected-(U21E-PR83C-PadAC28)")
  (net 559 "unconnected-(U21A-NC-PadAC29)")
  (net 560 "unconnected-(U21E-PR89A-PadAC30)")
  (net 561 "unconnected-(U21E-PR77D-PadAD26)")
  (net 562 "unconnected-(U21E-PR80A-PadAD27)")
  (net 563 "unconnected-(U21E-PR83D-PadAD29)")
  (net 564 "unconnected-(U21E-PR86C-PadAD30)")
  (net 565 "unconnected-(U21A-NC-PadAE7)")
  (net 566 "unconnected-(U21A-NC-PadAE26)")
  (net 567 "unconnected-(U21E-PR80B-PadAE27)")
  (net 568 "unconnected-(U21E-PR80C-PadAE28)")
  (net 569 "unconnected-(U21E-PR80D-PadAE29)")
  (net 570 "unconnected-(U21E-PR86D-PadAE30)")
  (net 571 "unconnected-(U21A-NC-PadAG2)")
  (net 572 "unconnected-(U21A-NC-PadAG24)")
  (net 573 "unconnected-(U21A-NC-PadAG31)")
  (net 574 "unconnected-(U21I-PB13B-PadAH3)")
  (net 575 "unconnected-(U21I-PB15A-PadAJ3)")
  (net 576 "unconnected-(U21I-CFG_2-PadAK4)")
  (net 577 "unconnected-(U21K-HDTXP0_D0CH1-PadAK12)")
  (net 578 "unconnected-(U21K-HDTXN0_D0CH1-PadAK13)")
  (net 579 "unconnected-(U21A-RESERVED-PadAK15)")
  (net 580 "unconnected-(U21A-RESERVED-PadAK16)")
  (net 581 "unconnected-(U21L-HDTXP0_D1CH0-PadAK18)")
  (net 582 "unconnected-(U21L-HDTXN0_D1CH0-PadAK19)")
  (net 583 "unconnected-(U21L-HDTXP0_D1CH1-PadAK21)")
  (net 584 "unconnected-(U21L-HDTXN0_D1CH1-PadAK22)")
  (net 585 "unconnected-(U21A-RESERVED-PadAK24)")
  (net 586 "unconnected-(U21A-RESERVED-PadAK25)")
  (net 587 "unconnected-(U21I-CFG_1-PadAL4)")
  (net 588 "unconnected-(U21I-CFG_0-PadAM4)")
  (net 589 "unconnected-(U21K-HDRXP0_D0CH1-PadAM11)")
  (net 590 "unconnected-(U21K-HDRXN0_D0CH1-PadAM12)")
  (net 591 "unconnected-(U21L-HDRXP0_D1CH0-PadAM17)")
  (net 592 "unconnected-(U21L-HDRXN0_D1CH0-PadAM18)")
  (net 593 "unconnected-(U21L-HDRXP0_D1CH1-PadAM20)")
  (net 594 "unconnected-(U21L-HDRXN0_D1CH1-PadAM21)")
  (net 595 "unconnected-(U21L-REFCLKP_D1-PadAM23)")
  (net 596 "unconnected-(U21L-REFCLKN_D1-PadAM24)")
  (net 597 "unconnected-(U21B-PT4A-PadB3)")
  (net 598 "unconnected-(U21B-PT4B-PadB4)")
  (net 599 "unconnected-(U21B-PT13A-PadB7)")
  (net 600 "unconnected-(U21B-PT31A-PadB10)")
  (net 601 "unconnected-(U21B-PT38A-PadB11)")
  (net 602 "unconnected-(U21B-PT49A-PadB14)")
  (net 603 "unconnected-(U21D-PR17A-PadB32)")
  (net 604 "unconnected-(U21H-PL11D-PadC3)")
  (net 605 "unconnected-(U21H-PL11C-PadC4)")
  (net 606 "unconnected-(U21H-PL11A-PadC5)")
  (net 607 "unconnected-(U21B-PT11B-PadC7)")
  (net 608 "unconnected-(U21B-PT24A-PadC9)")
  (net 609 "unconnected-(U21B-PT29B-PadC10)")
  (net 610 "unconnected-(U21B-PT36B-PadC11)")
  (net 611 "unconnected-(U21B-PT42A-PadC13)")
  (net 612 "unconnected-(U21B-PT47B-PadC14)")
  (net 613 "unconnected-(U21B-PT54A-PadC15)")
  (net 614 "unconnected-(U21C-PT71B-PadC18)")
  (net 615 "unconnected-(U21D-PR11A-PadC28)")
  (net 616 "unconnected-(U21D-PR11C-PadC29)")
  (net 617 "unconnected-(U21D-PR17B-PadC31)")
  (net 618 "unconnected-(U21D-PR20C-PadC32)")
  (net 619 "unconnected-(U21H-PL17C-PadD3)")
  (net 620 "unconnected-(U21H-PL14A-PadD4)")
  (net 621 "unconnected-(U21H-PL11B-PadD5)")
  (net 622 "unconnected-(U21B-PT11A-PadD7)")
  (net 623 "unconnected-(U21B-PT22B-PadD9)")
  (net 624 "unconnected-(U21B-PT29A-PadD10)")
  (net 625 "unconnected-(U21B-PT36A-PadD11)")
  (net 626 "unconnected-(U21B-PT40B-PadD13)")
  (net 627 "unconnected-(U21B-PT47A-PadD14)")
  (net 628 "unconnected-(U21D-PR11B-PadD28)")
  (net 629 "unconnected-(U21D-PR14A-PadD29)")
  (net 630 "unconnected-(U21D-PR17C-PadD30)")
  (net 631 "unconnected-(U21D-PR17D-PadD31)")
  (net 632 "unconnected-(U21D-PR20D-PadD32)")
  (net 633 "unconnected-(U21H-PL14B-PadE4)")
  (net 634 "unconnected-(U21A-NC-PadE7)")
  (net 635 "unconnected-(U21B-PT15B-PadE8)")
  (net 636 "unconnected-(U21B-PT27B-PadE10)")
  (net 637 "unconnected-(U21B-PT33B-PadE11)")
  (net 638 "unconnected-(U21B-PT45B-PadE14)")
  (net 639 "unconnected-(U21C-PT69A-PadE17)")
  (net 640 "unconnected-(U21A-NC-PadE26)")
  (net 641 "unconnected-(U21D-PR14B-PadE29)")
  (net 642 "unconnected-(U21D-PR20B-PadE30)")
  (net 643 "unconnected-(U21D-PR23B-PadE32)")
  (net 644 "unconnected-(U21H-PL20A-PadF3)")
  (net 645 "unconnected-(U21H-PL14C-PadF4)")
  (net 646 "unconnected-(U21H-PL14D-PadF5)")
  (net 647 "unconnected-(U21B-PT15A-PadF8)")
  (net 648 "unconnected-(U21B-PT22A-PadF9)")
  (net 649 "unconnected-(U21B-PT27A-PadF10)")
  (net 650 "unconnected-(U21B-PT33A-PadF11)")
  (net 651 "unconnected-(U21B-PT40A-PadF13)")
  (net 652 "unconnected-(U21B-PT45A-PadF14)")
  (net 653 "unconnected-(U21B-PT51A-PadF15)")
  (net 654 "unconnected-(U21B-PT56A-PadF16)")
  (net 655 "unconnected-(U21C-PT69B-PadF17)")
  (net 656 "unconnected-(U21C-PT74B-PadF18)")
  (net 657 "VREGOUT")
  (net 658 "unconnected-(U21D-PR14D-PadF28)")
  (net 659 "ROT_MISO")
  (net 660 "ROT_MOSI")
  (net 661 "ROT_SS")
  (net 662 "ROT_TX")
  (net 663 "ROT_RX")
  (net 664 "ROT_SCLK")
  (net 665 "ROT_GPIO2")
  (net 666 "ROT_GPIO1")
  (net 667 "unconnected-(U21D-PR14C-PadF29)")
  (net 668 "unconnected-(U21D-PR20A-PadF30)")
  (net 669 "unconnected-(U21D-PR23A-PadF31)")
  (net 670 "unconnected-(U21D-PR23C-PadF32)")
  (net 671 "unconnected-(U21A-NC-PadG9)")
  (net 672 "Net-(C76-Pad2)")
  (net 673 "unconnected-(U21A-NC-PadG10)")
  (net 674 "unconnected-(U21A-NC-PadG11)")
  (net 675 "unconnected-(U21A-NC-PadG14)")
  (net 676 "/Ethernet/PHY_CLK")
  (net 677 "unconnected-(U21A-NC-PadG15)")
  (net 678 "/Interfaces/USB2_CLK")
  (net 679 "/Interfaces/USB1_CLK")
  (net 680 "Net-(J1-Pad13)")
  (net 681 "Net-(J1-Pad15)")
  (net 682 "unconnected-(U21A-NC-PadG16)")
  (net 683 "unconnected-(U21A-NC-PadG17)")
  (net 684 "unconnected-(U21A-NC-PadG18)")
  (net 685 "unconnected-(U21A-NC-PadG19)")
  (net 686 "/FPGA banks/PCIE_BMC_TX_C_DN")
  (net 687 "/FPGA banks/PCIE_BMC_TX_C_DP")
  (net 688 "PCIE_HPM_TX0_P")
  (net 689 "PCIE_HPM_TX1_P")
  (net 690 "PCIE_HPM_TX2_P")
  (net 691 "PCIE_HPM_TX3_P")
  (net 692 "PCIE_HPM_TX0_N")
  (net 693 "PCIE_HPM_TX1_N")
  (net 694 "PCIE_HPM_TX2_N")
  (net 695 "PCIE_HPM_TX3_N")
  (net 696 "PCIE_HPM_RX3_N")
  (net 697 "PCIE_HPM_RX3_P")
  (net 698 "PCIE_HPM_RX2_N")
  (net 699 "PCIE_HPM_RX2_P")
  (net 700 "PCIE_HPM_RX1_N")
  (net 701 "PCIE_HPM_RX1_P")
  (net 702 "PCIE_HPM_RX0_P")
  (net 703 "PCIE_HPM_RX0_N")
  (net 704 "unconnected-(U21A-NC-PadG22)")
  (net 705 "unconnected-(U21A-NC-PadG23)")
  (net 706 "unconnected-(U21A-NC-PadG24)")
  (net 707 "unconnected-(U21H-PL23D-PadH1)")
  (net 708 "unconnected-(U21H-PL26A-PadH2)")
  (net 709 "unconnected-(U21H-PL26B-PadH3)")
  (net 710 "unconnected-(U21A-NC-PadH4)")
  (net 711 "unconnected-(U21H-PL35B-PadH5)")
  (net 712 "unconnected-(U21H-PL35A-PadH6)")
  (net 713 "unconnected-(U21D-PR35A-PadH27)")
  (net 714 "unconnected-(U21D-PR35B-PadH28)")
  (net 715 "unconnected-(U21A-NC-PadH29)")
  (net 716 "unconnected-(U21H-PL29B-PadJ1)")
  (net 717 "unconnected-(U21H-PL26C-PadJ3)")
  (net 718 "unconnected-(U21H-PL32C-PadJ4)")
  (net 719 "unconnected-(U21D-PR35C-PadJ26)")
  (net 720 "unconnected-(U21D-PR35D-PadJ27)")
  (net 721 "unconnected-(U21D-PR32C-PadJ29)")
  (net 722 "unconnected-(U21D-PR26C-PadJ30)")
  (net 723 "unconnected-(U21H-PL29C-PadK1)")
  (net 724 "unconnected-(U21H-PL29A-PadK2)")
  (net 725 "unconnected-(U21H-PL26D-PadK3)")
  (net 726 "unconnected-(U21H-PL32D-PadK4)")
  (net 727 "unconnected-(U21D-PR38B-PadK26)")
  (net 728 "unconnected-(U21D-PR38A-PadK27)")
  (net 729 "unconnected-(U21D-PR38C-PadK28)")
  (net 730 "unconnected-(U21D-PR32D-PadK29)")
  (net 731 "unconnected-(U21H-PL29D-PadL1)")
  (net 732 "unconnected-(U21H-PL32A-PadL2)")
  (net 733 "unconnected-(U21A-NC-PadL5)")
  (net 734 "unconnected-(U21H-PL41D-PadL6)")
  (net 735 "unconnected-(U21D-PR41C-PadL26)")
  (net 736 "unconnected-(U21D-PR41D-PadL27)")
  (net 737 "unconnected-(U21A-NC-PadL28)")
  (net 738 "unconnected-(U21D-PR38D-PadL29)")
  (net 739 "unconnected-(U21D-PR32B-PadL30)")
  (net 740 "unconnected-(U21G-PL62A-PadN1)")
  (net 741 "unconnected-(U21H-PL44B-PadN7)")
  (net 742 "unconnected-(U21D-PR44B-PadN26)")
  (net 743 "unconnected-(U21D-PR44A-PadN27)")
  (net 744 "unconnected-(U21D-PR41B-PadN29)")
  (net 745 "unconnected-(U21D-PR41A-PadN30)")
  (net 746 "unconnected-(U21G-PL62B-PadP1)")
  (net 747 "unconnected-(U21G-PL59A-PadP2)")
  (net 748 "unconnected-(U21G-PL59B-PadP3)")
  (net 749 "unconnected-(U21H-PL44D-PadP7)")
  (net 750 "unconnected-(U21D-PR44D-PadP26)")
  (net 751 "unconnected-(U21D-PR44C-PadP27)")
  (net 752 "unconnected-(U21E-PR47B-PadP29)")
  (net 753 "unconnected-(U21G-PL59C-PadR3)")
  (net 754 "unconnected-(U21E-PR59C-PadR30)")
  (net 755 "unconnected-(U21G-PL68A-PadT1)")
  (net 756 "unconnected-(U21G-PL59D-PadT3)")
  (net 757 "unconnected-(U21E-PR47D-PadT26)")
  (net 758 "unconnected-(U21E-PR59D-PadT30)")
  (net 759 "unconnected-(U21G-PL68B-PadU1)")
  (net 760 "unconnected-(U21G-PL62C-PadU2)")
  (net 761 "unconnected-(U21G-PL62D-PadU3)")
  (net 762 "unconnected-(U21E-PR62D-PadU30)")
  (net 763 "unconnected-(U21G-PL68C-PadV1)")
  (net 764 "unconnected-(U21A-NC-PadV3)")
  (net 765 "unconnected-(U21E-PR56D-PadV26)")
  (net 766 "unconnected-(U21E-PR56C-PadV27)")
  (net 767 "unconnected-(U21A-NC-PadV30)")
  (net 768 "unconnected-(U21G-PL68D-PadW1)")
  (net 769 "unconnected-(U21G-PL65C-PadW3)")
  (net 770 "unconnected-(U21A-NC-PadW6)")
  (net 771 "unconnected-(U21A-NC-PadW27)")
  (net 772 "unconnected-(U21E-PR71D-PadW28)")
  (net 773 "unconnected-(U21E-PR74B-PadW29)")
  (net 774 "unconnected-(U21G-PL65D-PadY3)")
  (net 775 "unconnected-(U21E-PR71A-PadY26)")
  (net 776 "unconnected-(U7-EP-Pad21)")
  (net 777 "Net-(D1-A)")
  (net 778 "unconnected-(H1-Pad1)")
  (net 779 "unconnected-(H2-Pad1)")
  (net 780 "Net-(U15-SS{slash}TR)")
  (net 781 "Net-(U15-COMP)")
  (net 782 "Net-(U15-BOOT)")
  (net 783 "Net-(U15-RT{slash}CLK)")
  (net 784 "Net-(U15-FB)")
  (net 785 "Net-(U15-EN)")

  (footprint "antmicro-footprints:R_0402_1005Metric" (layer "F.Cu")
    (at 71.4 124.67 90)
    (descr "Resistor SMD 0402")
    (tags "resistor SMD 0402")
    (property "Author" "Antmicro")
    (property "License" "Apache-2.0")
    (property "MPN" "CR0402-FX-1002GLF")
    (property "Manufacturer" "Bourns")
    (property "Public" "False")
    (property "Sheetfile" "ddr3.kicad_sch")
    (property "Sheetname" "DDR3")
    (property "Tolerance" "1%")
    (property "Val" "10k")
    (property "ki_description" "SMD Chip Resistor, 10 kohm, ± 1%, 62.5 mW, 0402 [1005 Metric], Thick Film, General Purpose")
    (property "ki_keywords" "0402, SMT, RESISTOR, PASSIVE")
    (attr smd)
    (fp_text reference "R79" (at -3.38 -0.03 90) (layer "F.SilkS")
        (effects (font (size 0.7 0.7) (thickness 0.127)))
    )
    (fp_text value "R_10k_0402" (at 0 1.17 90) (layer "F.Fab")
        (effects (font (size 1 1) (thickness 0.15)))
    )
    (fp_text user "${REFERENCE}" (at 0 0 90) (layer "F.Fab")
        (effects (font (size 0.25 0.25) (thickness 0.04)))
    )
    (fp_text user "Author: Antmicro" (at -0.95 4.169 90) (layer "F.Fab") hide
        (effects (font (size 0.7 0.7) (thickness 0.15)) (justify left bottom))
    )
    (fp_text user "License: Apache-2.0" (at -0.95 5.169 90) (layer "F.Fab") hide
        (effects (font (size 0.7 0.7) (thickness 0.15)) (justify left bottom))
    )
    (fp_rect (start -0.925 -0.47) (end 0.925 0.47)
      (stroke (width 0.05) (type default)) (fill none) (layer "F.CrtYd"))
    (fp_rect (start -0.5 -0.25) (end 0.5 0.25)
      (stroke (width 0.15) (type solid)) (fill none) (layer "F.Fab"))
    (pad "1" smd roundrect (at -0.48 0 90) (size 0.59 0.64) (layers "F.Cu" "F.Paste" "F.Mask") (roundrect_rratio 0.25)
      (net 3 "VCC1V35") (pintype "passive"))
    (pad "2" smd roundrect (at 0.48 0 90) (size 0.59 0.64) (layers "F.Cu" "F.Paste" "F.Mask") (roundrect_rratio 0.25)
      (net 305 "Net-(U11-REFIN)") (pintype "passive"))
  )

  (footprint "antmicro-footprints:R_0402_1005Metric" (layer "F.Cu")
    (at 74.45 61.2)
    (descr "Resistor SMD 0402")
    (tags "resistor SMD 0402")
    (property "Author" "Antmicro")
    (property "License" "Apache-2.0")
    (property "MPN" "CR0402-FX-49R9GLF")
    (property "Manufacturer" "Bourns")
    (property "Public" "False")
    (property "Sheetfile" "power-supply.kicad_sch")
    (property "Sheetname" "Power supply")
    (property "Tolerance" "1%")
    (property "Val" "49R9")
    (property "ki_description" "SMD Chip Resistor, 49.9 ohm, ± 1%, 62.5 mW, 0402 [1005 Metric], Thick Film, General Purpose")
    (property "ki_keywords" "0402, SMT, RESISTOR, PASSIVE")
    (attr smd)
    (fp_text reference "R95" (at -0.6 -1.75) (layer "F.SilkS")
        (effects (font (size 0.7 0.7) (thickness 0.127)))
    )
    (fp_text value "R_49R9_0402" (at 0 1.17) (layer "F.Fab")
        (effects (font (size 1 1) (thickness 0.15)))
    )
    (fp_text user "${REFERENCE}" (at 0 0) (layer "F.Fab")
        (effects (font (size 0.25 0.25) (thickness 0.04)))
    )
    (fp_text user "License: Apache-2.0" (at -0.95 5.169) (layer "F.Fab") hide
        (effects (font (size 0.7 0.7) (thickness 0.15)) (justify left bottom))
    )
    (fp_text user "Author: Antmicro" (at -0.95 4.169) (layer "F.Fab") hide
        (effects (font (size 0.7 0.7) (thickness 0.15)) (justify left bottom))
    )
    (fp_rect (start -0.925 -0.47) (end 0.925 0.47)
      (stroke (width 0.05) (type default)) (fill none) (layer "F.CrtYd"))
    (fp_rect (start -0.5 -0.25) (end 0.5 0.25)
      (stroke (width 0.15) (type solid)) (fill none) (layer "F.Fab"))
    (pad "1" smd roundrect (at -0.48 0) (size 0.59 0.64) (layers "F.Cu" "F.Paste" "F.Mask") (roundrect_rratio 0.25)
      (net 290 "Net-(C110-Pad2)") (pintype "passive"))
    (pad "2" smd roundrect (at 0.48 0) (size 0.59 0.64) (layers "F.Cu" "F.Paste" "F.Mask") (roundrect_rratio 0.25)
      (net 364 "Net-(R95-Pad2)") (pintype "passive"))
  )

  (footprint "antmicro-footprints:C_0603_1608Metric" (layer "F.Cu")
    (at 76.85 68.65 -90)
    (descr "Capacitor SMD 0603")
    (tags "capacitor 0603")
    (property "Author" "Antmicro")
    (property "Dielectric" "")
    (property "License" "Apache-2.0")
    (property "MPN" "GRM188R60J476ME15D")
    (property "Manufacturer" "Murata")
    (property "Public" "False")
    (property "Sheetfile" "power-supply.kicad_sch")
    (property "Sheetname" "Power supply")
    (property "Val" "47u")
    (property "Voltage" "")
    (property "ki_description" "SMD Multilayer Ceramic Capacitor, 47 µF, 6.3 V, 0603 [1608 Metric], ± 20%, X5R, GRM Series")
    (property "ki_keywords" "0603, SMT, CAPACITOR, PASSIVE, CERAMIC, MLCC")
    (attr smd)
    (fp_text reference "C110" (at -0.065 2.37 90) (layer "F.SilkS")
        (effects (font (size 0.7 0.7) (thickness 0.127)))
    )
    (fp_text value "C_47u_0603" (at 0 1.91 90) (layer "F.Fab")
        (effects (font (size 1 1) (thickness 0.15)))
    )
    (fp_text user "Author: Antmicro" (at -1.682 4.894 -90) (layer "F.Fab") hide
        (effects (font (size 0.7 0.7) (thickness 0.15)) (justify left bottom))
    )
    (fp_text user "License: Apache-2.0" (at -1.682 5.895 -90) (layer "F.Fab") hide
        (effects (font (size 0.7 0.7) (thickness 0.15)) (justify left bottom))
    )
    (fp_text user "${REFERENCE}" (at -1.682 3.895 -90) (layer "F.Fab") hide
        (effects (font (size 0.7 0.7) (thickness 0.15)) (justify left bottom))
    )
    (fp_line (start -0.15 -0.4) (end 0.15 -0.4)
      (stroke (width 0.15) (type solid)) (layer "F.SilkS"))
    (fp_line (start -0.15 0.4) (end 0.15 0.4)
      (stroke (width 0.15) (type solid)) (layer "F.SilkS"))
    (fp_rect (start -1.25 -0.65) (end 1.25 0.65)
      (stroke (width 0.05) (type solid)) (fill none) (layer "F.CrtYd"))
    (fp_rect (start -0.8 -0.4) (end 0.8 0.4)
      (stroke (width 0.15) (type solid)) (fill none) (layer "F.Fab"))
    (pad "1" smd roundrect (at -0.7 0 270) (size 0.8 1) (layers "F.Cu" "F.Paste" "F.Mask") (roundrect_rratio 0.2)
      (net 1 "GND") (pintype "passive"))
    (pad "2" smd roundrect (at 0.7 0 270) (size 0.8 1) (layers "F.Cu" "F.Paste" "F.Mask") (roundrect_rratio 0.2)
      (net 290 "Net-(C110-Pad2)") (pintype "passive"))
  )

  (footprint "antmicro-footprints:WSON-10-1EP_4x4mm_P0.8mm_EP2.6x3mm" (layer "F.Cu")
    (at 78.8 65 180)
    (property "Author" "Antmicro")
    (property "License" "Apache-2.0")
    (property "MPN" "TPS54561QDPRRQ1")
    (property "Manufacturer" "Texas Instruments")
    (property "Sheetfile" "power-supply.kicad_sch")
    (property "Sheetname" "Power supply")
    (property "ki_description" "DC/DC converter")
    (property "ki_keywords" "SMT, PMIC, IC, SWITCHING, VOLTAGE, REGULATOR, DC-DC")
    (attr smd)
    (fp_text reference "U15" (at 1.5 3.335) (layer "F.SilkS")
        (effects (font (size 0.7 0.7) (thickness 0.15)) (justify left bottom))
    )
    (fp_text value "TPS54561QDPRRQ1" (at 0 3.4) (layer "F.Fab")
        (effects (font (size 0.7 0.7) (thickness 0.15)) (justify left bottom))
    )
    (fp_text user "Author: Antmicro" (at -2.52 6.6 180) (layer "F.Fab") hide
        (effects (font (size 0.7 0.7) (thickness 0.15)) (justify left bottom))
    )
    (fp_text user "License: Apache-2.0" (at -2.52 7.8 180) (layer "F.Fab") hide
        (effects (font (size 0.7 0.7) (thickness 0.15)) (justify left bottom))
    )
    (fp_text user "${REFERENCE}" (at -2.52 5.4 180) (layer "F.Fab") hide
        (effects (font (size 0.7 0.7) (thickness 0.15)) (justify left bottom))
    )
    (fp_line (start -2.1 -2.123) (end -2.1 -1.975)
      (stroke (width 0.15) (type solid)) (layer "F.SilkS"))
    (fp_line (start -2.1 -2.123) (end 2.1 -2.123)
      (stroke (width 0.15) (type solid)) (layer "F.SilkS"))
    (fp_line (start -2.1 2.123) (end -2.1 1.975)
      (stroke (width 0.15) (type solid)) (layer "F.SilkS"))
    (fp_line (start 2.1 -2.123) (end 2.1 -1.975)
      (stroke (width 0.15) (type solid)) (layer "F.SilkS"))
    (fp_line (start 2.1 2.122) (end -2.1 2.122)
      (stroke (width 0.15) (type solid)) (layer "F.SilkS"))
    (fp_line (start 2.1 2.122) (end 2.1 1.975)
      (stroke (width 0.15) (type solid)) (layer "F.SilkS"))
    (fp_circle (center -2.325 -2.05) (end -2.275 -2.05)
      (stroke (width 0.15) (type solid)) (fill solid) (layer "F.SilkS"))
    (fp_rect (start -2.57 -2.2) (end 2.469 2.2)
      (stroke (width 0.05) (type solid)) (fill none) (layer "F.CrtYd"))
    (fp_line (start -2 -1.5) (end -1.5 -2)
      (stroke (width 0.15) (type solid)) (layer "F.Fab"))
    (fp_line (start -2 2) (end -2 -1.5)
      (stroke (width 0.15) (type solid)) (layer "F.Fab"))
    (fp_line (start -1.5 -2) (end 2 -2)
      (stroke (width 0.15) (type solid)) (layer "F.Fab"))
    (fp_line (start 2 -2) (end 2 2)
      (stroke (width 0.15) (type solid)) (layer "F.Fab"))
    (fp_line (start 2 2) (end -2 2)
      (stroke (width 0.15) (type solid)) (layer "F.Fab"))
    (pad "1" smd roundrect (at -1.9 -1.6 270) (size 0.3 0.6) (layers "F.Cu" "F.Paste" "F.Mask") (roundrect_rratio 0.1666666667)
      (net 782 "Net-(U15-BOOT)") (pinfunction "BOOT") (pintype "output"))
    (pad "2" smd roundrect (at -1.9 -0.8 270) (size 0.3 0.6) (layers "F.Cu" "F.Paste" "F.Mask") (roundrect_rratio 0.1666666667)
      (net 15 "VCC12V") (pinfunction "V_{DD}") (pintype "power_in"))
    (pad "3" smd roundrect (at -1.9 0 270) (size 0.3 0.6) (layers "F.Cu" "F.Paste" "F.Mask") (roundrect_rratio 0.1666666667)
      (net 785 "Net-(U15-EN)") (pinfunction "EN") (pintype "input"))
    (pad "4" smd roundrect (at -1.9 0.8 270) (size 0.3 0.6) (layers "F.Cu" "F.Paste" "F.Mask") (roundrect_rratio 0.1666666667)
      (net 780 "Net-(U15-SS{slash}TR)") (pinfunction "SS/TR") (pintype "input"))
    (pad "5" smd roundrect (at -1.9 1.6 270) (size 0.3 0.6) (layers "F.Cu" "F.Paste" "F.Mask") (roundrect_rratio 0.1666666667)
      (net 783 "Net-(U15-RT{slash}CLK)") (pinfunction "RT/CLK") (pintype "input"))
    (pad "6" smd roundrect (at 1.9 1.6 270) (size 0.3 0.6) (layers "F.Cu" "F.Paste" "F.Mask") (roundrect_rratio 0.1666666667)
      (net 784 "Net-(U15-FB)") (pinfunction "FB") (pintype "input"))
    (pad "7" smd roundrect (at 1.9 0.8 270) (size 0.3 0.6) (layers "F.Cu" "F.Paste" "F.Mask") (roundrect_rratio 0.1666666667)
      (net 781 "Net-(U15-COMP)") (pinfunction "COMP") (pintype "output"))
    (pad "8" smd roundrect (at 1.9 0 270) (size 0.3 0.6) (layers "F.Cu" "F.Paste" "F.Mask") (roundrect_rratio 0.1666666667)
      (net 1 "GND") (pinfunction "GND") (pintype "power_in"))
    (pad "9" smd roundrect (at 1.9 -0.8 270) (size 0.3 0.6) (layers "F.Cu" "F.Paste" "F.Mask") (roundrect_rratio 0.1666666667)
      (net 265 "Net-(D6-C)") (pinfunction "SW") (pintype "power_out"))
    (pad "10" smd roundrect (at 1.9 -1.6 270) (size 0.3 0.6) (layers "F.Cu" "F.Paste" "F.Mask") (roundrect_rratio 0.1666666667)
      (net 270 "/Power supply/5V0_PG") (pinfunction "PWRGD") (pintype "output"))
    (pad "11" smd roundrect (at 0 0 180) (size 2.6 3) (layers "F.Cu" "F.Paste" "F.Mask") (roundrect_rratio 0.01923076923)
      (net 1 "GND") (pinfunction "GND") (pintype "passive"))
  )

  (footprint "antmicro-footprints:C_0603_1608Metric" (layer "F.Cu")
    (at 78.35 68.65 -90)
    (descr "Capacitor SMD 0603")
    (tags "capacitor 0603")
    (property "Author" "Antmicro")
    (property "Dielectric" "")
    (property "License" "Apache-2.0")
    (property "MPN" "GRM188R60J476ME15D")
    (property "Manufacturer" "Murata")
    (property "Public" "False")
    (property "Sheetfile" "power-supply.kicad_sch")
    (property "Sheetname" "Power supply")
    (property "Val" "47u")
    (property "Voltage" "")
    (property "ki_description" "SMD Multilayer Ceramic Capacitor, 47 µF, 6.3 V, 0603 [1608 Metric], ± 20%, X5R, GRM Series")
    (property "ki_keywords" "0603, SMT, CAPACITOR, PASSIVE, CERAMIC, MLCC")
    (attr smd)
    (fp_text reference "C111" (at -0.065 2.94 90) (layer "F.SilkS")
        (effects (font (size 0.7 0.7) (thickness 0.127)))
    )
    (fp_text value "C_47u_0603" (at 0 1.9 90) (layer "F.Fab")
        (effects (font (size 1 1) (thickness 0.15)))
    )
    (fp_text user "License: Apache-2.0" (at -1.682 5.895 -90) (layer "F.Fab") hide
        (effects (font (size 0.7 0.7) (thickness 0.15)) (justify left bottom))
    )
    (fp_text user "${REFERENCE}" (at -1.682 3.895 -90) (layer "F.Fab") hide
        (effects (font (size 0.7 0.7) (thickness 0.15)) (justify left bottom))
    )
    (fp_text user "Author: Antmicro" (at -1.682 4.894 -90) (layer "F.Fab") hide
        (effects (font (size 0.7 0.7) (thickness 0.15)) (justify left bottom))
    )
    (fp_line (start -0.15 -0.4) (end 0.15 -0.4)
      (stroke (width 0.15) (type solid)) (layer "F.SilkS"))
    (fp_line (start -0.15 0.4) (end 0.15 0.4)
      (stroke (width 0.15) (type solid)) (layer "F.SilkS"))
    (fp_rect (start -1.25 -0.65) (end 1.25 0.65)
      (stroke (width 0.05) (type solid)) (fill none) (layer "F.CrtYd"))
    (fp_rect (start -0.8 -0.4) (end 0.8 0.4)
      (stroke (width 0.15) (type solid)) (fill none) (layer "F.Fab"))
    (pad "1" smd roundrect (at -0.7 0 270) (size 0.8 1) (layers "F.Cu" "F.Paste" "F.Mask") (roundrect_rratio 0.2)
      (net 1 "GND") (pintype "passive"))
    (pad "2" smd roundrect (at 0.7 0 270) (size 0.8 1) (layers "F.Cu" "F.Paste" "F.Mask") (roundrect_rratio 0.2)
      (net 290 "Net-(C110-Pad2)") (pintype "passive"))
  )

  (footprint "antmicro-footprints:VSON-10-1EP_3x3mm" (layer "F.Cu")
    (at 73.822 120.904 90)
    (property "Author" "Antmicro")
    (property "License" "Apache-2.0")
    (property "MPN" "TPS51200DRCT")
    (property "Manufacturer" "Texas Instruments")
    (property "Sheetfile" "ddr3.kicad_sch")
    (property "Sheetname" "DDR3")
    (property "ki_description" "Fixed LDO Voltage Regulator, 2.375 V to 3.5 V, 0.8 V Dropout, 1.25 V / 3 A out, VSON-10")
    (property "ki_keywords" "SMT, PMIC, IC")
    (attr smd)
    (fp_text reference "U11" (at -1.051 2.588 90) (layer "F.SilkS")
        (effects (font (size 0.7 0.7) (thickness 0.15)) (justify left bottom))
    )
    (fp_text value "TPS51200DRCT" (at -2 2.7 90) (layer "F.Fab")
        (effects (font (size 0.7 0.7) (thickness 0.15)) (justify left bottom))
    )
    (fp_text user "." (at -2.05 -1.65 90) (layer "F.SilkS") hide
        (effects (font (size 0.7 0.7) (thickness 0.15)) (justify left bottom))
    )
    (fp_text user "Author: Antmicro" (at -2 4.7 90) (layer "F.Fab") hide
        (effects (font (size 0.7 0.7) (thickness 0.15)) (justify left bottom))
    )
    (fp_text user "${REFERENCE}" (at -2 5.9 90) (layer "F.Fab") hide
        (effects (font (size 0.7 0.7) (thickness 0.15)) (justify left bottom))
    )
    (fp_text user "License: Apache-2.0" (at -2 7.1 90) (layer "F.Fab") hide
        (effects (font (size 0.7 0.7) (thickness 0.15)) (justify left bottom))
    )
    (fp_line (start -1.5 1.598) (end 1.499 1.598)
      (stroke (width 0.15) (type solid)) (layer "F.SilkS"))
    (fp_line (start 0 -1.621) (end 1.499 -1.621)
      (stroke (width 0.15) (type solid)) (layer "F.SilkS"))
    (fp_line (start -1.97 1.215) (end -1.97 -1.24)
      (stroke (width 0.05) (type solid)) (layer "F.CrtYd"))
    (fp_line (start -1.65 -1.65) (end -1.65 -1.24)
      (stroke (width 0.05) (type solid)) (layer "F.CrtYd"))
    (fp_line (start -1.65 -1.24) (end -1.97 -1.24)
      (stroke (width 0.05) (type solid)) (layer "F.CrtYd"))
    (fp_line (start -1.65 1.215) (end -1.97 1.215)
      (stroke (width 0.05) (type solid)) (layer "F.CrtYd"))
    (fp_line (start -1.65 1.215) (end -1.65 1.625)
      (stroke (width 0.05) (type solid)) (layer "F.CrtYd"))
    (fp_line (start -1.65 1.625) (end 1.65 1.625)
      (stroke (width 0.05) (type solid)) (layer "F.CrtYd"))
    (fp_line (start 1.65 -1.65) (end -1.65 -1.65)
      (stroke (width 0.05) (type solid)) (layer "F.CrtYd"))
    (fp_line (start 1.65 -1.24) (end 1.65 -1.65)
      (stroke (width 0.05) (type solid)) (layer "F.CrtYd"))
    (fp_line (start 1.65 -1.24) (end 1.97 -1.24)
      (stroke (width 0.05) (type solid)) (layer "F.CrtYd"))
    (fp_line (start 1.65 1.215) (end 1.97 1.215)
      (stroke (width 0.05) (type solid)) (layer "F.CrtYd"))
    (fp_line (start 1.65 1.625) (end 1.65 1.215)
      (stroke (width 0.05) (type solid)) (layer "F.CrtYd"))
    (fp_line (start 1.97 -1.24) (end 1.97 1.215)
      (stroke (width 0.05) (type solid)) (layer "F.CrtYd"))
    (fp_line (start -1.5 -0.76) (end -0.75 -1.51)
      (stroke (width 0.15) (type solid)) (layer "F.Fab"))
    (fp_line (start -1.5 1.489) (end -1.5 -0.76)
      (stroke (width 0.15) (type solid)) (layer "F.Fab"))
    (fp_line (start -0.75 -1.51) (end 1.499 -1.51)
      (stroke (width 0.15) (type solid)) (layer "F.Fab"))
    (fp_line (start 1.499 -1.51) (end 1.499 1.489)
      (stroke (width 0.15) (type solid)) (layer "F.Fab"))
    (fp_line (start 1.499 1.489) (end -1.5 1.489)
      (stroke (width 0.15) (type solid)) (layer "F.Fab"))
    (pad "" smd roundrect (at -0.3 -0.51 90) (size 0.48 0.81) (layers "F.Paste") (roundrect_rratio 0.25))
    (pad "" smd roundrect (at -0.3 0.488 90) (size 0.48 0.81) (layers "F.Paste") (roundrect_rratio 0.25))
    (pad "" smd roundrect (at 0.299 -0.51 90) (size 0.48 0.81) (layers "F.Paste") (roundrect_rratio 0.25))
    (pad "" smd roundrect (at 0.299 0.488 90) (size 0.48 0.81) (layers "F.Paste") (roundrect_rratio 0.25))
    (pad "1" smd roundrect (at -1.438 -1.01 90) (size 0.875 0.25) (layers "F.Cu" "F.Paste" "F.Mask") (roundrect_rratio 0.25)
      (net 305 "Net-(U11-REFIN)") (pinfunction "REFIN") (pintype "input"))
    (pad "2" smd roundrect (at -1.438 -0.51 90) (size 0.875 0.25) (layers "F.Cu" "F.Paste" "F.Mask") (roundrect_rratio 0.25)
      (net 3 "VCC1V35") (pinfunction "VLDOIN") (pintype "power_in"))
    (pad "3" smd roundrect (at -1.438 -0.011 90) (size 0.875 0.25) (layers "F.Cu" "F.Paste" "F.Mask") (roundrect_rratio 0.25)
      (net 166 "/DDR3/DDR3_VTT") (pinfunction "VO") (pintype "power_out"))
    (pad "4" smd roundrect (at -1.438 0.488 90) (size 0.875 0.25) (layers "F.Cu" "F.Paste" "F.Mask") (roundrect_rratio 0.25)
      (net 1 "GND") (pinfunction "GND") (pintype "passive"))
    (pad "5" smd roundrect (at -1.438 0.988 90) (size 0.875 0.25) (layers "F.Cu" "F.Paste" "F.Mask") (roundrect_rratio 0.25)
      (net 166 "/DDR3/DDR3_VTT") (pinfunction "VOSNS") (pintype "input"))
    (pad "6" smd roundrect (at 1.437 0.988 90) (size 0.875 0.25) (layers "F.Cu" "F.Paste" "F.Mask") (roundrect_rratio 0.25)
      (net 217 "DDR3_VREF") (pinfunction "REFOUT") (pintype "power_out"))
    (pad "7" smd roundrect (at 1.437 0.488 90) (size 0.875 0.25) (layers "F.Cu" "F.Paste" "F.Mask") (roundrect_rratio 0.25)
      (net 430 "DDR3_VTT_EN") (pinfunction "EN") (pintype "input"))
    (pad "8" smd roundrect (at 1.437 -0.011 90) (size 0.875 0.25) (layers "F.Cu" "F.Paste" "F.Mask") (roundrect_rratio 0.25)
      (net 1 "GND") (pinfunction "GND") (pintype "power_in"))
    (pad "9" smd roundrect (at 1.437 -0.51 90) (size 0.875 0.25) (layers "F.Cu" "F.Paste" "F.Mask") (roundrect_rratio 0.25)
      (net 408 "Net-(U11-PGOOD)") (pinfunction "PGOOD") (pintype "open_collector"))
    (pad "10" smd roundrect (at 1.437 -1.01 90) (size 0.875 0.25) (layers "F.Cu" "F.Paste" "F.Mask") (roundrect_rratio 0.25)
      (net 2 "VCC3V3") (pinfunction "VIN") (pintype "power_in"))
    (pad "11" smd roundrect (at 0 -0.011 90) (size 1.2 2) (layers "F.Cu" "F.Mask") (roundrect_rratio 0.208333)
      (net 1 "GND") (pinfunction "GND") (pintype "passive"))
  )

  (footprint "antmicro-footprints:C_0402_1005Metric" (layer "F.Cu")
    (at 72.384 124.67 90)
    (descr "Capacitor SMD 0402")
    (tags "capacitor SMD 0402")
    (property "Author" "Antmicro")
    (property "Dielectric" "X5R")
    (property "License" "Apache-2.0")
    (property "MPN" "GRM155R61H104KE14D")
    (property "Manufacturer" "Murata")
    (property "Public" "False")
    (property "Sheetfile" "ddr3.kicad_sch")
    (property "Sheetname" "DDR3")
    (property "Val" "100n")
    (property "Voltage" "50V")
    (property "ki_description" "SMD Multilayer Ceramic Capacitor, 0.1 µF, 50 V, 0402 [1005 Metric], ± 10%, X5R, GRM Series")
    (property "ki_keywords" "0402, SMT, CAPACITOR, PASSIVE, CERAMIC, MLCC")
    (attr smd)
    (fp_text reference "C240" (at -3.755 -0.004 90) (layer "F.SilkS")
        (effects (font (size 0.7 0.7) (thickness 0.127)))
    )
    (fp_text value "C_100n_0402" (at 0 1.17 90) (layer "F.Fab")
        (effects (font (size 1 1) (thickness 0.15)))
    )
    (fp_text user "License: Apache-2.0" (at -0.939 5.799 90) (layer "F.Fab") hide
        (effects (font (size 0.7 0.7) (thickness 0.15)) (justify left bottom))
    )
    (fp_text user "Author: Antmicro" (at -0.939 3.399 90) (layer "F.Fab") hide
        (effects (font (size 0.7 0.7) (thickness 0.15)) (justify left bottom))
    )
    (fp_text user "${REFERENCE}" (at 0 0 90) (layer "F.Fab")
        (effects (font (size 0.25 0.25) (thickness 0.04)))
    )
    (fp_rect (start -0.925 -0.47) (end 0.925 0.47)
      (stroke (width 0.05) (type default)) (fill none) (layer "F.CrtYd"))
    (fp_line (start -0.494 -0.25) (end 0.504 -0.25)
      (stroke (width 0.15) (type solid)) (layer "F.Fab"))
    (fp_line (start -0.494 0.248) (end -0.494 -0.25)
      (stroke (width 0.15) (type solid)) (layer "F.Fab"))
    (fp_line (start 0.504 -0.25) (end 0.504 0.248)
      (stroke (width 0.15) (type solid)) (layer "F.Fab"))
    (fp_line (start 0.504 0.248) (end -0.494 0.248)
      (stroke (width 0.15) (type solid)) (layer "F.Fab"))
    (pad "1" smd roundrect (at -0.48 0 90) (size 0.59 0.64) (layers "F.Cu" "F.Paste" "F.Mask") (roundrect_rratio 0.25)
      (net 1 "GND") (pintype "passive"))
    (pad "2" smd roundrect (at 0.48 0 90) (size 0.59 0.64) (layers "F.Cu" "F.Paste" "F.Mask") (roundrect_rratio 0.25)
      (net 3 "VCC1V35") (pintype "passive"))
  )

  (footprint "antmicro-footprints:C_0402_1005Metric" (layer "F.Cu")
    (at 75.32 117.92 180)
    (descr "Capacitor SMD 0402")
    (tags "capacitor SMD 0402")
    (property "Author" "Antmicro")
    (property "Dielectric" "X5R")
    (property "License" "Apache-2.0")
    (property "MPN" "GRM155R61H104KE14D")
    (property "Manufacturer" "Murata")
    (property "Public" "False")
    (property "Sheetfile" "ddr3.kicad_sch")
    (property "Sheetname" "DDR3")
    (property "Val" "100n")
    (property "Voltage" "50V")
    (property "ki_description" "SMD Multilayer Ceramic Capacitor, 0.1 µF, 50 V, 0402 [1005 Metric], ± 10%, X5R, GRM Series")
    (property "ki_keywords" "0402, SMT, CAPACITOR, PASSIVE, CERAMIC, MLCC")
    (attr smd)
    (fp_text reference "C201" (at -2.2 -0.035 180) (layer "F.SilkS")
        (effects (font (size 0.7 0.7) (thickness 0.127)))
    )
    (fp_text value "C_100n_0402" (at 0 1.17) (layer "F.Fab")
        (effects (font (size 1 1) (thickness 0.15)))
    )
    (fp_text user "${REFERENCE}" (at 0 0) (layer "F.Fab")
        (effects (font (size 0.25 0.25) (thickness 0.04)))
    )
    (fp_text user "License: Apache-2.0" (at -0.939 5.799 180) (layer "F.Fab") hide
        (effects (font (size 0.7 0.7) (thickness 0.15)) (justify left bottom))
    )
    (fp_text user "Author: Antmicro" (at -0.939 3.399 180) (layer "F.Fab") hide
        (effects (font (size 0.7 0.7) (thickness 0.15)) (justify left bottom))
    )
    (fp_rect (start -0.925 -0.47) (end 0.925 0.47)
      (stroke (width 0.05) (type default)) (fill none) (layer "F.CrtYd"))
    (fp_line (start -0.494 -0.25) (end 0.504 -0.25)
      (stroke (width 0.15) (type solid)) (layer "F.Fab"))
    (fp_line (start -0.494 0.248) (end -0.494 -0.25)
      (stroke (width 0.15) (type solid)) (layer "F.Fab"))
    (fp_line (start 0.504 -0.25) (end 0.504 0.248)
      (stroke (width 0.15) (type solid)) (layer "F.Fab"))
    (fp_line (start 0.504 0.248) (end -0.494 0.248)
      (stroke (width 0.15) (type solid)) (layer "F.Fab"))
    (pad "1" smd roundrect (at -0.48 0 180) (size 0.59 0.64) (layers "F.Cu" "F.Paste" "F.Mask") (roundrect_rratio 0.25)
      (net 1 "GND") (pintype "passive"))
    (pad "2" smd roundrect (at 0.48 0 180) (size 0.59 0.64) (layers "F.Cu" "F.Paste" "F.Mask") (roundrect_rratio 0.25)
      (net 217 "DDR3_VREF") (pintype "passive"))
  )

  (footprint "antmicro-footprints:C_0402_1005Metric" (layer "F.Cu")
    (at 74.352 124.67 90)
    (descr "Capacitor SMD 0402")
    (tags "capacitor SMD 0402")
    (property "Author" "Antmicro")
    (property "Dielectric" "")
    (property "License" "Apache-2.0")
    (property "MPN" "CC0402MRX5R5BB106")
    (property "Manufacturer" "YAGEO")
    (property "Public" "False")
    (property "Sheetfile" "ddr3.kicad_sch")
    (property "Sheetname" "DDR3")
    (property "Val" "10u")
    (property "Voltage" "")
    (property "ki_description" "SMD Multilayer Ceramic Capacitor, 10 µF, 6.3 V, 0402 [1005 Metric], ± 20%, X5R, CC Series")
    (property "ki_keywords" "0402, SMT, CAPACITOR, PASSIVE, MLCC, CERAMIC")
    (attr smd)
    (fp_text reference "C199" (at -3.735 0.058 90) (layer "F.SilkS")
        (effects (font (size 0.7 0.7) (thickness 0.127)))
    )
    (fp_text value "C_10u_0402" (at 0 1.17 90) (layer "F.Fab")
        (effects (font (size 1 1) (thickness 0.15)))
    )
    (fp_text user "Author: Antmicro" (at -0.939 3.399 90) (layer "F.Fab") hide
        (effects (font (size 0.7 0.7) (thickness 0.15)) (justify left bottom))
    )
    (fp_text user "License: Apache-2.0" (at -0.939 5.799 90) (layer "F.Fab") hide
        (effects (font (size 0.7 0.7) (thickness 0.15)) (justify left bottom))
    )
    (fp_text user "${REFERENCE}" (at 0 0 90) (layer "F.Fab")
        (effects (font (size 0.25 0.25) (thickness 0.04)))
    )
    (fp_rect (start -0.925 -0.47) (end 0.925 0.47)
      (stroke (width 0.05) (type default)) (fill none) (layer "F.CrtYd"))
    (fp_line (start -0.494 -0.25) (end 0.504 -0.25)
      (stroke (width 0.15) (type solid)) (layer "F.Fab"))
    (fp_line (start -0.494 0.248) (end -0.494 -0.25)
      (stroke (width 0.15) (type solid)) (layer "F.Fab"))
    (fp_line (start 0.504 -0.25) (end 0.504 0.248)
      (stroke (width 0.15) (type solid)) (layer "F.Fab"))
    (fp_line (start 0.504 0.248) (end -0.494 0.248)
      (stroke (width 0.15) (type solid)) (layer "F.Fab"))
    (pad "1" smd roundrect (at -0.48 0 90) (size 0.59 0.64) (layers "F.Cu" "F.Paste" "F.Mask") (roundrect_rratio 0.25)
      (net 1 "GND") (pintype "passive"))
    (pad "2" smd roundrect (at 0.48 0 90) (size 0.59 0.64) (layers "F.Cu" "F.Paste" "F.Mask") (roundrect_rratio 0.25)
      (net 166 "/DDR3/DDR3_VTT") (pintype "passive"))
  )

  (footprint "antmicro-footprints:R_0402_1005Metric" (layer "F.Cu")
    (at 71.9 118.07)
    (descr "Resistor SMD 0402")
    (tags "resistor SMD 0402")
    (property "Author" "Antmicro")
    (property "License" "Apache-2.0")
    (property "MPN" "CR0402-FX-1002GLF")
    (property "Manufacturer" "Bourns")
    (property "Public" "False")
    (property "Sheetfile" "ddr3.kicad_sch")
    (property "Sheetname" "DDR3")
    (property "Tolerance" "1%")
    (property "Val" "10k")
    (property "ki_description" "SMD Chip Resistor, 10 kohm, ± 1%, 62.5 mW, 0402 [1005 Metric], Thick Film, General Purpose")
    (property "ki_keywords" "0402, SMT, RESISTOR, PASSIVE")
    (attr smd)
    (fp_text reference "R80" (at -1.89 -0.085) (layer "F.SilkS")
        (effects (font (size 0.7 0.7) (thickness 0.127)))
    )
    (fp_text value "R_10k_0402" (at 0 1.17) (layer "F.Fab")
        (effects (font (size 1 1) (thickness 0.15)))
    )
    (fp_text user "License: Apache-2.0" (at -0.95 5.169) (layer "F.Fab") hide
        (effects (font (size 0.7 0.7) (thickness 0.15)) (justify left bottom))
    )
    (fp_text user "${REFERENCE}" (at 0 0) (layer "F.Fab")
        (effects (font (size 0.25 0.25) (thickness 0.04)))
    )
    (fp_text user "Author: Antmicro" (at -0.95 4.169) (layer "F.Fab") hide
        (effects (font (size 0.7 0.7) (thickness 0.15)) (justify left bottom))
    )
    (fp_rect (start -0.925 -0.47) (end 0.925 0.47)
      (stroke (width 0.05) (type default)) (fill none) (layer "F.CrtYd"))
    (fp_rect (start -0.5 -0.25) (end 0.5 0.25)
      (stroke (width 0.15) (type solid)) (fill none) (layer "F.Fab"))
    (pad "1" smd roundrect (at -0.48 0) (size 0.59 0.64) (layers "F.Cu" "F.Paste" "F.Mask") (roundrect_rratio 0.25)
      (net 2 "VCC3V3") (pintype "passive"))
    (pad "2" smd roundrect (at 0.48 0) (size 0.59 0.64) (layers "F.Cu" "F.Paste" "F.Mask") (roundrect_rratio 0.25)
      (net 408 "Net-(U11-PGOOD)") (pintype "passive"))
  )

  (footprint "antmicro-footprints:R_0402_1005Metric" (layer "F.Cu")
    (at 70.42 122.04 90)
    (descr "Resistor SMD 0402")
    (tags "resistor SMD 0402")
    (property "Author" "Antmicro")
    (property "License" "Apache-2.0")
    (property "MPN" "CR0402-FX-1002GLF")
    (property "Manufacturer" "Bourns")
    (property "Public" "False")
    (property "Sheetfile" "ddr3.kicad_sch")
    (property "Sheetname" "DDR3")
    (property "Tolerance" "1%")
    (property "Val" "10k")
    (property "ki_description" "SMD Chip Resistor, 10 kohm, ± 1%, 62.5 mW, 0402 [1005 Metric], Thick Film, General Purpose")
    (property "ki_keywords" "0402, SMT, RESISTOR, PASSIVE")
    (attr smd)
    (fp_text reference "R78" (at 0.03 -2.16 90) (layer "F.SilkS")
        (effects (font (size 0.7 0.7) (thickness 0.127)))
    )
    (fp_text value "R_10k_0402" (at 0 1.17 90) (layer "F.Fab")
        (effects (font (size 1 1) (thickness 0.15)))
    )
    (fp_text user "License: Apache-2.0" (at -0.95 5.169 90) (layer "F.Fab") hide
        (effects (font (size 0.7 0.7) (thickness 0.15)) (justify left bottom))
    )
    (fp_text user "Author: Antmicro" (at -0.95 4.169 90) (layer "F.Fab") hide
        (effects (font (size 0.7 0.7) (thickness 0.15)) (justify left bottom))
    )
    (fp_text user "${REFERENCE}" (at 0 0 90) (layer "F.Fab")
        (effects (font (size 0.25 0.25) (thickness 0.04)))
    )
    (fp_rect (start -0.925 -0.47) (end 0.925 0.47)
      (stroke (width 0.05) (type default)) (fill none) (layer "F.CrtYd"))
    (fp_rect (start -0.5 -0.25) (end 0.5 0.25)
      (stroke (width 0.15) (type solid)) (fill none) (layer "F.Fab"))
    (pad "1" smd roundrect (at -0.48 0 90) (size 0.59 0.64) (layers "F.Cu" "F.Paste" "F.Mask") (roundrect_rratio 0.25)
      (net 305 "Net-(U11-REFIN)") (pintype "passive"))
    (pad "2" smd roundrect (at 0.48 0 90) (size 0.59 0.64) (layers "F.Cu" "F.Paste" "F.Mask") (roundrect_rratio 0.25)
      (net 1 "GND") (pintype "passive"))
  )

  (footprint "antmicro-footprints:C_0402_1005Metric" (layer "F.Cu")
    (at 76.32 124.67 90)
    (descr "Capacitor SMD 0402")
    (tags "capacitor SMD 0402")
    (property "Author" "Antmicro")
    (property "Dielectric" "")
    (property "License" "Apache-2.0")
    (property "MPN" "CC0402MRX5R5BB106")
    (property "Manufacturer" "YAGEO")
    (property "Public" "False")
    (property "Sheetfile" "ddr3.kicad_sch")
    (property "Sheetname" "DDR3")
    (property "Val" "10u")
    (property "Voltage" "")
    (property "ki_description" "SMD Multilayer Ceramic Capacitor, 10 µF, 6.3 V, 0402 [1005 Metric], ± 20%, X5R, CC Series")
    (property "ki_keywords" "0402, SMT, CAPACITOR, PASSIVE, MLCC, CERAMIC")
    (attr smd)
    (fp_text reference "C197" (at -3.765 0.02 270) (layer "F.SilkS")
        (effects (font (size 0.7 0.7) (thickness 0.127)))
    )
    (fp_text value "C_10u_0402" (at 0 1.17 90) (layer "F.Fab")
        (effects (font (size 1 1) (thickness 0.15)))
    )
    (fp_text user "License: Apache-2.0" (at -0.939 5.799 90) (layer "F.Fab") hide
        (effects (font (size 0.7 0.7) (thickness 0.15)) (justify left bottom))
    )
    (fp_text user "${REFERENCE}" (at 0 0 90) (layer "F.Fab")
        (effects (font (size 0.25 0.25) (thickness 0.04)))
    )
    (fp_text user "Author: Antmicro" (at -0.939 3.399 90) (layer "F.Fab") hide
        (effects (font (size 0.7 0.7) (thickness 0.15)) (justify left bottom))
    )
    (fp_rect (start -0.925 -0.47) (end 0.925 0.47)
      (stroke (width 0.05) (type default)) (fill none) (layer "F.CrtYd"))
    (fp_line (start -0.494 -0.25) (end 0.504 -0.25)
      (stroke (width 0.15) (type solid)) (layer "F.Fab"))
    (fp_line (start -0.494 0.248) (end -0.494 -0.25)
      (stroke (width 0.15) (type solid)) (layer "F.Fab"))
    (fp_line (start 0.504 -0.25) (end 0.504 0.248)
      (stroke (width 0.15) (type solid)) (layer "F.Fab"))
    (fp_line (start 0.504 0.248) (end -0.494 0.248)
      (stroke (width 0.15) (type solid)) (layer "F.Fab"))
    (pad "1" smd roundrect (at -0.48 0 90) (size 0.59 0.64) (layers "F.Cu" "F.Paste" "F.Mask") (roundrect_rratio 0.25)
      (net 1 "GND") (pintype "passive"))
    (pad "2" smd roundrect (at 0.48 0 90) (size 0.59 0.64) (layers "F.Cu" "F.Paste" "F.Mask") (roundrect_rratio 0.25)
      (net 166 "/DDR3/DDR3_VTT") (pintype "passive"))
  )

  (footprint "antmicro-footprints:C_0402_1005Metric" (layer "F.Cu")
    (at 73.368 124.67 90)
    (descr "Capacitor SMD 0402")
    (tags "capacitor SMD 0402")
    (property "Author" "Antmicro")
    (property "Dielectric" "X5R")
    (property "License" "Apache-2.0")
    (property "MPN" "GRM155R61H104KE14D")
    (property "Manufacturer" "Murata")
    (property "Public" "False")
    (property "Sheetfile" "ddr3.kicad_sch")
    (property "Sheetname" "DDR3")
    (property "Val" "100n")
    (property "Voltage" "50V")
    (property "ki_description" "SMD Multilayer Ceramic Capacitor, 0.1 µF, 50 V, 0402 [1005 Metric], ± 10%, X5R, GRM Series")
    (property "ki_keywords" "0402, SMT, CAPACITOR, PASSIVE, CERAMIC, MLCC")
    (attr smd)
    (fp_text reference "C202" (at -3.745 0.032 90) (layer "F.SilkS")
        (effects (font (size 0.7 0.7) (thickness 0.127)))
    )
    (fp_text value "C_100n_0402" (at 0 1.17 90) (layer "F.Fab")
        (effects (font (size 1 1) (thickness 0.15)))
    )
    (fp_text user "Author: Antmicro" (at -0.939 3.399 90) (layer "F.Fab") hide
        (effects (font (size 0.7 0.7) (thickness 0.15)) (justify left bottom))
    )
    (fp_text user "${REFERENCE}" (at 0 0 90) (layer "F.Fab")
        (effects (font (size 0.25 0.25) (thickness 0.04)))
    )
    (fp_text user "License: Apache-2.0" (at -0.939 5.799 90) (layer "F.Fab") hide
        (effects (font (size 0.7 0.7) (thickness 0.15)) (justify left bottom))
    )
    (fp_rect (start -0.925 -0.47) (end 0.925 0.47)
      (stroke (width 0.05) (type default)) (fill none) (layer "F.CrtYd"))
    (fp_line (start -0.494 -0.25) (end 0.504 -0.25)
      (stroke (width 0.15) (type solid)) (layer "F.Fab"))
    (fp_line (start -0.494 0.248) (end -0.494 -0.25)
      (stroke (width 0.15) (type solid)) (layer "F.Fab"))
    (fp_line (start 0.504 -0.25) (end 0.504 0.248)
      (stroke (width 0.15) (type solid)) (layer "F.Fab"))
    (fp_line (start 0.504 0.248) (end -0.494 0.248)
      (stroke (width 0.15) (type solid)) (layer "F.Fab"))
    (pad "1" smd roundrect (at -0.48 0 90) (size 0.59 0.64) (layers "F.Cu" "F.Paste" "F.Mask") (roundrect_rratio 0.25)
      (net 1 "GND") (pintype "passive"))
    (pad "2" smd roundrect (at 0.48 0 90) (size 0.59 0.64) (layers "F.Cu" "F.Paste" "F.Mask") (roundrect_rratio 0.25)
      (net 3 "VCC1V35") (pintype "passive"))
  )

  (footprint "antmicro-footprints:C_0402_1005Metric" (layer "F.Cu")
    (at 75.336 124.67 90)
    (descr "Capacitor SMD 0402")
    (tags "capacitor SMD 0402")
    (property "Author" "Antmicro")
    (property "Dielectric" "")
    (property "License" "Apache-2.0")
    (property "MPN" "CC0402MRX5R5BB106")
    (property "Manufacturer" "YAGEO")
    (property "Public" "False")
    (property "Sheetfile" "ddr3.kicad_sch")
    (property "Sheetname" "DDR3")
    (property "Val" "10u")
    (property "Voltage" "")
    (property "ki_description" "SMD Multilayer Ceramic Capacitor, 10 µF, 6.3 V, 0402 [1005 Metric], ± 20%, X5R, CC Series")
    (property "ki_keywords" "0402, SMT, CAPACITOR, PASSIVE, MLCC, CERAMIC")
    (attr smd)
    (fp_text reference "C198" (at -3.745 0.004 90) (layer "F.SilkS")
        (effects (font (size 0.7 0.7) (thickness 0.127)))
    )
    (fp_text value "C_10u_0402" (at 0 1.17 90) (layer "F.Fab")
        (effects (font (size 1 1) (thickness 0.15)))
    )
    (fp_text user "License: Apache-2.0" (at -0.939 5.799 90) (layer "F.Fab") hide
        (effects (font (size 0.7 0.7) (thickness 0.15)) (justify left bottom))
    )
    (fp_text user "${REFERENCE}" (at 0 0 90) (layer "F.Fab")
        (effects (font (size 0.25 0.25) (thickness 0.04)))
    )
    (fp_text user "Author: Antmicro" (at -0.939 3.399 90) (layer "F.Fab") hide
        (effects (font (size 0.7 0.7) (thickness 0.15)) (justify left bottom))
    )
    (fp_rect (start -0.925 -0.47) (end 0.925 0.47)
      (stroke (width 0.05) (type default)) (fill none) (layer "F.CrtYd"))
    (fp_line (start -0.494 -0.25) (end 0.504 -0.25)
      (stroke (width 0.15) (type solid)) (layer "F.Fab"))
    (fp_line (start -0.494 0.248) (end -0.494 -0.25)
      (stroke (width 0.15) (type solid)) (layer "F.Fab"))
    (fp_line (start 0.504 -0.25) (end 0.504 0.248)
      (stroke (width 0.15) (type solid)) (layer "F.Fab"))
    (fp_line (start 0.504 0.248) (end -0.494 0.248)
      (stroke (width 0.15) (type solid)) (layer "F.Fab"))
    (pad "1" smd roundrect (at -0.48 0 90) (size 0.59 0.64) (layers "F.Cu" "F.Paste" "F.Mask") (roundrect_rratio 0.25)
      (net 1 "GND") (pintype "passive"))
    (pad "2" smd roundrect (at 0.48 0 90) (size 0.59 0.64) (layers "F.Cu" "F.Paste" "F.Mask") (roundrect_rratio 0.25)
      (net 166 "/DDR3/DDR3_VTT") (pintype "passive"))
  )

  (footprint "antmicro-footprints:C_0402_1005Metric" (layer "F.Cu")
    (at 75.32 116.92 180)
    (descr "Capacitor SMD 0402")
    (tags "capacitor SMD 0402")
    (property "Author" "Antmicro")
    (property "Dielectric" "X5R")
    (property "License" "Apache-2.0")
    (property "MPN" "GRM155R61H104KE14D")
    (property "Manufacturer" "Murata")
    (property "Public" "False")
    (property "Sheetfile" "ddr3.kicad_sch")
    (property "Sheetname" "DDR3")
    (property "Val" "100n")
    (property "Voltage" "50V")
    (property "ki_description" "SMD Multilayer Ceramic Capacitor, 0.1 µF, 50 V, 0402 [1005 Metric], ± 10%, X5R, GRM Series")
    (property "ki_keywords" "0402, SMT, CAPACITOR, PASSIVE, CERAMIC, MLCC")
    (attr smd)
    (fp_text reference "C200" (at 2.27 0.05) (layer "F.SilkS")
        (effects (font (size 0.7 0.7) (thickness 0.127)))
    )
    (fp_text value "C_100n_0402" (at 0 1.17) (layer "F.Fab")
        (effects (font (size 1 1) (thickness 0.15)))
    )
    (fp_text user "Author: Antmicro" (at -0.939 3.399 180) (layer "F.Fab") hide
        (effects (font (size 0.7 0.7) (thickness 0.15)) (justify left bottom))
    )
    (fp_text user "License: Apache-2.0" (at -0.939 5.799 180) (layer "F.Fab") hide
        (effects (font (size 0.7 0.7) (thickness 0.15)) (justify left bottom))
    )
    (fp_text user "${REFERENCE}" (at 0 0) (layer "F.Fab")
        (effects (font (size 0.25 0.25) (thickness 0.04)))
    )
    (fp_rect (start -0.925 -0.47) (end 0.925 0.47)
      (stroke (width 0.05) (type default)) (fill none) (layer "F.CrtYd"))
    (fp_line (start -0.494 -0.25) (end 0.504 -0.25)
      (stroke (width 0.15) (type solid)) (layer "F.Fab"))
    (fp_line (start -0.494 0.248) (end -0.494 -0.25)
      (stroke (width 0.15) (type solid)) (layer "F.Fab"))
    (fp_line (start 0.504 -0.25) (end 0.504 0.248)
      (stroke (width 0.15) (type solid)) (layer "F.Fab"))
    (fp_line (start 0.504 0.248) (end -0.494 0.248)
      (stroke (width 0.15) (type solid)) (layer "F.Fab"))
    (pad "1" smd roundrect (at -0.48 0 180) (size 0.59 0.64) (layers "F.Cu" "F.Paste" "F.Mask") (roundrect_rratio 0.25)
      (net 1 "GND") (pintype "passive"))
    (pad "2" smd roundrect (at 0.48 0 180) (size 0.59 0.64) (layers "F.Cu" "F.Paste" "F.Mask") (roundrect_rratio 0.25)
      (net 217 "DDR3_VREF") (pintype "passive"))
  )

  (footprint "antmicro-footprints:C_0402_1005Metric" (layer "F.Cu")
    (at 71.4 119.6 90)
    (descr "Capacitor SMD 0402")
    (tags "capacitor SMD 0402")
    (property "Author" "Antmicro")
    (property "Dielectric" "")
    (property "License" "Apache-2.0")
    (property "MPN" "CC0402MRX5R5BB106")
    (property "Manufacturer" "YAGEO")
    (property "Public" "False")
    (property "Sheetfile" "ddr3.kicad_sch")
    (property "Sheetname" "DDR3")
    (property "Val" "10u")
    (property "Voltage" "")
    (property "ki_description" "SMD Multilayer Ceramic Capacitor, 10 µF, 6.3 V, 0402 [1005 Metric], ± 20%, X5R, CC Series")
    (property "ki_keywords" "0402, SMT, CAPACITOR, PASSIVE, MLCC, CERAMIC")
    (attr smd)
    (fp_text reference "C78" (at 0.155 -1.01 90) (layer "F.SilkS")
        (effects (font (size 0.7 0.7) (thickness 0.127)))
    )
    (fp_text value "C_10u_0402" (at 0 1.17 90) (layer "F.Fab")
        (effects (font (size 1 1) (thickness 0.15)))
    )
    (fp_text user "${REFERENCE}" (at 0 0 90) (layer "F.Fab")
        (effects (font (size 0.25 0.25) (thickness 0.04)))
    )
    (fp_text user "Author: Antmicro" (at -0.939 3.399 90) (layer "F.Fab") hide
        (effects (font (size 0.7 0.7) (thickness 0.15)) (justify left bottom))
    )
    (fp_text user "License: Apache-2.0" (at -0.939 5.799 90) (layer "F.Fab") hide
        (effects (font (size 0.7 0.7) (thickness 0.15)) (justify left bottom))
    )
    (fp_rect (start -0.925 -0.47) (end 0.925 0.47)
      (stroke (width 0.05) (type default)) (fill none) (layer "F.CrtYd"))
    (fp_line (start -0.494 -0.25) (end 0.504 -0.25)
      (stroke (width 0.15) (type solid)) (layer "F.Fab"))
    (fp_line (start -0.494 0.248) (end -0.494 -0.25)
      (stroke (width 0.15) (type solid)) (layer "F.Fab"))
    (fp_line (start 0.504 -0.25) (end 0.504 0.248)
      (stroke (width 0.15) (type solid)) (layer "F.Fab"))
    (fp_line (start 0.504 0.248) (end -0.494 0.248)
      (stroke (width 0.15) (type solid)) (layer "F.Fab"))
    (pad "1" smd roundrect (at -0.48 0 90) (size 0.59 0.64) (layers "F.Cu" "F.Paste" "F.Mask") (roundrect_rratio 0.25)
      (net 1 "GND") (pintype "passive"))
    (pad "2" smd roundrect (at 0.48 0 90) (size 0.59 0.64) (layers "F.Cu" "F.Paste" "F.Mask") (roundrect_rratio 0.25)
      (net 2 "VCC3V3") (pintype "passive"))
  )

  (footprint "antmicro-footprints:R_0402_1005Metric" (layer "F.Cu")
    (at 91.3 78.35 90)
    (descr "Resistor SMD 0402")
    (tags "resistor SMD 0402")
    (property "Author" "Antmicro")
    (property "License" "Apache-2.0")
    (property "MPN" "CR0402-FX-4703GLF")
    (property "Manufacturer" "Bourns")
    (property "Public" "False")
    (property "Sheetfile" "power-supply.kicad_sch")
    (property "Sheetname" "Power supply")
    (property "Tolerance" "1%")
    (property "Val" "470k")
    (property "ki_description" "SMD Chip Resistor, 470 kohm, ± 1%, 62.5 mW, 0402 [1005 Metric], Thick Film, Sulfur Resistant")
    (property "ki_keywords" "0402, SMT, RESISTOR, PASSIVE")
    (attr smd)
    (fp_text reference "R99" (at -4.795 3.26 90) (layer "F.SilkS")
        (effects (font (size 0.7 0.7) (thickness 0.127)))
    )
    (fp_text value "R_470k_0402" (at 0 1.17 90) (layer "F.Fab")
        (effects (font (size 1 1) (thickness 0.15)))
    )
    (fp_text user "${REFERENCE}" (at 0 0 90) (layer "F.Fab")
        (effects (font (size 0.25 0.25) (thickness 0.04)))
    )
    (fp_text user "Author: Antmicro" (at -0.95 4.169 90) (layer "F.Fab") hide
        (effects (font (size 0.7 0.7) (thickness 0.15)) (justify left bottom))
    )
    (fp_text user "License: Apache-2.0" (at -0.95 5.169 90) (layer "F.Fab") hide
        (effects (font (size 0.7 0.7) (thickness 0.15)) (justify left bottom))
    )
    (fp_rect (start -0.925 -0.47) (end 0.925 0.47)
      (stroke (width 0.05) (type default)) (fill none) (layer "F.CrtYd"))
    (fp_rect (start -0.5 -0.25) (end 0.5 0.25)
      (stroke (width 0.15) (type solid)) (fill none) (layer "F.Fab"))
    (pad "1" smd roundrect (at -0.48 0 90) (size 0.59 0.64) (layers "F.Cu" "F.Paste" "F.Mask") (roundrect_rratio 0.25)
      (net 368 "Net-(C108-Pad1)") (pintype "passive"))
    (pad "2" smd roundrect (at 0.48 0 90) (size 0.59 0.64) (layers "F.Cu" "F.Paste" "F.Mask") (roundrect_rratio 0.25)
      (net 289 "Net-(U13-FB)") (pintype "passive"))
  )

  (footprint "antmicro-footprints:R_0402_1005Metric" (layer "F.Cu")
    (at 91.8 76.85)
    (descr "Resistor SMD 0402")
    (tags "resistor SMD 0402")
    (property "Author" "Antmicro")
    (property "License" "Apache-2.0")
    (property "MPN" "CR0402-FX-1002GLF")
    (property "Manufacturer" "Bourns")
    (property "Public" "False")
    (property "Sheetfile" "power-supply.kicad_sch")
    (property "Sheetname" "Power supply")
    (property "Tolerance" "1%")
    (property "Val" "10k")
    (property "ki_description" "SMD Chip Resistor, 10 kohm, ± 1%, 62.5 mW, 0402 [1005 Metric], Thick Film, General Purpose")
    (property "ki_keywords" "0402, SMT, RESISTOR, PASSIVE")
    (attr smd)
    (fp_text reference "R98" (at 2.11 3.145) (layer "F.SilkS")
        (effects (font (size 0.7 0.7) (thickness 0.127)))
    )
    (fp_text value "R_10k_0402" (at 0 1.17) (layer "F.Fab")
        (effects (font (size 1 1) (thickness 0.15)))
    )
    (fp_text user "License: Apache-2.0" (at -0.95 5.169) (layer "F.Fab") hide
        (effects (font (size 0.7 0.7) (thickness 0.15)) (justify left bottom))
    )
    (fp_text user "Author: Antmicro" (at -0.95 4.169) (layer "F.Fab") hide
        (effects (font (size 0.7 0.7) (thickness 0.15)) (justify left bottom))
    )
    (fp_text user "${REFERENCE}" (at 0 0) (layer "F.Fab")
        (effects (font (size 0.25 0.25) (thickness 0.04)))
    )
    (fp_rect (start -0.925 -0.47) (end 0.925 0.47)
      (stroke (width 0.05) (type default)) (fill none) (layer "F.CrtYd"))
    (fp_rect (start -0.5 -0.25) (end 0.5 0.25)
      (stroke (width 0.15) (type solid)) (fill none) (layer "F.Fab"))
    (pad "1" smd roundrect (at -0.48 0) (size 0.59 0.64) (layers "F.Cu" "F.Paste" "F.Mask") (roundrect_rratio 0.25)
      (net 354 "Net-(C108-Pad2)") (pintype "passive"))
    (pad "2" smd roundrect (at 0.48 0) (size 0.59 0.64) (layers "F.Cu" "F.Paste" "F.Mask") (roundrect_rratio 0.25)
      (net 289 "Net-(U13-FB)") (pintype "passive"))
  )

  (footprint "antmicro-footprints:R_0402_1005Metric" (layer "F.Cu")
    (at 94.2 61.75 90)
    (descr "Resistor SMD 0402")
    (tags "resistor SMD 0402")
    (property "Author" "Antmicro")
    (property "License" "Apache-2.0")
    (property "MPN" "CR0402-FX-4702GLF")
    (property "Manufacturer" "Bourns")
    (property "Public" "False")
    (property "Sheetfile" "power-supply.kicad_sch")
    (property "Sheetname" "Power supply")
    (property "Tolerance" "1%")
    (property "Val" "47k")
    (property "ki_description" "SMD Chip Resistor, 47 kohm, ± 1%, 62.5 mW, 0402 [1005 Metric], Thick Film, General Purpose")
    (property "ki_keywords" "0402, SMT, RESISTOR, PASSIVE")
    (attr smd)
    (fp_text reference "R89" (at 0.115 1.73 90) (layer "F.SilkS")
        (effects (font (size 0.7 0.7) (thickness 0.127)))
    )
    (fp_text value "R_47k_0402" (at 0 1.17 90) (layer "F.Fab")
        (effects (font (size 1 1) (thickness 0.15)))
    )
    (fp_text user "License: Apache-2.0" (at -0.95 5.169 90) (layer "F.Fab") hide
        (effects (font (size 0.7 0.7) (thickness 0.15)) (justify left bottom))
    )
    (fp_text user "Author: Antmicro" (at -0.95 4.169 90) (layer "F.Fab") hide
        (effects (font (size 0.7 0.7) (thickness 0.15)) (justify left bottom))
    )
    (fp_text user "${REFERENCE}" (at 0 0 90) (layer "F.Fab")
        (effects (font (size 0.25 0.25) (thickness 0.04)))
    )
    (fp_rect (start -0.925 -0.47) (end 0.925 0.47)
      (stroke (width 0.05) (type default)) (fill none) (layer "F.CrtYd"))
    (fp_rect (start -0.5 -0.25) (end 0.5 0.25)
      (stroke (width 0.15) (type solid)) (fill none) (layer "F.Fab"))
    (pad "1" smd roundrect (at -0.48 0 90) (size 0.59 0.64) (layers "F.Cu" "F.Paste" "F.Mask") (roundrect_rratio 0.25)
      (net 423 "Net-(U13-FADJ)") (pintype "passive"))
    (pad "2" smd roundrect (at 0.48 0 90) (size 0.59 0.64) (layers "F.Cu" "F.Paste" "F.Mask") (roundrect_rratio 0.25)
      (net 1 "GND") (pintype "passive"))
  )

  (footprint "antmicro-footprints:C_1210_3225Metric" (layer "F.Cu")
    (at 92 74.25 180)
    (descr "Capacitor SMD 1210")
    (tags "capacitor SMD 1210")
    (property "Author" "Antmicro")
    (property "Dielectric" "")
    (property "License" "Apache-2.0")
    (property "MPN" "C1210C476K8RACTU")
    (property "Manufacturer" "KEMET")
    (property "Public" "False")
    (property "Sheetfile" "power-supply.kicad_sch")
    (property "Sheetname" "Power supply")
    (property "Val" "47u")
    (property "Voltage" "")
    (property "ki_description" "SMD Multilayer Ceramic Capacitor, 47 µF, 10 V, 1210 [3225 Metric], ± 10%, X7R, C Series KEMET")
    (property "ki_keywords" "1210, SMT, CAPACITOR, PASSIVE")
    (attr smd)
    (fp_text reference "C109" (at -6.57 0.125 90) (layer "F.SilkS")
        (effects (font (size 0.7 0.7) (thickness 0.127)))
    )
    (fp_text value "C_47u_1210" (at 0 2.8) (layer "F.Fab")
        (effects (font (size 1 1) (thickness 0.15)))
    )
    (fp_text user "${REFERENCE}" (at 0 0) (layer "F.Fab")
        (effects (font (size 0.5 0.5) (thickness 0.05)))
    )
    (fp_text user "Author: Antmicro" (at -2.1 5.749 180) (layer "F.Fab") hide
        (effects (font (size 0.7 0.7) (thickness 0.15)) (justify left bottom))
    )
    (fp_text user "License: Apache-2.0" (at -2.1 6.749 180) (layer "F.Fab") hide
        (effects (font (size 0.7 0.7) (thickness 0.15)) (justify left bottom))
    )
    (fp_line (start -0.3 -1.39) (end 0.3 -1.39)
      (stroke (width 0.15) (type solid)) (layer "F.SilkS"))
    (fp_line (start -0.3 1.39) (end 0.3 1.39)
      (stroke (width 0.15) (type solid)) (layer "F.SilkS"))
    (fp_rect (start -2.1 -1.75) (end 2.1 1.75)
      (stroke (width 0.05) (type solid)) (fill none) (layer "F.CrtYd"))
    (fp_rect (start -1.6 -1.25) (end 1.6 1.25)
      (stroke (width 0.15) (type solid)) (fill none) (layer "F.Fab"))
    (pad "1" smd rect (at -1.145 0 180) (size 1.52 3.05) (layers "F.Cu" "F.Paste" "F.Mask")
      (net 1 "GND") (pintype "passive"))
    (pad "2" smd rect (at 1.145 0 180) (size 1.52 3.05) (layers "F.Cu" "F.Paste" "F.Mask")
      (net 354 "Net-(C108-Pad2)") (pintype "passive"))
  )

  (footprint "antmicro-footprints:C_0402_1005Metric" (layer "F.Cu")
    (at 90.3 77.4 90)
    (descr "Capacitor SMD 0402")
    (tags "capacitor SMD 0402")
    (property "Author" "Antmicro")
    (property "Dielectric" "")
    (property "License" "Apache-2.0")
    (property "MPN" "C0402C751J5GACTU")
    (property "Manufacturer" "KEMET")
    (property "Public" "False")
    (property "Sheetfile" "power-supply.kicad_sch")
    (property "Sheetname" "Power supply")
    (property "Val" "750p")
    (property "Voltage" "")
    (property "ki_description" "SMD Multilayer Ceramic Capacitor, 750 pF, 50 V, 0402 [1005 Metric], ± 5%, C0G / NP0")
    (property "ki_keywords" "0402, SMT, CAPACITOR, PASSIVE, CERAMIC, MLCC")
    (attr smd)
    (fp_text reference "C108" (at 0.755 -3.35 90) (layer "F.SilkS")
        (effects (font (size 0.7 0.7) (thickness 0.127)))
    )
    (fp_text value "C_750p_0402" (at 0 1.17 90) (layer "F.Fab")
        (effects (font (size 1 1) (thickness 0.15)))
    )
    (fp_text user "License: Apache-2.0" (at -0.939 5.799 90) (layer "F.Fab") hide
        (effects (font (size 0.7 0.7) (thickness 0.15)) (justify left bottom))
    )
    (fp_text user "Author: Antmicro" (at -0.939 3.399 90) (layer "F.Fab") hide
        (effects (font (size 0.7 0.7) (thickness 0.15)) (justify left bottom))
    )
    (fp_text user "${REFERENCE}" (at 0 0 90) (layer "F.Fab")
        (effects (font (size 0.25 0.25) (thickness 0.04)))
    )
    (fp_rect (start -0.925 -0.47) (end 0.925 0.47)
      (stroke (width 0.05) (type default)) (fill none) (layer "F.CrtYd"))
    (fp_line (start -0.494 -0.25) (end 0.504 -0.25)
      (stroke (width 0.15) (type solid)) (layer "F.Fab"))
    (fp_line (start -0.494 0.248) (end -0.494 -0.25)
      (stroke (width 0.15) (type solid)) (layer "F.Fab"))
    (fp_line (start 0.504 -0.25) (end 0.504 0.248)
      (stroke (width 0.15) (type solid)) (layer "F.Fab"))
    (fp_line (start 0.504 0.248) (end -0.494 0.248)
      (stroke (width 0.15) (type solid)) (layer "F.Fab"))
    (pad "1" smd roundrect (at -0.48 0 90) (size 0.59 0.64) (layers "F.Cu" "F.Paste" "F.Mask") (roundrect_rratio 0.25)
      (net 368 "Net-(C108-Pad1)") (pintype "passive"))
    (pad "2" smd roundrect (at 0.48 0 90) (size 0.59 0.64) (layers "F.Cu" "F.Paste" "F.Mask") (roundrect_rratio 0.25)
      (net 354 "Net-(C108-Pad2)") (pintype "passive"))
  )

  (footprint "antmicro-footprints:C_0402_1005Metric" (layer "F.Cu")
    (at 92.8 77.9 180)
    (descr "Capacitor SMD 0402")
    (tags "capacitor SMD 0402")
    (property "Author" "Antmicro")
    (property "Dielectric" "")
    (property "License" "Apache-2.0")
    (property "MPN" "04025A181JAT2A")
    (property "Manufacturer" "AVX")
    (property "Public" "False")
    (property "Sheetfile" "power-supply.kicad_sch")
    (property "Sheetname" "Power supply")
    (property "Val" "180p")
    (property "Voltage" "")
    (property "ki_description" "SMD Multilayer Ceramic Capacitor, 180 pF, 50 V, 0402 [1005 Metric], ± 5%, C0G / NP0, AVX 0402 MLCC")
    (property "ki_keywords" "0402, SMT, CAPACITOR, PASSIVE, CERAMIC, MLCC")
    (attr smd)
    (fp_text reference "C107" (at -1.8 -2.935) (layer "F.SilkS")
        (effects (font (size 0.7 0.7) (thickness 0.127)))
    )
    (fp_text value "C_180p_0402" (at 0 1.17) (layer "F.Fab")
        (effects (font (size 1 1) (thickness 0.15)))
    )
    (fp_text user "Author: Antmicro" (at -0.939 3.399 180) (layer "F.Fab") hide
        (effects (font (size 0.7 0.7) (thickness 0.15)) (justify left bottom))
    )
    (fp_text user "License: Apache-2.0" (at -0.939 5.799 180) (layer "F.Fab") hide
        (effects (font (size 0.7 0.7) (thickness 0.15)) (justify left bottom))
    )
    (fp_text user "${REFERENCE}" (at 0 0) (layer "F.Fab")
        (effects (font (size 0.25 0.25) (thickness 0.04)))
    )
    (fp_rect (start -0.925 -0.47) (end 0.925 0.47)
      (stroke (width 0.05) (type default)) (fill none) (layer "F.CrtYd"))
    (fp_line (start -0.494 -0.25) (end 0.504 -0.25)
      (stroke (width 0.15) (type solid)) (layer "F.Fab"))
    (fp_line (start -0.494 0.248) (end -0.494 -0.25)
      (stroke (width 0.15) (type solid)) (layer "F.Fab"))
    (fp_line (start 0.504 -0.25) (end 0.504 0.248)
      (stroke (width 0.15) (type solid)) (layer "F.Fab"))
    (fp_line (start 0.504 0.248) (end -0.494 0.248)
      (stroke (width 0.15) (type solid)) (layer "F.Fab"))
    (pad "1" smd roundrect (at -0.48 0 180) (size 0.59 0.64) (layers "F.Cu" "F.Paste" "F.Mask") (roundrect_rratio 0.25)
      (net 267 "Net-(U13-COMP)") (pintype "passive"))
    (pad "2" smd roundrect (at 0.48 0 180) (size 0.59 0.64) (layers "F.Cu" "F.Paste" "F.Mask") (roundrect_rratio 0.25)
      (net 289 "Net-(U13-FB)") (pintype "passive"))
  )

  (footprint "antmicro-footprints:C_0402_1005Metric" (layer "F.Cu")
    (at 94.3 78.35 -90)
    (descr "Capacitor SMD 0402")
    (tags "capacitor SMD 0402")
    (property "Author" "Antmicro")
    (property "Dielectric" "")
    (property "License" "Apache-2.0")
    (property "MPN" "0402B182K500CT")
    (property "Manufacturer" "Walsin")
    (property "Public" "False")
    (property "Sheetfile" "power-supply.kicad_sch")
    (property "Sheetname" "Power supply")
    (property "Val" "1n8")
    (property "Voltage" "")
    (property "ki_description" "SMD Multilayer Ceramic Capacitor, General Purpose, 1800 pF, 50 V, 0402 [1005 Metric], ± 10%, X7R")
    (property "ki_keywords" "0402, SMT, CAPACITOR, PASSIVE, MLCC")
    (attr smd)
    (fp_text reference "C106" (at 3.555 -1.98 90) (layer "F.SilkS")
        (effects (font (size 0.7 0.7) (thickness 0.127)))
    )
    (fp_text value "C_1n8_0402" (at 0 1.17 90) (layer "F.Fab")
        (effects (font (size 1 1) (thickness 0.15)))
    )
    (fp_text user "Author: Antmicro" (at -0.939 3.399 -90) (layer "F.Fab") hide
        (effects (font (size 0.7 0.7) (thickness 0.15)) (justify left bottom))
    )
    (fp_text user "${REFERENCE}" (at 0 0 90) (layer "F.Fab")
        (effects (font (size 0.25 0.25) (thickness 0.04)))
    )
    (fp_text user "License: Apache-2.0" (at -0.939 5.799 -90) (layer "F.Fab") hide
        (effects (font (size 0.7 0.7) (thickness 0.15)) (justify left bottom))
    )
    (fp_rect (start -0.925 -0.47) (end 0.925 0.47)
      (stroke (width 0.05) (type default)) (fill none) (layer "F.CrtYd"))
    (fp_line (start -0.494 -0.25) (end 0.504 -0.25)
      (stroke (width 0.15) (type solid)) (layer "F.Fab"))
    (fp_line (start -0.494 0.248) (end -0.494 -0.25)
      (stroke (width 0.15) (type solid)) (layer "F.Fab"))
    (fp_line (start 0.504 -0.25) (end 0.504 0.248)
      (stroke (width 0.15) (type solid)) (layer "F.Fab"))
    (fp_line (start 0.504 0.248) (end -0.494 0.248)
      (stroke (width 0.15) (type solid)) (layer "F.Fab"))
    (pad "1" smd roundrect (at -0.48 0 270) (size 0.59 0.64) (layers "F.Cu" "F.Paste" "F.Mask") (roundrect_rratio 0.25)
      (net 267 "Net-(U13-COMP)") (pintype "passive"))
    (pad "2" smd roundrect (at 0.48 0 270) (size 0.59 0.64) (layers "F.Cu" "F.Paste" "F.Mask") (roundrect_rratio 0.25)
      (net 352 "Net-(C106-Pad2)") (pintype "passive"))
  )

  (footprint "antmicro-footprints:L_Coilcraft-XAL5030" (layer "F.Cu")
    (at 86.5 75.25)
    (property "Author" "Antmicro")
    (property "IMax" "13 A")
    (property "ISat" "18.5 A")
    (property "License" "Apache-2.0")
    (property "MPN" "XAL5030-801MEC")
    (property "Manufacturer" "Coilcraft")
    (property "Public" "False")
    (property "Sheetfile" "power-supply.kicad_sch")
    (property "Sheetname" "Power supply")
    (property "Size" "5.28x5.48")
    (property "Val" "800n/13A")
    (property "ki_description" "Power Inductor (SMD), 800 nH, 13 A, Shielded, 18.5 A, XAL5030")
    (property "ki_keywords" "SMT, INDUCTOR, PASSIVE")
    (attr smd)
    (fp_text reference "L1" (at 0.55 -3.4) (layer "F.SilkS")
        (effects (font (size 0.7 0.7) (thickness 0.127)) (justify left))
    )
    (fp_text value "XAL5030-801" (at -0.4318 4.2418) (layer "F.Fab")
        (effects (font (size 1.27 1.27) (thickness 0.15)))
    )
    (fp_text user "License: Apache-2.0" (at -2.89 6.241) (layer "F.Fab") hide
        (effects (font (size 0.7 0.7) (thickness 0.15)) (justify left bottom))
    )
    (fp_text user "Author: Antmicro" (at -2.89 7.441) (layer "F.Fab") hide
        (effects (font (size 0.7 0.7) (thickness 0.15)) (justify left bottom))
    )
    (fp_text user "${REFERENCE}" (at -2.89 8.641) (layer "F.Fab") hide
        (effects (font (size 0.7 0.7) (thickness 0.15)) (justify left bottom))
    )
    (fp_line (start -2.74 -2.84) (end 2.74 -2.84)
      (stroke (width 0.15) (type solid)) (layer "F.SilkS"))
    (fp_line (start -2.74 2.84) (end -2.74 -2.84)
      (stroke (width 0.15) (type solid)) (layer "F.SilkS"))
    (fp_line (start -2.74 2.84) (end 2.74 2.84)
      (stroke (width 0.15) (type solid)) (layer "F.SilkS"))
    (fp_line (start 2.74 2.84) (end 2.74 -2.84)
      (stroke (width 0.15) (type solid)) (layer "F.SilkS"))
    (fp_rect (start -2.89 -2.99) (end 2.89 2.99)
      (stroke (width 0.05) (type solid)) (fill none) (layer "F.CrtYd"))
    (fp_line (start -2.74 -2.84) (end 2.74 -2.84)
      (stroke (width 0.15) (type solid)) (layer "F.Fab"))
    (fp_line (start -2.74 2.84) (end -2.74 -2.84)
      (stroke (width 0.15) (type solid)) (layer "F.Fab"))
    (fp_line (start 2.74 -2.84) (end 2.74 2.84)
      (stroke (width 0.15) (type solid)) (layer "F.Fab"))
    (fp_line (start 2.74 2.84) (end -2.74 2.84)
      (stroke (width 0.15) (type solid)) (layer "F.Fab"))
    (pad "1" smd roundrect (at -1.655 0) (size 1.18 4.7) (layers "F.Cu" "F.Paste" "F.Mask") (roundrect_rratio 0.1)
      (net 234 "Net-(L1-Pad1)") (pintype "passive"))
    (pad "2" smd roundrect (at 1.655 0) (size 1.18 4.7) (layers "F.Cu" "F.Paste" "F.Mask") (roundrect_rratio 0.1)
      (net 354 "Net-(C108-Pad2)") (pintype "passive"))
  )

  (footprint "antmicro-footprints:LED_0603_1608Metric_G" (layer "F.Cu")
    (at 65.5 85.891666 180)
    (descr "LED SMD 0603 Green")
    (tags "LED SMD 0603 Green")
    (property "Author" "Antmicro")
    (property "Color" "Green")
    (property "License" "Apache-2.0")
    (property "MPN" "LG L29K-G2J1-24-Z")
    (property "Manufacturer" "OSRAM")
    (property "Sheetfile" "power-supply.kicad_sch")
    (property "Sheetname" "Power supply")
    (property "ki_description" "LED, Green, SMD, 0603, 20 mA, 1.7 V, 570 nm")
    (property "ki_keywords" "SMT, DIODE, SEMICONDUCTOR, LED")
    (attr smd)
    (fp_text reference "D7" (at 1.8 0.741666 90) (layer "F.SilkS")
        (effects (font (size 0.7 0.7) (thickness 0.127)))
    )
    (fp_text value "LED_G_0603_LG_L29K-G2J1-24-Z" (at 0 1.77) (layer "F.Fab")
        (effects (font (size 1 1) (thickness 0.15)))
    )
    (fp_text user "${REFERENCE}" (at -1.4224 5.999 180) (layer "F.Fab") hide
        (effects (font (size 0.7 0.7) (thickness 0.15)) (justify left bottom))
    )
    (fp_text user "License: Apache-2.0" (at -1.4224 3.599 180) (layer "F.Fab") hide
        (effects (font (size 0.7 0.7) (thickness 0.15)) (justify left bottom))
    )
    (fp_text user "Author: Antmicro" (at -1.4224 4.799 180) (layer "F.Fab") hide
        (effects (font (size 0.7 0.7) (thickness 0.15)) (justify left bottom))
    )
    (fp_line (start -1.18 -0.319) (end -1.18 0.321)
      (stroke (width 0.15) (type solid)) (layer "F.SilkS"))
    (fp_line (start -0.094672 0.001008) (end -0.24 0.001008)
      (stroke (width 0.1) (type solid)) (layer "F.SilkS"))
    (fp_line (start -0.094672 0.001008) (end 0.105328 -0.198992)
      (stroke (width 0.1) (type solid)) (layer "F.SilkS"))
    (fp_line (start -0.094672 0.201008) (end -0.094672 -0.198992)
      (stroke (width 0.1) (type solid)) (layer "F.SilkS"))
    (fp_line (start 0.105328 0.001008) (end 0.24 0.001)
      (stroke (width 0.1) (type solid)) (layer "F.SilkS"))
    (fp_line (start 0.105328 0.201008) (end -0.094672 0.001008)
      (stroke (width 0.1) (type solid)) (layer "F.SilkS"))
    (fp_line (start 0.105328 0.201008) (end 0.105328 -0.198992)
      (stroke (width 0.1) (type solid)) (layer "F.SilkS"))
    (fp_line (start 0.22 -0.35) (end -0.22 -0.35)
      (stroke (width 0.15) (type solid)) (layer "F.SilkS"))
    (fp_line (start 0.22 0.35) (end -0.22 0.35)
      (stroke (width 0.15) (type solid)) (layer "F.SilkS"))
    (fp_rect (start 1.25 0.65) (end -1.25 -0.65)
      (stroke (width 0.05) (type solid)) (fill none) (layer "F.CrtYd"))
    (fp_line (start -0.199 -0.202) (end -0.199 0.1)
      (stroke (width 0.15) (type solid)) (layer "F.Fab"))
    (fp_line (start -0.199 0) (end -0.597 0)
      (stroke (width 0.15) (type solid)) (layer "F.Fab"))
    (fp_line (start -0.199 0.2) (end -0.199 0.1)
      (stroke (width 0.15) (type solid)) (layer "F.Fab"))
    (fp_line (start -0.101 0) (end 0.201 0.2)
      (stroke (width 0.15) (type solid)) (layer "F.Fab"))
    (fp_line (start 0.201 -0.202) (end -0.101 0)
      (stroke (width 0.15) (type solid)) (layer "F.Fab"))
    (fp_line (start 0.201 0) (end 0.201 -0.202)
      (stroke (width 0.15) (type solid)) (layer "F.Fab"))
    (fp_line (start 0.201 0.2) (end 0.201 0)
      (stroke (width 0.15) (type solid)) (layer "F.Fab"))
    (fp_line (start 0.599 0) (end 0.201 0)
      (stroke (width 0.15) (type solid)) (layer "F.Fab"))
    (fp_rect (start 0.848 0.4) (end -0.85 -0.402)
      (stroke (width 0.15) (type solid)) (fill none) (layer "F.Fab"))
    (pad "1" smd roundrect (at -0.7 0) (size 0.8 1) (layers "F.Cu" "F.Paste" "F.Mask") (roundrect_rratio 0.2)
      (net 2 "VCC3V3") (pinfunction "C") (pintype "passive"))
    (pad "2" smd roundrect (at 0.7 0) (size 0.8 1) (layers "F.Cu" "F.Paste" "F.Mask") (roundrect_rratio 0.2)
      (net 315 "Net-(D7-A)") (pinfunction "A") (pintype "passive"))
  )

  (footprint "antmicro-footprints:LED_0603_1608Metric_G" (layer "F.Cu")
    (at 65.5 84.25 180)
    (descr "LED SMD 0603 Green")
    (tags "LED SMD 0603 Green")
    (property "Author" "Antmicro")
    (property "Color" "Green")
    (property "License" "Apache-2.0")
    (property "MPN" "LG L29K-G2J1-24-Z")
    (property "Manufacturer" "OSRAM")
    (property "Sheetfile" "power-supply.kicad_sch")
    (property "Sheetname" "Power supply")
    (property "ki_description" "LED, Green, SMD, 0603, 20 mA, 1.7 V, 570 nm")
    (property "ki_keywords" "SMT, DIODE, SEMICONDUCTOR, LED")
    (attr smd)
    (fp_text reference "D8" (at 1.8 0.6 90) (layer "F.SilkS")
        (effects (font (size 0.7 0.7) (thickness 0.127)))
    )
    (fp_text value "LED_G_0603_LG_L29K-G2J1-24-Z" (at 0 1.77) (layer "F.Fab")
        (effects (font (size 1 1) (thickness 0.15)))
    )
    (fp_text user "License: Apache-2.0" (at -1.4224 3.599 180) (layer "F.Fab") hide
        (effects (font (size 0.7 0.7) (thickness 0.15)) (justify left bottom))
    )
    (fp_text user "${REFERENCE}" (at -1.4224 5.999 180) (layer "F.Fab") hide
        (effects (font (size 0.7 0.7) (thickness 0.15)) (justify left bottom))
    )
    (fp_text user "Author: Antmicro" (at -1.4224 4.799 180) (layer "F.Fab") hide
        (effects (font (size 0.7 0.7) (thickness 0.15)) (justify left bottom))
    )
    (fp_line (start -1.18 -0.319) (end -1.18 0.321)
      (stroke (width 0.15) (type solid)) (layer "F.SilkS"))
    (fp_line (start -0.094672 0.001008) (end -0.24 0.001008)
      (stroke (width 0.1) (type solid)) (layer "F.SilkS"))
    (fp_line (start -0.094672 0.001008) (end 0.105328 -0.198992)
      (stroke (width 0.1) (type solid)) (layer "F.SilkS"))
    (fp_line (start -0.094672 0.201008) (end -0.094672 -0.198992)
      (stroke (width 0.1) (type solid)) (layer "F.SilkS"))
    (fp_line (start 0.105328 0.001008) (end 0.24 0.001)
      (stroke (width 0.1) (type solid)) (layer "F.SilkS"))
    (fp_line (start 0.105328 0.201008) (end -0.094672 0.001008)
      (stroke (width 0.1) (type solid)) (layer "F.SilkS"))
    (fp_line (start 0.105328 0.201008) (end 0.105328 -0.198992)
      (stroke (width 0.1) (type solid)) (layer "F.SilkS"))
    (fp_line (start 0.22 -0.35) (end -0.22 -0.35)
      (stroke (width 0.15) (type solid)) (layer "F.SilkS"))
    (fp_line (start 0.22 0.35) (end -0.22 0.35)
      (stroke (width 0.15) (type solid)) (layer "F.SilkS"))
    (fp_rect (start 1.25 0.65) (end -1.25 -0.65)
      (stroke (width 0.05) (type solid)) (fill none) (layer "F.CrtYd"))
    (fp_line (start -0.199 -0.202) (end -0.199 0.1)
      (stroke (width 0.15) (type solid)) (layer "F.Fab"))
    (fp_line (start -0.199 0) (end -0.597 0)
      (stroke (width 0.15) (type solid)) (layer "F.Fab"))
    (fp_line (start -0.199 0.2) (end -0.199 0.1)
      (stroke (width 0.15) (type solid)) (layer "F.Fab"))
    (fp_line (start -0.101 0) (end 0.201 0.2)
      (stroke (width 0.15) (type solid)) (layer "F.Fab"))
    (fp_line (start 0.201 -0.202) (end -0.101 0)
      (stroke (width 0.15) (type solid)) (layer "F.Fab"))
    (fp_line (start 0.201 0) (end 0.201 -0.202)
      (stroke (width 0.15) (type solid)) (layer "F.Fab"))
    (fp_line (start 0.201 0.2) (end 0.201 0)
      (stroke (width 0.15) (type solid)) (layer "F.Fab"))
    (fp_line (start 0.599 0) (end 0.201 0)
      (stroke (width 0.15) (type solid)) (layer "F.Fab"))
    (fp_rect (start 0.848 0.4) (end -0.85 -0.402)
      (stroke (width 0.15) (type solid)) (fill none) (layer "F.Fab"))
    (pad "1" smd roundrect (at -0.7 0) (size 0.8 1) (layers "F.Cu" "F.Paste" "F.Mask") (roundrect_rratio 0.2)
      (net 2 "VCC3V3") (pinfunction "C") (pintype "passive"))
    (pad "2" smd roundrect (at 0.7 0) (size 0.8 1) (layers "F.Cu" "F.Paste" "F.Mask") (roundrect_rratio 0.2)
      (net 316 "Net-(D8-A)") (pinfunction "A") (pintype "passive"))
  )

  (footprint "antmicro-footprints:LED_0603_1608Metric_G" (layer "F.Cu")
    (at 65.5 94.1 180)
    (descr "LED SMD 0603 Green")
    (tags "LED SMD 0603 Green")
    (property "Author" "Antmicro")
    (property "Color" "Green")
    (property "License" "Apache-2.0")
    (property "MPN" "LG L29K-G2J1-24-Z")
    (property "Manufacturer" "OSRAM")
    (property "Sheetfile" "power-supply.kicad_sch")
    (property "Sheetname" "Power supply")
    (property "ki_description" "LED, Green, SMD, 0603, 20 mA, 1.7 V, 570 nm")
    (property "ki_keywords" "SMT, DIODE, SEMICONDUCTOR, LED")
    (attr smd)
    (fp_text reference "D9" (at 1.8 -0.95 90) (layer "F.SilkS")
        (effects (font (size 0.7 0.7) (thickness 0.127)))
    )
    (fp_text value "LED_G_0603_LG_L29K-G2J1-24-Z" (at 0 1.77) (layer "F.Fab")
        (effects (font (size 1 1) (thickness 0.15)))
    )
    (fp_text user "License: Apache-2.0" (at -1.4224 3.599 180) (layer "F.Fab") hide
        (effects (font (size 0.7 0.7) (thickness 0.15)) (justify left bottom))
    )
    (fp_text user "${REFERENCE}" (at -1.4224 5.999 180) (layer "F.Fab") hide
        (effects (font (size 0.7 0.7) (thickness 0.15)) (justify left bottom))
    )
    (fp_text user "Author: Antmicro" (at -1.4224 4.799 180) (layer "F.Fab") hide
        (effects (font (size 0.7 0.7) (thickness 0.15)) (justify left bottom))
    )
    (fp_line (start -1.18 -0.319) (end -1.18 0.321)
      (stroke (width 0.15) (type solid)) (layer "F.SilkS"))
    (fp_line (start -0.094672 0.001008) (end -0.24 0.001008)
      (stroke (width 0.1) (type solid)) (layer "F.SilkS"))
    (fp_line (start -0.094672 0.001008) (end 0.105328 -0.198992)
      (stroke (width 0.1) (type solid)) (layer "F.SilkS"))
    (fp_line (start -0.094672 0.201008) (end -0.094672 -0.198992)
      (stroke (width 0.1) (type solid)) (layer "F.SilkS"))
    (fp_line (start 0.105328 0.001008) (end 0.24 0.001)
      (stroke (width 0.1) (type solid)) (layer "F.SilkS"))
    (fp_line (start 0.105328 0.201008) (end -0.094672 0.001008)
      (stroke (width 0.1) (type solid)) (layer "F.SilkS"))
    (fp_line (start 0.105328 0.201008) (end 0.105328 -0.198992)
      (stroke (width 0.1) (type solid)) (layer "F.SilkS"))
    (fp_line (start 0.22 -0.35) (end -0.22 -0.35)
      (stroke (width 0.15) (type solid)) (layer "F.SilkS"))
    (fp_line (start 0.22 0.35) (end -0.22 0.35)
      (stroke (width 0.15) (type solid)) (layer "F.SilkS"))
    (fp_rect (start 1.25 0.65) (end -1.25 -0.65)
      (stroke (width 0.05) (type solid)) (fill none) (layer "F.CrtYd"))
    (fp_line (start -0.199 -0.202) (end -0.199 0.1)
      (stroke (width 0.15) (type solid)) (layer "F.Fab"))
    (fp_line (start -0.199 0) (end -0.597 0)
      (stroke (width 0.15) (type solid)) (layer "F.Fab"))
    (fp_line (start -0.199 0.2) (end -0.199 0.1)
      (stroke (width 0.15) (type solid)) (layer "F.Fab"))
    (fp_line (start -0.101 0) (end 0.201 0.2)
      (stroke (width 0.15) (type solid)) (layer "F.Fab"))
    (fp_line (start 0.201 -0.202) (end -0.101 0)
      (stroke (width 0.15) (type solid)) (layer "F.Fab"))
    (fp_line (start 0.201 0) (end 0.201 -0.202)
      (stroke (width 0.15) (type solid)) (layer "F.Fab"))
    (fp_line (start 0.201 0.2) (end 0.201 0)
      (stroke (width 0.15) (type solid)) (layer "F.Fab"))
    (fp_line (start 0.599 0) (end 0.201 0)
      (stroke (width 0.15) (type solid)) (layer "F.Fab"))
    (fp_rect (start 0.848 0.4) (end -0.85 -0.402)
      (stroke (width 0.15) (type solid)) (fill none) (layer "F.Fab"))
    (pad "1" smd roundrect (at -0.7 0) (size 0.8 1) (layers "F.Cu" "F.Paste" "F.Mask") (roundrect_rratio 0.2)
      (net 2 "VCC3V3") (pinfunction "C") (pintype "passive"))
    (pad "2" smd roundrect (at 0.7 0) (size 0.8 1) (layers "F.Cu" "F.Paste" "F.Mask") (roundrect_rratio 0.2)
      (net 343 "Net-(D9-A)") (pinfunction "A") (pintype "passive"))
  )

  (footprint "antmicro-footprints:LED_0603_1608Metric_G" (layer "F.Cu")
    (at 65.5 92.45833 180)
    (descr "LED SMD 0603 Green")
    (tags "LED SMD 0603 Green")
    (property "Author" "Antmicro")
    (property "Color" "Green")
    (property "License" "Apache-2.0")
    (property "MPN" "LG L29K-G2J1-24-Z")
    (property "Manufacturer" "OSRAM")
    (property "Sheetfile" "power-supply.kicad_sch")
    (property "Sheetname" "Power supply")
    (property "ki_description" "LED, Green, SMD, 0603, 20 mA, 1.7 V, 570 nm")
    (property "ki_keywords" "SMT, DIODE, SEMICONDUCTOR, LED")
    (attr smd)
    (fp_text reference "D10" (at 1.8 -0.64167 90) (layer "F.SilkS")
        (effects (font (size 0.7 0.7) (thickness 0.127)))
    )
    (fp_text value "LED_G_0603_LG_L29K-G2J1-24-Z" (at 0 1.77) (layer "F.Fab")
        (effects (font (size 1 1) (thickness 0.15)))
    )
    (fp_text user "License: Apache-2.0" (at -1.4224 3.599 180) (layer "F.Fab") hide
        (effects (font (size 0.7 0.7) (thickness 0.15)) (justify left bottom))
    )
    (fp_text user "${REFERENCE}" (at -1.4224 5.999 180) (layer "F.Fab") hide
        (effects (font (size 0.7 0.7) (thickness 0.15)) (justify left bottom))
    )
    (fp_text user "Author: Antmicro" (at -1.4224 4.799 180) (layer "F.Fab") hide
        (effects (font (size 0.7 0.7) (thickness 0.15)) (justify left bottom))
    )
    (fp_line (start -1.18 -0.319) (end -1.18 0.321)
      (stroke (width 0.15) (type solid)) (layer "F.SilkS"))
    (fp_line (start -0.094672 0.001008) (end -0.24 0.001008)
      (stroke (width 0.1) (type solid)) (layer "F.SilkS"))
    (fp_line (start -0.094672 0.001008) (end 0.105328 -0.198992)
      (stroke (width 0.1) (type solid)) (layer "F.SilkS"))
    (fp_line (start -0.094672 0.201008) (end -0.094672 -0.198992)
      (stroke (width 0.1) (type solid)) (layer "F.SilkS"))
    (fp_line (start 0.105328 0.001008) (end 0.24 0.001)
      (stroke (width 0.1) (type solid)) (layer "F.SilkS"))
    (fp_line (start 0.105328 0.201008) (end -0.094672 0.001008)
      (stroke (width 0.1) (type solid)) (layer "F.SilkS"))
    (fp_line (start 0.105328 0.201008) (end 0.105328 -0.198992)
      (stroke (width 0.1) (type solid)) (layer "F.SilkS"))
    (fp_line (start 0.22 -0.35) (end -0.22 -0.35)
      (stroke (width 0.15) (type solid)) (layer "F.SilkS"))
    (fp_line (start 0.22 0.35) (end -0.22 0.35)
      (stroke (width 0.15) (type solid)) (layer "F.SilkS"))
    (fp_rect (start 1.25 0.65) (end -1.25 -0.65)
      (stroke (width 0.05) (type solid)) (fill none) (layer "F.CrtYd"))
    (fp_line (start -0.199 -0.202) (end -0.199 0.1)
      (stroke (width 0.15) (type solid)) (layer "F.Fab"))
    (fp_line (start -0.199 0) (end -0.597 0)
      (stroke (width 0.15) (type solid)) (layer "F.Fab"))
    (fp_line (start -0.199 0.2) (end -0.199 0.1)
      (stroke (width 0.15) (type solid)) (layer "F.Fab"))
    (fp_line (start -0.101 0) (end 0.201 0.2)
      (stroke (width 0.15) (type solid)) (layer "F.Fab"))
    (fp_line (start 0.201 -0.202) (end -0.101 0)
      (stroke (width 0.15) (type solid)) (layer "F.Fab"))
    (fp_line (start 0.201 0) (end 0.201 -0.202)
      (stroke (width 0.15) (type solid)) (layer "F.Fab"))
    (fp_line (start 0.201 0.2) (end 0.201 0)
      (stroke (width 0.15) (type solid)) (layer "F.Fab"))
    (fp_line (start 0.599 0) (end 0.201 0)
      (stroke (width 0.15) (type solid)) (layer "F.Fab"))
    (fp_rect (start 0.848 0.4) (end -0.85 -0.402)
      (stroke (width 0.15) (type solid)) (fill none) (layer "F.Fab"))
    (pad "1" smd roundrect (at -0.7 0) (size 0.8 1) (layers "F.Cu" "F.Paste" "F.Mask") (roundrect_rratio 0.2)
      (net 2 "VCC3V3") (pinfunction "C") (pintype "passive"))
    (pad "2" smd roundrect (at 0.7 0) (size 0.8 1) (layers "F.Cu" "F.Paste" "F.Mask") (roundrect_rratio 0.2)
      (net 344 "Net-(D10-A)") (pinfunction "A") (pintype "passive"))
  )

  (footprint "antmicro-footprints:LED_0603_1608Metric_G" (layer "F.Cu")
    (at 65.5 90.816664 180)
    (descr "LED SMD 0603 Green")
    (tags "LED SMD 0603 Green")
    (property "Author" "Antmicro")
    (property "Color" "Green")
    (property "License" "Apache-2.0")
    (property "MPN" "LG L29K-G2J1-24-Z")
    (property "Manufacturer" "OSRAM")
    (property "Sheetfile" "power-supply.kicad_sch")
    (property "Sheetname" "Power supply")
    (property "ki_description" "LED, Green, SMD, 0603, 20 mA, 1.7 V, 570 nm")
    (property "ki_keywords" "SMT, DIODE, SEMICONDUCTOR, LED")
    (attr smd)
    (fp_text reference "D11" (at 1.8 -0.283336 90) (layer "F.SilkS")
        (effects (font (size 0.7 0.7) (thickness 0.127)))
    )
    (fp_text value "LED_G_0603_LG_L29K-G2J1-24-Z" (at 0 1.77) (layer "F.Fab")
        (effects (font (size 1 1) (thickness 0.15)))
    )
    (fp_text user "${REFERENCE}" (at -1.4224 5.999 180) (layer "F.Fab") hide
        (effects (font (size 0.7 0.7) (thickness 0.15)) (justify left bottom))
    )
    (fp_text user "Author: Antmicro" (at -1.4224 4.799 180) (layer "F.Fab") hide
        (effects (font (size 0.7 0.7) (thickness 0.15)) (justify left bottom))
    )
    (fp_text user "License: Apache-2.0" (at -1.4224 3.599 180) (layer "F.Fab") hide
        (effects (font (size 0.7 0.7) (thickness 0.15)) (justify left bottom))
    )
    (fp_line (start -1.18 -0.319) (end -1.18 0.321)
      (stroke (width 0.15) (type solid)) (layer "F.SilkS"))
    (fp_line (start -0.094672 0.001008) (end -0.24 0.001008)
      (stroke (width 0.1) (type solid)) (layer "F.SilkS"))
    (fp_line (start -0.094672 0.001008) (end 0.105328 -0.198992)
      (stroke (width 0.1) (type solid)) (layer "F.SilkS"))
    (fp_line (start -0.094672 0.201008) (end -0.094672 -0.198992)
      (stroke (width 0.1) (type solid)) (layer "F.SilkS"))
    (fp_line (start 0.105328 0.001008) (end 0.24 0.001)
      (stroke (width 0.1) (type solid)) (layer "F.SilkS"))
    (fp_line (start 0.105328 0.201008) (end -0.094672 0.001008)
      (stroke (width 0.1) (type solid)) (layer "F.SilkS"))
    (fp_line (start 0.105328 0.201008) (end 0.105328 -0.198992)
      (stroke (width 0.1) (type solid)) (layer "F.SilkS"))
    (fp_line (start 0.22 -0.35) (end -0.22 -0.35)
      (stroke (width 0.15) (type solid)) (layer "F.SilkS"))
    (fp_line (start 0.22 0.35) (end -0.22 0.35)
      (stroke (width 0.15) (type solid)) (layer "F.SilkS"))
    (fp_rect (start 1.25 0.65) (end -1.25 -0.65)
      (stroke (width 0.05) (type solid)) (fill none) (layer "F.CrtYd"))
    (fp_line (start -0.199 -0.202) (end -0.199 0.1)
      (stroke (width 0.15) (type solid)) (layer "F.Fab"))
    (fp_line (start -0.199 0) (end -0.597 0)
      (stroke (width 0.15) (type solid)) (layer "F.Fab"))
    (fp_line (start -0.199 0.2) (end -0.199 0.1)
      (stroke (width 0.15) (type solid)) (layer "F.Fab"))
    (fp_line (start -0.101 0) (end 0.201 0.2)
      (stroke (width 0.15) (type solid)) (layer "F.Fab"))
    (fp_line (start 0.201 -0.202) (end -0.101 0)
      (stroke (width 0.15) (type solid)) (layer "F.Fab"))
    (fp_line (start 0.201 0) (end 0.201 -0.202)
      (stroke (width 0.15) (type solid)) (layer "F.Fab"))
    (fp_line (start 0.201 0.2) (end 0.201 0)
      (stroke (width 0.15) (type solid)) (layer "F.Fab"))
    (fp_line (start 0.599 0) (end 0.201 0)
      (stroke (width 0.15) (type solid)) (layer "F.Fab"))
    (fp_rect (start 0.848 0.4) (end -0.85 -0.402)
      (stroke (width 0.15) (type solid)) (fill none) (layer "F.Fab"))
    (pad "1" smd roundrect (at -0.7 0) (size 0.8 1) (layers "F.Cu" "F.Paste" "F.Mask") (roundrect_rratio 0.2)
      (net 2 "VCC3V3") (pinfunction "C") (pintype "passive"))
    (pad "2" smd roundrect (at 0.7 0) (size 0.8 1) (layers "F.Cu" "F.Paste" "F.Mask") (roundrect_rratio 0.2)
      (net 345 "Net-(D11-A)") (pinfunction "A") (pintype "passive"))
  )

  (footprint "antmicro-footprints:LED_0603_1608Metric_G" (layer "F.Cu")
    (at 65.5 89.174998 180)
    (descr "LED SMD 0603 Green")
    (tags "LED SMD 0603 Green")
    (property "Author" "Antmicro")
    (property "Color" "Green")
    (property "License" "Apache-2.0")
    (property "MPN" "LG L29K-G2J1-24-Z")
    (property "Manufacturer" "OSRAM")
    (property "Sheetfile" "power-supply.kicad_sch")
    (property "Sheetname" "Power supply")
    (property "ki_description" "LED, Green, SMD, 0603, 20 mA, 1.7 V, 570 nm")
    (property "ki_keywords" "SMT, DIODE, SEMICONDUCTOR, LED")
    (attr smd)
    (fp_text reference "D12" (at 1.8 0.024998 90) (layer "F.SilkS")
        (effects (font (size 0.7 0.7) (thickness 0.127)))
    )
    (fp_text value "LED_G_0603_LG_L29K-G2J1-24-Z" (at 0 1.77) (layer "F.Fab")
        (effects (font (size 1 1) (thickness 0.15)))
    )
    (fp_text user "${REFERENCE}" (at -1.4224 5.999 180) (layer "F.Fab") hide
        (effects (font (size 0.7 0.7) (thickness 0.15)) (justify left bottom))
    )
    (fp_text user "License: Apache-2.0" (at -1.4224 3.599 180) (layer "F.Fab") hide
        (effects (font (size 0.7 0.7) (thickness 0.15)) (justify left bottom))
    )
    (fp_text user "Author: Antmicro" (at -1.4224 4.799 180) (layer "F.Fab") hide
        (effects (font (size 0.7 0.7) (thickness 0.15)) (justify left bottom))
    )
    (fp_line (start -1.18 -0.319) (end -1.18 0.321)
      (stroke (width 0.15) (type solid)) (layer "F.SilkS"))
    (fp_line (start -0.094672 0.001008) (end -0.24 0.001008)
      (stroke (width 0.1) (type solid)) (layer "F.SilkS"))
    (fp_line (start -0.094672 0.001008) (end 0.105328 -0.198992)
      (stroke (width 0.1) (type solid)) (layer "F.SilkS"))
    (fp_line (start -0.094672 0.201008) (end -0.094672 -0.198992)
      (stroke (width 0.1) (type solid)) (layer "F.SilkS"))
    (fp_line (start 0.105328 0.001008) (end 0.24 0.001)
      (stroke (width 0.1) (type solid)) (layer "F.SilkS"))
    (fp_line (start 0.105328 0.201008) (end -0.094672 0.001008)
      (stroke (width 0.1) (type solid)) (layer "F.SilkS"))
    (fp_line (start 0.105328 0.201008) (end 0.105328 -0.198992)
      (stroke (width 0.1) (type solid)) (layer "F.SilkS"))
    (fp_line (start 0.22 -0.35) (end -0.22 -0.35)
      (stroke (width 0.15) (type solid)) (layer "F.SilkS"))
    (fp_line (start 0.22 0.35) (end -0.22 0.35)
      (stroke (width 0.15) (type solid)) (layer "F.SilkS"))
    (fp_rect (start 1.25 0.65) (end -1.25 -0.65)
      (stroke (width 0.05) (type solid)) (fill none) (layer "F.CrtYd"))
    (fp_line (start -0.199 -0.202) (end -0.199 0.1)
      (stroke (width 0.15) (type solid)) (layer "F.Fab"))
    (fp_line (start -0.199 0) (end -0.597 0)
      (stroke (width 0.15) (type solid)) (layer "F.Fab"))
    (fp_line (start -0.199 0.2) (end -0.199 0.1)
      (stroke (width 0.15) (type solid)) (layer "F.Fab"))
    (fp_line (start -0.101 0) (end 0.201 0.2)
      (stroke (width 0.15) (type solid)) (layer "F.Fab"))
    (fp_line (start 0.201 -0.202) (end -0.101 0)
      (stroke (width 0.15) (type solid)) (layer "F.Fab"))
    (fp_line (start 0.201 0) (end 0.201 -0.202)
      (stroke (width 0.15) (type solid)) (layer "F.Fab"))
    (fp_line (start 0.201 0.2) (end 0.201 0)
      (stroke (width 0.15) (type solid)) (layer "F.Fab"))
    (fp_line (start 0.599 0) (end 0.201 0)
      (stroke (width 0.15) (type solid)) (layer "F.Fab"))
    (fp_rect (start 0.848 0.4) (end -0.85 -0.402)
      (stroke (width 0.15) (type solid)) (fill none) (layer "F.Fab"))
    (pad "1" smd roundrect (at -0.7 0) (size 0.8 1) (layers "F.Cu" "F.Paste" "F.Mask") (roundrect_rratio 0.2)
      (net 2 "VCC3V3") (pinfunction "C") (pintype "passive"))
    (pad "2" smd roundrect (at 0.7 0) (size 0.8 1) (layers "F.Cu" "F.Paste" "F.Mask") (roundrect_rratio 0.2)
      (net 346 "Net-(D12-A)") (pinfunction "A") (pintype "passive"))
  )

  (footprint "antmicro-footprints:R_1206_3216Metric" (layer "F.Cu")
    (at 79.25 71.4 180)
    (property "Author" "Antmicro")
    (property "Current" "2A")
    (property "License" "Apache-2.0")
    (property "MPN" "MCMR12X000_PTL")
    (property "Manufacturer" "Multicomp Pro")
    (property "Public" "False")
    (property "Sheetfile" "power-supply.kicad_sch")
    (property "Sheetname" "Power supply")
    (property "Tolerance" "")
    (property "Val" "0R")
    (property "ki_description" "Zero Ohm Resistor, Jumper, 1206 [3216 Metric], Thick Film, 250 mW, 2 A, Surface Mount Device")
    (property "ki_keywords" "1206, SMT, RESISTOR, PASSIVE")
    (attr smd)
    (fp_text reference "R94" (at -2.46 -1.62 180) (layer "F.SilkS")
        (effects (font (size 0.7 0.7) (thickness 0.127)))
    )
    (fp_text value "R_0R_1206" (at 0 2.6) (layer "F.Fab")
        (effects (font (size 1 1) (thickness 0.15)))
    )
    (fp_text user "Author: Antmicro" (at -2.401 4.899 180) (layer "F.Fab") hide
        (effects (font (size 0.7 0.7) (thickness 0.15)) (justify left bottom))
    )
    (fp_text user "License: Apache-2.0" (at -2.401 6.3 180) (layer "F.Fab") hide
        (effects (font (size 0.7 0.7) (thickness 0.15)) (justify left bottom))
    )
    (fp_text user "${REFERENCE}" (at 0 0) (layer "F.Fab")
        (effects (font (size 1 1) (thickness 0.15)))
    )
    (fp_line (start 0.8 -0.899) (end -0.8 -0.899)
      (stroke (width 0.15) (type solid)) (layer "F.SilkS"))
    (fp_line (start 0.8 0.901) (end -0.8 0.901)
      (stroke (width 0.15) (type solid)) (layer "F.SilkS"))
    (fp_rect (start -2.325 -1.15) (end 2.325 1.15)
      (stroke (width 0.05) (type default)) (fill none) (layer "F.CrtYd"))
    (fp_line (start -1.601 -0.802) (end -1.601 0.8)
      (stroke (width 0.15) (type solid)) (layer "F.Fab"))
    (fp_line (start -1.601 -0.802) (end 1.6 -0.802)
      (stroke (width 0.15) (type solid)) (layer "F.Fab"))
    (fp_line (start -1.601 0.8) (end 1.6 0.8)
      (stroke (width 0.15) (type solid)) (layer "F.Fab"))
    (fp_line (start 1.6 -0.802) (end 1.6 0.8)
      (stroke (width 0.15) (type solid)) (layer "F.Fab"))
    (pad "1" smd roundrect (at -1.5 0.001 180) (size 1.15 1.8) (layers "F.Cu" "F.Paste" "F.Mask") (roundrect_rratio 0.25)
      (net 11 "VCC5V0") (pintype "passive"))
    (pad "2" smd roundrect (at 1.5 0.001 180) (size 1.15 1.8) (layers "F.Cu" "F.Paste" "F.Mask") (roundrect_rratio 0.25)
      (net 290 "Net-(C110-Pad2)") (pintype "passive"))
  )

  (footprint "antmicro-footprints:R_0402_1005Metric" (layer "F.Cu")
    (at 86 78.9 180)
    (descr "Resistor SMD 0402")
    (tags "resistor SMD 0402")
    (property "Author" "Antmicro")
    (property "License" "Apache-2.0")
    (property "MPN" "CR0402-FX-1002GLF")
    (property "Manufacturer" "Bourns")
    (property "Public" "False")
    (property "Sheetfile" "power-supply.kicad_sch")
    (property "Sheetname" "Power supply")
    (property "Tolerance" "1%")
    (property "Val" "10k")
    (property "ki_description" "SMD Chip Resistor, 10 kohm, ± 1%, 62.5 mW, 0402 [1005 Metric], Thick Film, General Purpose")
    (property "ki_keywords" "0402, SMT, RESISTOR, PASSIVE")
    (attr smd)
    (fp_text reference "R101" (at 0.72 -1.595) (layer "F.SilkS")
        (effects (font (size 0.7 0.7) (thickness 0.127)))
    )
    (fp_text value "R_10k_0402" (at 0 1.17) (layer "F.Fab")
        (effects (font (size 1 1) (thickness 0.15)))
    )
    (fp_text user "${REFERENCE}" (at 0 0) (layer "F.Fab")
        (effects (font (size 0.25 0.25) (thickness 0.04)))
    )
    (fp_text user "License: Apache-2.0" (at -0.95 5.169) (layer "F.Fab") hide
        (effects (font (size 0.7 0.7) (thickness 0.15)) (justify right bottom))
    )
    (fp_text user "Author: Antmicro" (at -0.95 4.169) (layer "F.Fab") hide
        (effects (font (size 0.7 0.7) (thickness 0.15)) (justify right bottom))
    )
    (fp_rect (start -0.925 -0.47) (end 0.925 0.47)
      (stroke (width 0.05) (type default)) (fill none) (layer "F.CrtYd"))
    (fp_rect (start -0.5 -0.25) (end 0.5 0.25)
      (stroke (width 0.15) (type solid)) (fill none) (layer "F.Fab"))
    (pad "1" smd roundrect (at -0.48 0 180) (size 0.59 0.64) (layers "F.Cu" "F.Paste" "F.Mask") (roundrect_rratio 0.25)
      (net 11 "VCC5V0") (pintype "passive"))
    (pad "2" smd roundrect (at 0.48 0 180) (size 0.59 0.64) (layers "F.Cu" "F.Paste" "F.Mask") (roundrect_rratio 0.25)
      (net 235 "/Power supply/1V2_PG") (pintype "passive"))
  )

  (footprint "antmicro-footprints:LED_0603_1608Metric_G" (layer "F.Cu")
    (at 65.5 87.533332 180)
    (descr "LED SMD 0603 Green")
    (tags "LED SMD 0603 Green")
    (property "Author" "Antmicro")
    (property "Color" "Green")
    (property "License" "Apache-2.0")
    (property "MPN" "LG L29K-G2J1-24-Z")
    (property "Manufacturer" "OSRAM")
    (property "Sheetfile" "power-supply.kicad_sch")
    (property "Sheetname" "Power supply")
    (property "ki_description" "LED, Green, SMD, 0603, 20 mA, 1.7 V, 570 nm")
    (property "ki_keywords" "SMT, DIODE, SEMICONDUCTOR, LED")
    (attr smd)
    (fp_text reference "D13" (at 1.8 0.433332 90) (layer "F.SilkS")
        (effects (font (size 0.7 0.7) (thickness 0.127)))
    )
    (fp_text value "LED_G_0603_LG_L29K-G2J1-24-Z" (at 0 1.77) (layer "F.Fab")
        (effects (font (size 1 1) (thickness 0.15)))
    )
    (fp_text user "Author: Antmicro" (at -1.4224 4.799 180) (layer "F.Fab") hide
        (effects (font (size 0.7 0.7) (thickness 0.15)) (justify left bottom))
    )
    (fp_text user "License: Apache-2.0" (at -1.4224 3.599 180) (layer "F.Fab") hide
        (effects (font (size 0.7 0.7) (thickness 0.15)) (justify left bottom))
    )
    (fp_text user "${REFERENCE}" (at -1.4224 5.999 180) (layer "F.Fab") hide
        (effects (font (size 0.7 0.7) (thickness 0.15)) (justify left bottom))
    )
    (fp_line (start -1.18 -0.319) (end -1.18 0.321)
      (stroke (width 0.15) (type solid)) (layer "F.SilkS"))
    (fp_line (start -0.094672 0.001008) (end -0.24 0.001008)
      (stroke (width 0.1) (type solid)) (layer "F.SilkS"))
    (fp_line (start -0.094672 0.001008) (end 0.105328 -0.198992)
      (stroke (width 0.1) (type solid)) (layer "F.SilkS"))
    (fp_line (start -0.094672 0.201008) (end -0.094672 -0.198992)
      (stroke (width 0.1) (type solid)) (layer "F.SilkS"))
    (fp_line (start 0.105328 0.001008) (end 0.24 0.001)
      (stroke (width 0.1) (type solid)) (layer "F.SilkS"))
    (fp_line (start 0.105328 0.201008) (end -0.094672 0.001008)
      (stroke (width 0.1) (type solid)) (layer "F.SilkS"))
    (fp_line (start 0.105328 0.201008) (end 0.105328 -0.198992)
      (stroke (width 0.1) (type solid)) (layer "F.SilkS"))
    (fp_line (start 0.22 -0.35) (end -0.22 -0.35)
      (stroke (width 0.15) (type solid)) (layer "F.SilkS"))
    (fp_line (start 0.22 0.35) (end -0.22 0.35)
      (stroke (width 0.15) (type solid)) (layer "F.SilkS"))
    (fp_rect (start 1.25 0.65) (end -1.25 -0.65)
      (stroke (width 0.05) (type solid)) (fill none) (layer "F.CrtYd"))
    (fp_line (start -0.199 -0.202) (end -0.199 0.1)
      (stroke (width 0.15) (type solid)) (layer "F.Fab"))
    (fp_line (start -0.199 0) (end -0.597 0)
      (stroke (width 0.15) (type solid)) (layer "F.Fab"))
    (fp_line (start -0.199 0.2) (end -0.199 0.1)
      (stroke (width 0.15) (type solid)) (layer "F.Fab"))
    (fp_line (start -0.101 0) (end 0.201 0.2)
      (stroke (width 0.15) (type solid)) (layer "F.Fab"))
    (fp_line (start 0.201 -0.202) (end -0.101 0)
      (stroke (width 0.15) (type solid)) (layer "F.Fab"))
    (fp_line (start 0.201 0) (end 0.201 -0.202)
      (stroke (width 0.15) (type solid)) (layer "F.Fab"))
    (fp_line (start 0.201 0.2) (end 0.201 0)
      (stroke (width 0.15) (type solid)) (layer "F.Fab"))
    (fp_line (start 0.599 0) (end 0.201 0)
      (stroke (width 0.15) (type solid)) (layer "F.Fab"))
    (fp_rect (start 0.848 0.4) (end -0.85 -0.402)
      (stroke (width 0.15) (type solid)) (fill none) (layer "F.Fab"))
    (pad "1" smd roundrect (at -0.7 0) (size 0.8 1) (layers "F.Cu" "F.Paste" "F.Mask") (roundrect_rratio 0.2)
      (net 2 "VCC3V3") (pinfunction "C") (pintype "passive"))
    (pad "2" smd roundrect (at 0.7 0) (size 0.8 1) (layers "F.Cu" "F.Paste" "F.Mask") (roundrect_rratio 0.2)
      (net 347 "Net-(D13-A)") (pinfunction "A") (pintype "passive"))
  )

  (footprint "antmicro-footprints:TP_SMD_1mm" (layer "F.Cu")
    (at 87.6 78.9 90)
    (property "Author" "Antmicro")
    (property "License" "Apache-2.0")
    (property "MPN" "")
    (property "Manufacturer" "")
    (property "Sheetfile" "power-supply.kicad_sch")
    (property "Sheetname" "Power supply")
    (property "exclude_from_bom" "")
    (property "ki_description" "Test point 1mm SMD")
    (property "ki_keywords" "TESTPOINT")
    (attr exclude_from_pos_files exclude_from_bom)
    (fp_text reference "TP7" (at -2.515 0.68 90) (layer "F.SilkS")
        (effects (font (size 0.7 0.7) (thickness 0.15)) (justify left bottom))
    )
    (fp_text value "TP_1mm_SMD" (at 0 1.4 90) (layer "F.Fab")
        (effects (font (size 0.7 0.7) (thickness 0.15)) (justify left bottom))
    )
    (fp_text user "Author: Antmicro" (at -0.5 4 90) (layer "F.Fab") hide
        (effects (font (size 0.7 0.7) (thickness 0.15)) (justify left bottom))
    )
    (fp_text user "${REFERENCE}" (at -0.5 2.8 90) (layer "F.Fab") hide
        (effects (font (size 0.7 0.7) (thickness 0.15)) (justify left bottom))
    )
    (fp_text user "License: Apache-2.0" (at -0.5 5.2 90) (layer "F.Fab") hide
        (effects (font (size 0.7 0.7) (thickness 0.15)) (justify left bottom))
    )
    (fp_circle (center 0 0) (end 0.6 0)
      (stroke (width 0.05) (type default)) (fill none) (layer "F.CrtYd"))
    (pad "1" smd circle (at 0 0 90) (size 1 1) (layers "F.Cu" "F.Mask")
      (net 354 "Net-(C108-Pad2)") (pinfunction "1") (pintype "passive"))
  )

  (footprint "antmicro-footprints:VSSOP-8_3x3mm_P0.65mm" (layer "F.Cu")
    (at 76.95 76.5 180)
    (property "Author" "Antmicro")
    (property "License" "Apache-2.0")
    (property "MPN" "LM3881MME/NOPB")
    (property "Manufacturer" "Texas Instruments")
    (property "Sheetfile" "power-supply.kicad_sch")
    (property "Sheetname" "Power supply")
    (property "ki_description" "Power Sequencer, 3-Monitors, 2.7V-5.5Vin,VSSOP-8")
    (property "ki_keywords" "SMT, PMIC, IC, POWER, SEQUENCER")
    (attr smd)
    (fp_text reference "U12" (at -4.7 1.485 90) (layer "F.SilkS")
        (effects (font (size 0.7 0.7) (thickness 0.127)) (justify right))
    )
    (fp_text value "LM3881MME_NOPB" (at -0.0254 2.9972) (layer "F.Fab")
        (effects (font (size 1.27 1.27) (thickness 0.15)))
    )
    (fp_text user "${REFERENCE}" (at -0.352 5.972 180) (layer "F.Fab") hide
        (effects (font (size 0.7 0.7) (thickness 0.15)) (justify left bottom))
    )
    (fp_text user "Author: Antmicro" (at -0.352 7.171 180) (layer "F.Fab") hide
        (effects (font (size 0.7 0.7) (thickness 0.15)) (justify left bottom))
    )
    (fp_text user "License: Apache-2.0" (at -0.352 8.371 180) (layer "F.Fab") hide
        (effects (font (size 0.7 0.7) (thickness 0.15)) (justify left bottom))
    )
    (fp_line (start -1.6 -1.625) (end 1.554 -1.625)
      (stroke (width 0.12) (type solid)) (layer "F.SilkS"))
    (fp_line (start -1.496 1.625) (end 1.554 1.625)
      (stroke (width 0.12) (type solid)) (layer "F.SilkS"))
    (fp_circle (center -2.1 -1.438) (end -2.05 -1.438)
      (stroke (width 0.12) (type solid)) (fill solid) (layer "F.SilkS"))
    (fp_rect (start -3 -1.838) (end 3 1.862)
      (stroke (width 0.05) (type solid)) (fill none) (layer "F.CrtYd"))
    (fp_line (start -1.497 -1.502) (end 1.504 -1.502)
      (stroke (width 0.15) (type solid)) (layer "F.Fab"))
    (fp_line (start -1.497 1.5) (end -1.497 -1.502)
      (stroke (width 0.15) (type solid)) (layer "F.Fab"))
    (fp_line (start 1.504 -1.502) (end 1.504 1.5)
      (stroke (width 0.15) (type solid)) (layer "F.Fab"))
    (fp_line (start 1.504 1.5) (end -1.497 1.5)
      (stroke (width 0.15) (type solid)) (layer "F.Fab"))
    (pad "1" smd rect (at -2.096 -0.975 180) (size 1.556504 0.457986) (layers "F.Cu" "F.Paste" "F.Mask")
      (net 11 "VCC5V0") (pinfunction "VCC") (pintype "power_in"))
    (pad "2" smd roundrect (at -2.096 -0.326 180) (size 1.556504 0.457986) (layers "F.Cu" "F.Paste" "F.Mask") (roundrect_rratio 0.5)
      (net 270 "/Power supply/5V0_PG") (pinfunction "EN") (pintype "passive"))
    (pad "3" smd roundrect (at -2.096 0.325 180) (size 1.556504 0.457986) (layers "F.Cu" "F.Paste" "F.Mask") (roundrect_rratio 0.5)
      (net 1 "GND") (pinfunction "GND") (pintype "power_in"))
    (pad "4" smd roundrect (at -2.096 0.974 180) (size 1.556504 0.457986) (layers "F.Cu" "F.Paste" "F.Mask") (roundrect_rratio 0.5)
      (net 1 "GND") (pinfunction "INV") (pintype "input"))
    (pad "5" smd roundrect (at 2.105 0.974 180) (size 1.556504 0.457986) (layers "F.Cu" "F.Paste" "F.Mask") (roundrect_rratio 0.5)
      (net 229 "Net-(U12-TADJ)") (pinfunction "TADJ") (pintype "passive"))
    (pad "6" smd roundrect (at 2.105 0.325 180) (size 1.556504 0.457986) (layers "F.Cu" "F.Paste" "F.Mask") (roundrect_rratio 0.5)
      (net 422 "Net-(U12-FLAG3)") (pinfunction "FLAG3") (pintype "open_collector"))
    (pad "7" smd roundrect (at 2.105 -0.326 180) (size 1.556504 0.457986) (layers "F.Cu" "F.Paste" "F.Mask") (roundrect_rratio 0.5)
      (net 420 "Net-(U12-FLAG2)") (pinfunction "FLAG2") (pintype "open_collector"))
    (pad "8" smd roundrect (at 2.105 -0.975 180) (size 1.556504 0.457986) (layers "F.Cu" "F.Paste" "F.Mask") (roundrect_rratio 0.5)
      (net 419 "Net-(U12-FLAG1)") (pinfunction "FLAG1") (pintype "open_collector"))
  )

  (footprint "antmicro-footprints:BGA-96_9.0x13.0mm_Layout2x3x16_P0.8mm" locked (layer "F.Cu")
    (at 83.5 123.35 180)
    (descr "BGA-96, http://www.mouser.com/ds/2/198/43-46TR16640B-81280BL-706483.pdf")
    (tags "BGA-96")
    (property "Author" "Antmicro")
    (property "License" "Apache-2.0")
    (property "MPN" "AS4C256M16D3")
    (property "Manufacturer" "Alliance Memory")
    (property "Sheetfile" "ddr3.kicad_sch")
    (property "Sheetname" "DDR3")
    (property "ki_description" "SDRAM - DDR3 Memory IC 4Gbit Parallel 800 MHz 20 ns 96-FBGA (9x13)")
    (property "ki_keywords" "SMT, MEMORY, IC, DDR, SYNCHRONOUS")
    (attr smd)
    (fp_text reference "U10" (at 3.41 7.225) (layer "F.SilkS")
        (effects (font (size 0.7 0.7) (thickness 0.127)))
    )
    (fp_text value "AS4C256M16D3" (at 0 7.5) (layer "F.Fab")
        (effects (font (size 1 1) (thickness 0.15)))
    )
    (fp_text user "Author: Antmicro" (at -5.5 10.698 180) (layer "F.Fab") hide
        (effects (font (size 0.7 0.7) (thickness 0.15)) (justify left bottom))
    )
    (fp_text user "License: Apache-2.0" (at -5.5 11.899 180) (layer "F.Fab") hide
        (effects (font (size 0.7 0.7) (thickness 0.15)) (justify left bottom))
    )
    (fp_text user "${REFERENCE}" (at 0 0) (layer "F.Fab")
        (effects (font (size 1 1) (thickness 0.15)))
    )
    (fp_line (start -4.8 -6.8) (end -4.8 -6.101)
      (stroke (width 0.15) (type solid)) (layer "F.SilkS"))
    (fp_line (start -4.601 -6.601) (end -4.601 6.599)
      (stroke (width 0.15) (type solid)) (layer "F.SilkS"))
    (fp_line (start -4.601 6.599) (end 4.599 6.599)
      (stroke (width 0.15) (type solid)) (layer "F.SilkS"))
    (fp_line (start -4.1 -6.8) (end -4.8 -6.8)
      (stroke (width 0.15) (type solid)) (layer "F.SilkS"))
    (fp_line (start 4.599 -6.601) (end -4.601 -6.601)
      (stroke (width 0.15) (type solid)) (layer "F.SilkS"))
    (fp_line (start 4.599 6.599) (end 4.599 -6.601)
      (stroke (width 0.15) (type solid)) (layer "F.SilkS"))
    (fp_rect (start -5 -7) (end 4.998 6.999)
      (stroke (width 0.05) (type solid)) (fill none) (layer "F.CrtYd"))
    (fp_line (start -4.5 -6) (end -4.5 6.499)
      (stroke (width 0.15) (type solid)) (layer "F.Fab"))
    (fp_line (start -4.5 6.499) (end 4.498 6.499)
      (stroke (width 0.15) (type solid)) (layer "F.Fab"))
    (fp_line (start -4 -6.5) (end -4.5 -6)
      (stroke (width 0.15) (type solid)) (layer "F.Fab"))
    (fp_line (start 4.498 -6.5) (end -4 -6.5)
      (stroke (width 0.15) (type solid)) (layer "F.Fab"))
    (fp_line (start 4.498 6.499) (end 4.498 -6.5)
      (stroke (width 0.15) (type solid)) (layer "F.Fab"))
    (pad "A1" smd circle locked (at -3.202 -6 180) (size 0.4 0.4) (layers "F.Cu" "F.Paste" "F.Mask")
      (net 3 "VCC1V35") (pinfunction "VDDQ") (pintype "power_in"))
    (pad "A2" smd circle locked (at -2.4 -6 180) (size 0.4 0.4) (layers "F.Cu" "F.Paste" "F.Mask")
      (net 180 "DDR3_DQ13") (pinfunction "DQ13") (pintype "bidirectional"))
    (pad "A3" smd circle locked (at -1.601 -6 180) (size 0.4 0.4) (layers "F.Cu" "F.Paste" "F.Mask")
      (net 179 "DDR3_DQ15") (pinfunction "DQ15") (pintype "bidirectional"))
    (pad "A7" smd circle locked (at 1.6 -6 180) (size 0.4 0.4) (layers "F.Cu" "F.Paste" "F.Mask")
      (net 185 "DDR3_DQ12") (pinfunction "DQ12") (pintype "bidirectional"))
    (pad "A8" smd circle locked (at 2.398 -6 180) (size 0.4 0.4) (layers "F.Cu" "F.Paste" "F.Mask")
      (net 3 "VCC1V35") (pinfunction "VDDQ") (pintype "passive"))
    (pad "A9" smd circle locked (at 3.2 -6 180) (size 0.4 0.4) (layers "F.Cu" "F.Paste" "F.Mask")
      (net 1 "GND") (pinfunction "VSS") (pintype "power_in"))
    (pad "B1" smd circle locked (at -3.202 -5.202 180) (size 0.4 0.4) (layers "F.Cu" "F.Paste" "F.Mask")
      (net 1 "GND") (pinfunction "VSSQ") (pintype "power_in"))
    (pad "B2" smd circle locked (at -2.4 -5.202 180) (size 0.4 0.4) (layers "F.Cu" "F.Paste" "F.Mask")
      (net 3 "VCC1V35") (pinfunction "VDD") (pintype "power_in"))
    (pad "B3" smd circle locked (at -1.601 -5.202 180) (size 0.4 0.4) (layers "F.Cu" "F.Paste" "F.Mask")
      (net 1 "GND") (pinfunction "VSS") (pintype "passive"))
    (pad "B7" smd circle locked (at 1.6 -5.202 180) (size 0.4 0.4) (layers "F.Cu" "F.Paste" "F.Mask")
      (net 176 "DDR3_DQS1-") (pinfunction "~{UDQS}") (pintype "bidirectional"))
    (pad "B8" smd circle locked (at 2.398 -5.202 180) (size 0.4 0.4) (layers "F.Cu" "F.Paste" "F.Mask")
      (net 181 "DDR3_DQ14") (pinfunction "DQ14") (pintype "bidirectional"))
    (pad "B9" smd circle locked (at 3.2 -5.202 180) (size 0.4 0.4) (layers "F.Cu" "F.Paste" "F.Mask")
      (net 1 "GND") (pinfunction "VSSQ") (pintype "passive"))
    (pad "C1" smd circle locked (at -3.202 -4.401 180) (size 0.4 0.4) (layers "F.Cu" "F.Paste" "F.Mask")
      (net 3 "VCC1V35") (pinfunction "VDDQ") (pintype "passive"))
    (pad "C2" smd circle locked (at -2.4 -4.401 180) (size 0.4 0.4) (layers "F.Cu" "F.Paste" "F.Mask")
      (net 187 "DDR3_DQ11") (pinfunction "DQ11") (pintype "bidirectional"))
    (pad "C3" smd circle locked (at -1.601 -4.401 180) (size 0.4 0.4) (layers "F.Cu" "F.Paste" "F.Mask")
      (net 182 "DDR3_DQ9") (pinfunction "DQ9") (pintype "bidirectional"))
    (pad "C7" smd circle locked (at 1.6 -4.401 180) (size 0.4 0.4) (layers "F.Cu" "F.Paste" "F.Mask")
      (net 175 "DDR3_DQS1+") (pinfunction "UDQS") (pintype "bidirectional"))
    (pad "C8" smd circle locked (at 2.398 -4.401 180) (size 0.4 0.4) (layers "F.Cu" "F.Paste" "F.Mask")
      (net 186 "DDR3_DQ10") (pinfunction "DQ10") (pintype "bidirectional"))
    (pad "C9" smd circle locked (at 3.2 -4.401 180) (size 0.4 0.4) (layers "F.Cu" "F.Paste" "F.Mask")
      (net 3 "VCC1V35") (pinfunction "VDDQ") (pintype "passive"))
    (pad "D1" smd circle locked (at -3.202 -3.601 180) (size 0.4 0.4) (layers "F.Cu" "F.Paste" "F.Mask")
      (net 1 "GND") (pinfunction "VSSQ") (pintype "passive"))
    (pad "D2" smd circle locked (at -2.4 -3.601 180) (size 0.4 0.4) (layers "F.Cu" "F.Paste" "F.Mask")
      (net 3 "VCC1V35") (pinfunction "VDDQ") (pintype "passive"))
    (pad "D3" smd circle locked (at -1.601 -3.601 180) (size 0.4 0.4) (layers "F.Cu" "F.Paste" "F.Mask")
      (net 184 "DDR3_DM1") (pinfunction "UDM") (pintype "input"))
    (pad "D7" smd circle locked (at 1.6 -3.601 180) (size 0.4 0.4) (layers "F.Cu" "F.Paste" "F.Mask")
      (net 195 "DDR3_DQ8") (pinfunction "DQ8") (pintype "bidirectional"))
    (pad "D8" smd circle locked (at 2.398 -3.601 180) (size 0.4 0.4) (layers "F.Cu" "F.Paste" "F.Mask")
      (net 1 "GND") (pinfunction "VSSQ") (pintype "passive"))
    (pad "D9" smd circle locked (at 3.2 -3.601 180) (size 0.4 0.4) (layers "F.Cu" "F.Paste" "F.Mask")
      (net 3 "VCC1V35") (pinfunction "VDD") (pintype "passive"))
    (pad "E1" smd circle locked (at -3.202 -2.801 180) (size 0.4 0.4) (layers "F.Cu" "F.Paste" "F.Mask")
      (net 1 "GND") (pinfunction "VSS") (pintype "passive"))
    (pad "E2" smd circle locked (at -2.4 -2.801 180) (size 0.4 0.4) (layers "F.Cu" "F.Paste" "F.Mask")
      (net 1 "GND") (pinfunction "VSSQ") (pintype "passive"))
    (pad "E3" smd circle locked (at -1.601 -2.801 180) (size 0.4 0.4) (layers "F.Cu" "F.Paste" "F.Mask")
      (net 196 "DDR3_DQ0") (pinfunction "DQ0") (pintype "bidirectional"))
    (pad "E7" smd circle locked (at 1.6 -2.801 180) (size 0.4 0.4) (layers "F.Cu" "F.Paste" "F.Mask")
      (net 178 "DDR3_DM0") (pinfunction "LDM") (pintype "input"))
    (pad "E8" smd circle locked (at 2.398 -2.801 180) (size 0.4 0.4) (layers "F.Cu" "F.Paste" "F.Mask")
      (net 1 "GND") (pinfunction "VSSQ") (pintype "passive"))
    (pad "E9" smd circle locked (at 3.2 -2.801 180) (size 0.4 0.4) (layers "F.Cu" "F.Paste" "F.Mask")
      (net 3 "VCC1V35") (pinfunction "VDDQ") (pintype "passive"))
    (pad "F1" smd circle locked (at -3.202 -2 180) (size 0.4 0.4) (layers "F.Cu" "F.Paste" "F.Mask")
      (net 3 "VCC1V35") (pinfunction "VDDQ") (pintype "passive"))
    (pad "F2" smd circle locked (at -2.4 -2 180) (size 0.4 0.4) (layers "F.Cu" "F.Paste" "F.Mask")
      (net 190 "DDR3_DQ2") (pinfunction "DQ2") (pintype "bidirectional"))
    (pad "F3" smd circle locked (at -1.601 -2 180) (size 0.4 0.4) (layers "F.Cu" "F.Paste" "F.Mask")
      (net 183 "DDR3_DQS0+") (pinfunction "LDQS") (pintype "bidirectional"))
    (pad "F7" smd circle locked (at 1.6 -2 180) (size 0.4 0.4) (layers "F.Cu" "F.Paste" "F.Mask")
      (net 191 "DDR3_DQ1") (pinfunction "DQ1") (pintype "bidirectional"))
    (pad "F8" smd circle locked (at 2.398 -2 180) (size 0.4 0.4) (layers "F.Cu" "F.Paste" "F.Mask")
      (net 193 "DDR3_DQ3") (pinfunction "DQ3") (pintype "bidirectional"))
    (pad "F9" smd circle locked (at 3.2 -2 180) (size 0.4 0.4) (layers "F.Cu" "F.Paste" "F.Mask")
      (net 1 "GND") (pinfunction "VSSQ") (pintype "passive"))
    (pad "G1" smd circle locked (at -3.202 -1.2 180) (size 0.4 0.4) (layers "F.Cu" "F.Paste" "F.Mask")
      (net 1 "GND") (pinfunction "VSSQ") (pintype "passive"))
    (pad "G2" smd circle locked (at -2.4 -1.2 180) (size 0.4 0.4) (layers "F.Cu" "F.Paste" "F.Mask")
      (net 194 "DDR3_DQ6") (pinfunction "DQ6") (pintype "bidirectional"))
    (pad "G3" smd circle locked (at -1.601 -1.2 180) (size 0.4 0.4) (layers "F.Cu" "F.Paste" "F.Mask")
      (net 177 "DDR3_DQS0-") (pinfunction "~{LDQS}") (pintype "bidirectional"))
    (pad "G7" smd circle locked (at 1.6 -1.2 180) (size 0.4 0.4) (layers "F.Cu" "F.Paste" "F.Mask")
      (net 3 "VCC1V35") (pinfunction "VDD") (pintype "passive"))
    (pad "G8" smd circle locked (at 2.398 -1.2 180) (size 0.4 0.4) (layers "F.Cu" "F.Paste" "F.Mask")
      (net 1 "GND") (pinfunction "VSS") (pintype "passive"))
    (pad "G9" smd circle locked (at 3.2 -1.2 180) (size 0.4 0.4) (layers "F.Cu" "F.Paste" "F.Mask")
      (net 1 "GND") (pinfunction "VSSQ") (pintype "passive"))
    (pad "H1" smd circle locked (at -3.202 -0.402 180) (size 0.4 0.4) (layers "F.Cu" "F.Paste" "F.Mask")
      (net 217 "DDR3_VREF") (pinfunction "VREF_DQ") (pintype "power_in"))
    (pad "H2" smd circle locked (at -2.4 -0.402 180) (size 0.4 0.4) (layers "F.Cu" "F.Paste" "F.Mask")
      (net 3 "VCC1V35") (pinfunction "VDDQ") (pintype "passive"))
    (pad "H3" smd circle locked (at -1.601 -0.402 180) (size 0.4 0.4) (layers "F.Cu" "F.Paste" "F.Mask")
      (net 192 "DDR3_DQ4") (pinfunction "DQ4") (pintype "bidirectional"))
    (pad "H7" smd circle locked (at 1.6 -0.402 180) (size 0.4 0.4) (layers "F.Cu" "F.Paste" "F.Mask")
      (net 188 "DDR3_DQ7") (pinfunction "DQ7") (pintype "bidirectional"))
    (pad "H8" smd circle locked (at 2.398 -0.402 180) (size 0.4 0.4) (layers "F.Cu" "F.Paste" "F.Mask")
      (net 189 "DDR3_DQ5") (pinfunction "DQ5") (pintype "bidirectional"))
    (pad "H9" smd circle locked (at 3.2 -0.402 180) (size 0.4 0.4) (layers "F.Cu" "F.Paste" "F.Mask")
      (net 3 "VCC1V35") (pinfunction "VDDQ") (pintype "passive"))
    (pad "J1" smd circle locked (at -3.202 0.4 180) (size 0.4 0.4) (layers "F.Cu" "F.Paste" "F.Mask")
      (net 504 "unconnected-(U10-NC{slash}ODT1-PadJ1)") (pinfunction "NC/ODT1") (pintype "passive+no_connect"))
    (pad "J2" smd circle locked (at -2.4 0.4 180) (size 0.4 0.4) (layers "F.Cu" "F.Paste" "F.Mask")
      (net 1 "GND") (pinfunction "VSS") (pintype "passive"))
    (pad "J3" smd circle locked (at -1.601 0.4 180) (size 0.4 0.4) (layers "F.Cu" "F.Paste" "F.Mask")
      (net 258 "DDR3_RAS") (pinfunction "~{RAS}") (pintype "input"))
    (pad "J7" smd circle locked (at 1.6 0.4 180) (size 0.4 0.4) (layers "F.Cu" "F.Paste" "F.Mask")
      (net 261 "DDR3_CLK+") (pinfunction "CK") (pintype "input"))
    (pad "J8" smd circle locked (at 2.398 0.4 180) (size 0.4 0.4) (layers "F.Cu" "F.Paste" "F.Mask")
      (net 1 "GND") (pinfunction "VSS") (pintype "passive"))
    (pad "J9" smd circle locked (at 3.2 0.4 180) (size 0.4 0.4) (layers "F.Cu" "F.Paste" "F.Mask")
      (net 505 "unconnected-(U10-NC{slash}CKE1-PadJ9)") (pinfunction "NC/CKE1") (pintype "passive+no_connect"))
    (pad "K1" smd circle locked (at -3.202 1.199 180) (size 0.4 0.4) (layers "F.Cu" "F.Paste" "F.Mask")
      (net 259 "DDR3_ODT") (pinfunction "ODT") (pintype "input"))
    (pad "K2" smd circle locked (at -2.4 1.199 180) (size 0.4 0.4) (layers "F.Cu" "F.Paste" "F.Mask")
      (net 3 "VCC1V35") (pinfunction "VDD") (pintype "passive"))
    (pad "K3" smd circle locked (at -1.601 1.199 180) (size 0.4 0.4) (layers "F.Cu" "F.Paste" "F.Mask")
      (net 254 "DDR3_CAS") (pinfunction "~{CAS}") (pintype "input"))
    (pad "K7" smd circle locked (at 1.6 1.199 180) (size 0.4 0.4) (layers "F.Cu" "F.Paste" "F.Mask")
      (net 262 "DDR3_CLK-") (pinfunction "~{CK}") (pintype "input"))
    (pad "K8" smd circle locked (at 2.398 1.199 180) (size 0.4 0.4) (layers "F.Cu" "F.Paste" "F.Mask")
      (net 3 "VCC1V35") (pinfunction "VDD") (pintype "passive"))
    (pad "K9" smd circle locked (at 3.2 1.199 180) (size 0.4 0.4) (layers "F.Cu" "F.Paste" "F.Mask")
      (net 260 "DDR3_CKE") (pinfunction "CKE") (pintype "input"))
    (pad "L1" smd circle locked (at -3.202 1.999 180) (size 0.4 0.4) (layers "F.Cu" "F.Paste" "F.Mask")
      (net 506 "unconnected-(U10-NC{slash}~{CS1}-PadL1)") (pinfunction "NC/~{CS1}") (pintype "passive+no_connect"))
    (pad "L2" smd circle locked (at -2.4 1.999 180) (size 0.4 0.4) (layers "F.Cu" "F.Paste" "F.Mask")
      (net 257 "DDR3_CS") (pinfunction "~{CS}") (pintype "input"))
    (pad "L3" smd circle locked (at -1.601 1.999 180) (size 0.4 0.4) (layers "F.Cu" "F.Paste" "F.Mask")
      (net 251 "DDR3_WE") (pinfunction "~{WE}") (pintype "input"))
    (pad "L7" smd circle locked (at 1.6 1.999 180) (size 0.4 0.4) (layers "F.Cu" "F.Paste" "F.Mask")
      (net 250 "DDR3_A10") (pinfunction "A10/AP") (pintype "input"))
    (pad "L8" smd circle locked (at 2.398 1.999 180) (size 0.4 0.4) (layers "F.Cu" "F.Paste" "F.Mask")
      (net 418 "Net-(U10-ZQ)") (pinfunction "ZQ") (pintype "passive"))
    (pad "L9" smd circle locked (at 3.2 1.999 180) (size 0.4 0.4) (layers "F.Cu" "F.Paste" "F.Mask")
      (net 507 "unconnected-(U10-NC{slash}ZQ1-PadL9)") (pinfunction "NC/ZQ1") (pintype "passive+no_connect"))
    (pad "M1" smd circle locked (at -3.202 2.798 180) (size 0.4 0.4) (layers "F.Cu" "F.Paste" "F.Mask")
      (net 1 "GND") (pinfunction "VSS") (pintype "passive"))
    (pad "M2" smd circle locked (at -2.4 2.798 180) (size 0.4 0.4) (layers "F.Cu" "F.Paste" "F.Mask")
      (net 256 "DDR3_BA0") (pinfunction "BA0") (pintype "input"))
    (pad "M3" smd circle locked (at -1.601 2.798 180) (size 0.4 0.4) (layers "F.Cu" "F.Paste" "F.Mask")
      (net 252 "DDR3_BA2") (pinfunction "BA2") (pintype "input"))
    (pad "M7" smd circle locked (at 1.6 2.798 180) (size 0.4 0.4) (layers "F.Cu" "F.Paste" "F.Mask")
      (net 508 "unconnected-(U10-NC{slash}A15-PadM7)") (pinfunction "NC/A15") (pintype "passive+no_connect"))
    (pad "M8" smd circle locked (at 2.398 2.798 180) (size 0.4 0.4) (layers "F.Cu" "F.Paste" "F.Mask")
      (net 217 "DDR3_VREF") (pinfunction "VREF_CA") (pintype "power_in"))
    (pad "M9" smd circle locked (at 3.2 2.798 180) (size 0.4 0.4) (layers "F.Cu" "F.Paste" "F.Mask")
      (net 1 "GND") (pinfunction "VSS") (pintype "passive"))
    (pad "N1" smd circle locked (at -3.202 3.6 180) (size 0.4 0.4) (layers "F.Cu" "F.Paste" "F.Mask")
      (net 3 "VCC1V35") (pinfunction "VDD") (pintype "passive"))
    (pad "N2" smd circle locked (at -2.4 3.6 180) (size 0.4 0.4) (layers "F.Cu" "F.Paste" "F.Mask")
      (net 255 "DDR3_A3") (pinfunction "A3") (pintype "input"))
    (pad "N3" smd circle locked (at -1.601 3.6 180) (size 0.4 0.4) (layers "F.Cu" "F.Paste" "F.Mask")
      (net 246 "DDR3_A0") (pinfunction "A0") (pintype "input"))
    (pad "N7" smd circle locked (at 1.6 3.6 180) (size 0.4 0.4) (layers "F.Cu" "F.Paste" "F.Mask")
      (net 248 "DDR3_A12") (pinfunction "A12/~{BC}") (pintype "input"))
    (pad "N8" smd circle locked (at 2.398 3.6 180) (size 0.4 0.4) (layers "F.Cu" "F.Paste" "F.Mask")
      (net 249 "DDR3_BA1") (pinfunction "BA1") (pintype "input"))
    (pad "N9" smd circle locked (at 3.2 3.6 180) (size 0.4 0.4) (layers "F.Cu" "F.Paste" "F.Mask")
      (net 3 "VCC1V35") (pinfunction "VDD") (pintype "passive"))
    (pad "P1" smd circle locked (at -3.202 4.4 180) (size 0.4 0.4) (layers "F.Cu" "F.Paste" "F.Mask")
      (net 1 "GND") (pinfunction "VSS") (pintype "passive"))
    (pad "P2" smd circle locked (at -2.4 4.4 180) (size 0.4 0.4) (layers "F.Cu" "F.Paste" "F.Mask")
      (net 253 "DDR3_A5") (pinfunction "A5") (pintype "input"))
    (pad "P3" smd circle locked (at -1.601 4.4 180) (size 0.4 0.4) (layers "F.Cu" "F.Paste" "F.Mask")
      (net 241 "DDR3_A2") (pinfunction "A2") (pintype "input"))
    (pad "P7" smd circle locked (at 1.6 4.4 180) (size 0.4 0.4) (layers "F.Cu" "F.Paste" "F.Mask")
      (net 247 "DDR3_A1") (pinfunction "A1") (pintype "input"))
    (pad "P8" smd circle locked (at 2.398 4.4 180) (size 0.4 0.4) (layers "F.Cu" "F.Paste" "F.Mask")
      (net 245 "DDR3_A4") (pinfunction "A4") (pintype "input"))
    (pad "P9" smd circle locked (at 3.2 4.4 180) (size 0.4 0.4) (layers "F.Cu" "F.Paste" "F.Mask")
      (net 1 "GND") (pinfunction "VSS") (pintype "passive"))
    (pad "R1" smd circle locked (at -3.202 5.2 180) (size 0.4 0.4) (layers "F.Cu" "F.Paste" "F.Mask")
      (net 3 "VCC1V35") (pinfunction "VDD") (pintype "passive"))
    (pad "R2" smd circle locked (at -2.4 5.2 180) (size 0.4 0.4) (layers "F.Cu" "F.Paste" "F.Mask")
      (net 240 "DDR3_A7") (pinfunction "A7") (pintype "input"))
    (pad "R3" smd circle locked (at -1.601 5.2 180) (size 0.4 0.4) (layers "F.Cu" "F.Paste" "F.Mask")
      (net 239 "DDR3_A9") (pinfunction "A9") (pintype "input"))
    (pad "R7" smd circle locked (at 1.6 5.2 180) (size 0.4 0.4) (layers "F.Cu" "F.Paste" "F.Mask")
      (net 238 "DDR3_A11") (pinfunction "A11") (pintype "input"))
    (pad "R8" smd circle locked (at 2.398 5.2 180) (size 0.4 0.4) (layers "F.Cu" "F.Paste" "F.Mask")
      (net 242 "DDR3_A6") (pinfunction "A6") (pintype "input"))
    (pad "R9" smd circle locked (at 3.2 5.2 180) (size 0.4 0.4) (layers "F.Cu" "F.Paste" "F.Mask")
      (net 3 "VCC1V35") (pinfunction "VDD") (pintype "passive"))
    (pad "T1" smd circle locked (at -3.202 5.999 180) (size 0.4 0.4) (layers "F.Cu" "F.Paste" "F.Mask")
      (net 1 "GND") (pinfunction "VSS") (pintype "passive"))
    (pad "T2" smd circle locked (at -2.4 5.999 180) (size 0.4 0.4) (layers "F.Cu" "F.Paste" "F.Mask")
      (net 263 "DDR3_RESET") (pinfunction "~{RESET}") (pintype "input"))
    (pad "T3" smd circle locked (at -1.601 5.999 180) (size 0.4 0.4) (layers "F.Cu" "F.Paste" "F.Mask")
      (net 237 "DDR3_A13") (pinfunction "A13") (pintype "input"))
    (pad "T7" smd circle locked (at 1.6 5.999 180) (size 0.4 0.4) (layers "F.Cu" "F.Paste" "F.Mask")
      (net 244 "DDR3_A14") (pinfunction "A14") (pintype "input"))
    (pad "T8" smd circle locked (at 2.398 5.999 180) (size 0.4 0.4) (layers "F.Cu" "F.Paste" "F.Mask")
      (net 243 "DDR3_A8") (pinfunction "A8") (pintype "input"))
    (pad "T9" smd circle locked (at 3.2 5.999 180) (size 0.4 0.4) (layers "F.Cu" "F.Paste" "F.Mask")
      (net 1 "GND") (pinfunction "VSS") (pintype "passive"))
  )

  (footprint "antmicro-footprints:VQFN-20_1EP_4.5x2.5mm_P0.5mm" (layer "F.Cu")
    (at 90.9 145.35 -90)
    (property "Author" "Antmicro")
    (property "License" "Apache-2.0")
    (property "MPN" "NVT2008BQ,115")
    (property "Manufacturer" "NXP")
    (property "Sheetfile" "interfaces.kicad_sch")
    (property "Sheetname" "Interfaces")
    (property "ki_description" "Bidirectional Voltage Level Translator, 8 Inputs, 1.5ns, 1.8V to 5.5V, DHVQFN-20")
    (property "ki_keywords" "SMT, LEVEL-SHIFTER, IC, LOGIC")
    (attr smd)
    (fp_text reference "U7" (at 2.03 2.59 90) (layer "F.SilkS")
        (effects (font (size 0.7 0.7) (thickness 0.127)))
    )
    (fp_text value "NVT2008BQ,115" (at 0.69 2.96 90) (layer "F.Fab") hide
        (effects (font (size 1 1) (thickness 0.015)))
    )
    (fp_text user "${REFERENCE}" (at -3.347 4.959 -90) (layer "F.Fab") hide
        (effects (font (size 0.7 0.7) (thickness 0.15)) (justify left bottom))
    )
    (fp_text user "Author: Antmicro" (at -3.347 6.16 -90) (layer "F.Fab") hide
        (effects (font (size 0.7 0.7) (thickness 0.15)) (justify left bottom))
    )
    (fp_text user "License: Apache-2.0" (at -3.347 7.36 -90) (layer "F.Fab") hide
        (effects (font (size 0.7 0.7) (thickness 0.15)) (justify left bottom))
    )
    (fp_poly
      (pts
        (xy -0.951 -0.32)
        (xy 0.949 -0.32)
        (xy 0.949 0.32)
        (xy -0.951 0.32)
      )

      (stroke (width 0.01) (type solid)) (fill solid) (layer "F.Paste"))
    (fp_line (start -2.25 -1.25) (end -2.25 -0.5)
      (stroke (width 0.15) (type solid)) (layer "F.SilkS"))
    (fp_line (start -2.249 1.25) (end -2 1.25)
      (stroke (width 0.15) (type solid)) (layer "F.SilkS"))
    (fp_line (start -2.001 -1.25) (end -2.25 -1.25)
      (stroke (width 0.15) (type solid)) (layer "F.SilkS"))
    (fp_line (start 2.249 -1.25) (end 2 -1.25)
      (stroke (width 0.15) (type solid)) (layer "F.SilkS"))
    (fp_line (start 2.249 -1.25) (end 2.249 -0.5)
      (stroke (width 0.15) (type solid)) (layer "F.SilkS"))
    (fp_line (start 2.249 1.249) (end 2 1.249)
      (stroke (width 0.15) (type solid)) (layer "F.SilkS"))
    (fp_line (start 2.249 1.249) (end 2.249 0.5)
      (stroke (width 0.15) (type solid)) (layer "F.SilkS"))
    (fp_rect (start -2.711 -1.71) (end 2.708 1.709)
      (stroke (width 0.05) (type solid)) (fill none) (layer "F.CrtYd"))
    (fp_line (start -2.25 1.249) (end -2.25 -1.25)
      (stroke (width 0.15) (type solid)) (layer "F.Fab"))
    (fp_line (start 2.249 -1.25) (end -2.25 -1.25)
      (stroke (width 0.15) (type solid)) (layer "F.Fab"))
    (fp_line (start 2.249 1.249) (end -2.25 1.249)
      (stroke (width 0.15) (type solid)) (layer "F.Fab"))
    (fp_line (start 2.249 1.249) (end 2.249 -1.25)
      (stroke (width 0.15) (type solid)) (layer "F.Fab"))
    (pad "1" smd roundrect (at -2.186 0.248) (size 0.26 0.86) (layers "F.Cu" "F.Paste" "F.Mask") (roundrect_rratio 0.25)
      (chamfer_ratio 0.3) (chamfer top_left)
      (net 1 "GND") (pinfunction "GND") (pintype "power_in"))
    (pad "2" smd roundrect (at -1.75 1.185 270) (size 0.26 0.86) (layers "F.Cu" "F.Paste" "F.Mask") (roundrect_rratio 0.2)
      (net 12 "VCC1V0") (pinfunction "VREFA") (pintype "power_in"))
    (pad "3" smd roundrect (at -1.25 1.185 270) (size 0.26 0.86) (layers "F.Cu" "F.Paste" "F.Mask") (roundrect_rratio 0.2)
      (net 206 "I3C[0]_SCL_1V0") (pinfunction "A1") (pintype "bidirectional"))
    (pad "4" smd roundrect (at -0.75 1.185 270) (size 0.26 0.86) (layers "F.Cu" "F.Paste" "F.Mask") (roundrect_rratio 0.2)
      (net 205 "I3C[0]_SDA_1V0") (pinfunction "A2") (pintype "bidirectional"))
    (pad "5" smd roundrect (at -0.25 1.185 270) (size 0.26 0.86) (layers "F.Cu" "F.Paste" "F.Mask") (roundrect_rratio 0.2)
      (net 208 "I3C[1]_SCL_1V0") (pinfunction "A3") (pintype "bidirectional"))
    (pad "6" smd roundrect (at 0.248 1.185 270) (size 0.26 0.86) (layers "F.Cu" "F.Paste" "F.Mask") (roundrect_rratio 0.2)
      (net 207 "I3C[1]_SDA_1V0") (pinfunction "A4") (pintype "bidirectional"))
    (pad "7" smd roundrect (at 0.748 1.185 270) (size 0.26 0.86) (layers "F.Cu" "F.Paste" "F.Mask") (roundrect_rratio 0.2)
      (net 210 "I3C[2]_SCL_1V0") (pinfunction "A5") (pintype "bidirectional"))
    (pad "8" smd roundrect (at 1.249 1.185 270) (size 0.26 0.86) (layers "F.Cu" "F.Paste" "F.Mask") (roundrect_rratio 0.2)
      (net 209 "I3C[2]_SDA_1V0") (pinfunction "A6") (pintype "bidirectional"))
    (pad "9" smd roundrect (at 1.749 1.185 270) (size 0.26 0.86) (layers "F.Cu" "F.Paste" "F.Mask") (roundrect_rratio 0.2)
      (net 204 "I3C[3]_SCL_1V0") (pinfunction "A7") (pintype "bidirectional"))
    (pad "10" smd roundrect (at 2.185 0.248) (size 0.26 0.86) (layers "F.Cu" "F.Paste" "F.Mask") (roundrect_rratio 0.2)
      (net 203 "I3C[3]_SDA_1V0") (pinfunction "A8") (pintype "bidirectional"))
    (pad "11" smd roundrect (at 2.185 -0.25) (size 0.26 0.86) (layers "F.Cu" "F.Paste" "F.Mask") (roundrect_rratio 0.2)
      (net 173 "I3C[3]_SDA_3V3") (pinfunction "B8") (pintype "bidirectional"))
    (pad "12" smd roundrect (at 1.749 -1.186 270) (size 0.26 0.86) (layers "F.Cu" "F.Paste" "F.Mask") (roundrect_rratio 0.2)
      (net 174 "I3C[3]_SCL_3V3") (pinfunction "B7") (pintype "bidirectional"))
    (pad "13" smd roundrect (at 1.249 -1.186 270) (size 0.26 0.86) (layers "F.Cu" "F.Paste" "F.Mask") (roundrect_rratio 0.2)
      (net 171 "I3C[2]_SDA_3V3") (pinfunction "B6") (pintype "bidirectional"))
    (pad "14" smd roundrect (at 0.748 -1.186 270) (size 0.26 0.86) (layers "F.Cu" "F.Paste" "F.Mask") (roundrect_rratio 0.2)
      (net 172 "I3C[2]_SCL_3V3") (pinfunction "B5") (pintype "bidirectional"))
    (pad "15" smd roundrect (at 0.248 -1.186 270) (size 0.26 0.86) (layers "F.Cu" "F.Paste" "F.Mask") (roundrect_rratio 0.2)
      (net 169 "I3C[1]_SDA_3V3") (pinfunction "B4") (pintype "bidirectional"))
    (pad "16" smd roundrect (at -0.25 -1.186 270) (size 0.26 0.86) (layers "F.Cu" "F.Paste" "F.Mask") (roundrect_rratio 0.2)
      (net 170 "I3C[1]_SCL_3V3") (pinfunction "B3") (pintype "bidirectional"))
    (pad "17" smd roundrect (at -0.75 -1.186 270) (size 0.26 0.86) (layers "F.Cu" "F.Paste" "F.Mask") (roundrect_rratio 0.2)
      (net 167 "I3C[0]_SDA_3V3") (pinfunction "B2") (pintype "bidirectional"))
    (pad "18" smd roundrect (at -1.25 -1.186 270) (size 0.26 0.86) (layers "F.Cu" "F.Paste" "F.Mask") (roundrect_rratio 0.2)
      (net 168 "I3C[0]_SCL_3V3") (pinfunction "B1") (pintype "bidirectional"))
    (pad "19" smd roundrect (at -1.75 -1.186 270) (size 0.26 0.86) (layers "F.Cu" "F.Paste" "F.Mask") (roundrect_rratio 0.2)
      (net 220 "Net-(U7-EN)") (pinfunction "VREFB") (pintype "power_in"))
    (pad "20" smd roundrect (at -2.186 -0.25) (size 0.26 0.86) (layers "F.Cu" "F.Paste" "F.Mask") (roundrect_rratio 0.2)
      (net 220 "Net-(U7-EN)") (pinfunction "EN") (pintype "input"))
    (pad "21" smd roundrect (at 0 0 270) (size 3 1) (layers "F.Cu" "F.Mask") (roundrect_rratio 0.1)
      (net 776 "unconnected-(U7-EP-Pad21)") (pinfunction "EP") (pintype "power_in+no_connect"))
  )

  (footprint "antmicro-footprints:C_0402_1005Metric" (layer "F.Cu")
    (at 87.4 141.05 -90)
    (descr "Capacitor SMD 0402")
    (tags "capacitor SMD 0402")
    (property "Author" "Antmicro")
    (property "Dielectric" "X5R")
    (property "License" "Apache-2.0")
    (property "MPN" "GRM155R61H104KE14D")
    (property "Manufacturer" "Murata")
    (property "Public" "False")
    (property "Sheetfile" "interfaces.kicad_sch")
    (property "Sheetname" "Interfaces")
    (property "Val" "100n")
    (property "Voltage" "50V")
    (property "ki_description" "SMD Multilayer Ceramic Capacitor, 0.1 µF, 50 V, 0402 [1005 Metric], ± 10%, X5R, GRM Series")
    (property "ki_keywords" "0402, SMT, CAPACITOR, PASSIVE, CERAMIC, MLCC")
    (attr smd)
    (fp_text reference "C55" (at -2.53 -0.03 90) (layer "F.SilkS")
        (effects (font (size 0.7 0.7) (thickness 0.127)))
    )
    (fp_text value "C_100n_0402" (at 0 1.17 90) (layer "F.Fab")
        (effects (font (size 1 1) (thickness 0.15)))
    )
    (fp_text user "License: Apache-2.0" (at -0.939 5.799 -90) (layer "F.Fab") hide
        (effects (font (size 0.7 0.7) (thickness 0.15)) (justify left bottom))
    )
    (fp_text user "${REFERENCE}" (at 0 0 90) (layer "F.Fab")
        (effects (font (size 0.25 0.25) (thickness 0.04)))
    )
    (fp_text user "Author: Antmicro" (at -0.939 3.399 -90) (layer "F.Fab") hide
        (effects (font (size 0.7 0.7) (thickness 0.15)) (justify left bottom))
    )
    (fp_rect (start -0.925 -0.47) (end 0.925 0.47)
      (stroke (width 0.05) (type default)) (fill none) (layer "F.CrtYd"))
    (fp_line (start -0.494 -0.25) (end 0.504 -0.25)
      (stroke (width 0.15) (type solid)) (layer "F.Fab"))
    (fp_line (start -0.494 0.248) (end -0.494 -0.25)
      (stroke (width 0.15) (type solid)) (layer "F.Fab"))
    (fp_line (start 0.504 -0.25) (end 0.504 0.248)
      (stroke (width 0.15) (type solid)) (layer "F.Fab"))
    (fp_line (start 0.504 0.248) (end -0.494 0.248)
      (stroke (width 0.15) (type solid)) (layer "F.Fab"))
    (pad "1" smd roundrect (at -0.48 0 270) (size 0.59 0.64) (layers "F.Cu" "F.Paste" "F.Mask") (roundrect_rratio 0.25)
      (net 1 "GND") (pintype "passive"))
    (pad "2" smd roundrect (at 0.48 0 270) (size 0.59 0.64) (layers "F.Cu" "F.Paste" "F.Mask") (roundrect_rratio 0.25)
      (net 220 "Net-(U7-EN)") (pintype "passive"))
  )

  (footprint "antmicro-footprints:R_0402_1005Metric" (layer "F.Cu")
    (at 86.25 141.05 -90)
    (descr "Resistor SMD 0402")
    (tags "resistor SMD 0402")
    (property "Author" "Antmicro")
    (property "License" "Apache-2.0")
    (property "MPN" "CR0402-FX-2003GLF")
    (property "Manufacturer" "Bourns")
    (property "Public" "False")
    (property "Sheetfile" "interfaces.kicad_sch")
    (property "Sheetname" "Interfaces")
    (property "Tolerance" "1%")
    (property "Val" "200k")
    (property "ki_description" "SMD Chip Resistor, 200 kohm, ± 1%, 62.5 mW, 0402 [1005 Metric], Thick Film, General Purpose")
    (property "ki_keywords" "0402, SMT, RESISTOR, PASSIVE")
    (attr smd)
    (fp_text reference "R57" (at -2.55 0.04 -90) (layer "F.SilkS")
        (effects (font (size 0.7 0.7) (thickness 0.127)))
    )
    (fp_text value "R_200k_0402" (at 0 1.17 -90) (layer "F.Fab")
        (effects (font (size 1 1) (thickness 0.15)))
    )
    (fp_text user "${REFERENCE}" (at 0 0 -90) (layer "F.Fab")
        (effects (font (size 0.25 0.25) (thickness 0.04)))
    )
    (fp_text user "License: Apache-2.0" (at -0.95 5.169 -90) (layer "F.Fab") hide
        (effects (font (size 0.7 0.7) (thickness 0.15)) (justify left bottom))
    )
    (fp_text user "Author: Antmicro" (at -0.95 4.169 -90) (layer "F.Fab") hide
        (effects (font (size 0.7 0.7) (thickness 0.15)) (justify left bottom))
    )
    (fp_rect (start -0.925 -0.47) (end 0.925 0.47)
      (stroke (width 0.05) (type default)) (fill none) (layer "F.CrtYd"))
    (fp_rect (start -0.5 -0.25) (end 0.5 0.25)
      (stroke (width 0.15) (type solid)) (fill none) (layer "F.Fab"))
    (pad "1" smd roundrect (at -0.48 0 270) (size 0.59 0.64) (layers "F.Cu" "F.Paste" "F.Mask") (roundrect_rratio 0.25)
      (net 385 "1V0_PG") (pintype "passive"))
    (pad "2" smd roundrect (at 0.48 0 270) (size 0.59 0.64) (layers "F.Cu" "F.Paste" "F.Mask") (roundrect_rratio 0.25)
      (net 220 "Net-(U7-EN)") (pintype "passive"))
  )

  (footprint "antmicro-footprints:C_0402_1005Metric" (layer "F.Cu")
    (at 71.42 122.04 -90)
    (descr "Capacitor SMD 0402")
    (tags "capacitor SMD 0402")
    (property "Author" "Antmicro")
    (property "Dielectric" "C0G")
    (property "License" "Apache-2.0")
    (property "MPN" "GRM1555C1H102JA01D")
    (property "Manufacturer" "Murata")
    (property "Public" "False")
    (property "Sheetfile" "ddr3.kicad_sch")
    (property "Sheetname" "DDR3")
    (property "Val" "1n")
    (property "Voltage" "50V")
    (property "ki_description" "SMD Multilayer Ceramic Capacitor, 1000 pF, 50 V, 0402 [1005 Metric], ± 5%, C0G / NP0, GRM Series")
    (property "ki_keywords" "0402, SMT, CAPACITOR, PASSIVE, CERAMIC, MLCC")
    (attr smd)
    (fp_text reference "C196" (at -0.055 1.99 90) (layer "F.SilkS")
        (effects (font (size 0.7 0.7) (thickness 0.127)))
    )
    (fp_text value "C_1n_0402" (at 0 1.17 90) (layer "F.Fab")
        (effects (font (size 1 1) (thickness 0.15)))
    )
    (fp_text user "${REFERENCE}" (at 0 0 90) (layer "F.Fab")
        (effects (font (size 0.25 0.25) (thickness 0.04)))
    )
    (fp_text user "License: Apache-2.0" (at -0.939 5.799 -90) (layer "F.Fab") hide
        (effects (font (size 0.7 0.7) (thickness 0.15)) (justify left bottom))
    )
    (fp_text user "Author: Antmicro" (at -0.939 3.399 -90) (layer "F.Fab") hide
        (effects (font (size 0.7 0.7) (thickness 0.15)) (justify left bottom))
    )
    (fp_rect (start -0.925 -0.47) (end 0.925 0.47)
      (stroke (width 0.05) (type default)) (fill none) (layer "F.CrtYd"))
    (fp_line (start -0.494 -0.25) (end 0.504 -0.25)
      (stroke (width 0.15) (type solid)) (layer "F.Fab"))
    (fp_line (start -0.494 0.248) (end -0.494 -0.25)
      (stroke (width 0.15) (type solid)) (layer "F.Fab"))
    (fp_line (start 0.504 -0.25) (end 0.504 0.248)
      (stroke (width 0.15) (type solid)) (layer "F.Fab"))
    (fp_line (start 0.504 0.248) (end -0.494 0.248)
      (stroke (width 0.15) (type solid)) (layer "F.Fab"))
    (pad "1" smd roundrect (at -0.48 0 270) (size 0.59 0.64) (layers "F.Cu" "F.Paste" "F.Mask") (roundrect_rratio 0.25)
      (net 1 "GND") (pintype "passive"))
    (pad "2" smd roundrect (at 0.48 0 270) (size 0.59 0.64) (layers "F.Cu" "F.Paste" "F.Mask") (roundrect_rratio 0.25)
      (net 305 "Net-(U11-REFIN)") (pintype "passive"))
  )

  (footprint "antmicro-footprints:LED_0603_1608Metric_G" (layer "F.Cu")
    (at 139.161 61.478 90)
    (descr "LED SMD 0603 Green")
    (tags "LED SMD 0603 Green")
    (property "Author" "Antmicro")
    (property "Color" "Green")
    (property "License" "Apache-2.0")
    (property "MPN" "LG L29K-G2J1-24-Z")
    (property "Manufacturer" "OSRAM")
    (property "Sheetfile" "interfaces.kicad_sch")
    (property "Sheetname" "Interfaces")
    (property "ki_description" "LED, Green, SMD, 0603, 20 mA, 1.7 V, 570 nm")
    (property "ki_keywords" "SMT, DIODE, SEMICONDUCTOR, LED")
    (attr smd)
    (fp_text reference "D3" (at 1.858 0.009) (layer "F.SilkS")
        (effects (font (size 0.7 0.7) (thickness 0.127)))
    )
    (fp_text value "LED_G_0603_LG_L29K-G2J1-24-Z" (at 0 1.77 90) (layer "F.Fab")
        (effects (font (size 1 1) (thickness 0.15)))
    )
    (fp_text user "${REFERENCE}" (at -1.4224 5.999 90) (layer "F.Fab") hide
        (effects (font (size 0.7 0.7) (thickness 0.15)) (justify left bottom))
    )
    (fp_text user "License: Apache-2.0" (at -1.4224 3.599 90) (layer "F.Fab") hide
        (effects (font (size 0.7 0.7) (thickness 0.15)) (justify left bottom))
    )
    (fp_text user "Author: Antmicro" (at -1.4224 4.799 90) (layer "F.Fab") hide
        (effects (font (size 0.7 0.7) (thickness 0.15)) (justify left bottom))
    )
    (fp_line (start -1.18 -0.319) (end -1.18 0.321)
      (stroke (width 0.15) (type solid)) (layer "F.SilkS"))
    (fp_line (start -0.094672 0.001008) (end -0.24 0.001008)
      (stroke (width 0.1) (type solid)) (layer "F.SilkS"))
    (fp_line (start -0.094672 0.001008) (end 0.105328 -0.198992)
      (stroke (width 0.1) (type solid)) (layer "F.SilkS"))
    (fp_line (start -0.094672 0.201008) (end -0.094672 -0.198992)
      (stroke (width 0.1) (type solid)) (layer "F.SilkS"))
    (fp_line (start 0.105328 0.001008) (end 0.24 0.001)
      (stroke (width 0.1) (type solid)) (layer "F.SilkS"))
    (fp_line (start 0.105328 0.201008) (end -0.094672 0.001008)
      (stroke (width 0.1) (type solid)) (layer "F.SilkS"))
    (fp_line (start 0.105328 0.201008) (end 0.105328 -0.198992)
      (stroke (width 0.1) (type solid)) (layer "F.SilkS"))
    (fp_line (start 0.22 -0.35) (end -0.22 -0.35)
      (stroke (width 0.15) (type solid)) (layer "F.SilkS"))
    (fp_line (start 0.22 0.35) (end -0.22 0.35)
      (stroke (width 0.15) (type solid)) (layer "F.SilkS"))
    (fp_rect (start 1.25 0.65) (end -1.25 -0.65)
      (stroke (width 0.05) (type solid)) (fill none) (layer "F.CrtYd"))
    (fp_line (start -0.199 -0.202) (end -0.199 0.1)
      (stroke (width 0.15) (type solid)) (layer "F.Fab"))
    (fp_line (start -0.199 0) (end -0.597 0)
      (stroke (width 0.15) (type solid)) (layer "F.Fab"))
    (fp_line (start -0.199 0.2) (end -0.199 0.1)
      (stroke (width 0.15) (type solid)) (layer "F.Fab"))
    (fp_line (start -0.101 0) (end 0.201 0.2)
      (stroke (width 0.15) (type solid)) (layer "F.Fab"))
    (fp_line (start 0.201 -0.202) (end -0.101 0)
      (stroke (width 0.15) (type solid)) (layer "F.Fab"))
    (fp_line (start 0.201 0) (end 0.201 -0.202)
      (stroke (width 0.15) (type solid)) (layer "F.Fab"))
    (fp_line (start 0.201 0.2) (end 0.201 0)
      (stroke (width 0.15) (type solid)) (layer "F.Fab"))
    (fp_line (start 0.599 0) (end 0.201 0)
      (stroke (width 0.15) (type solid)) (layer "F.Fab"))
    (fp_rect (start 0.848 0.4) (end -0.85 -0.402)
      (stroke (width 0.15) (type solid)) (fill none) (layer "F.Fab"))
    (pad "1" smd roundrect (at -0.7 0 270) (size 0.8 1) (layers "F.Cu" "F.Paste" "F.Mask") (roundrect_rratio 0.2)
      (net 309 "Net-(D3-C)") (pinfunction "C") (pintype "passive"))
    (pad "2" smd roundrect (at 0.7 0 270) (size 0.8 1) (layers "F.Cu" "F.Paste" "F.Mask") (roundrect_rratio 0.2)
      (net 310 "Net-(D3-A)") (pinfunction "A") (pintype "passive"))
  )

  (footprint "antmicro-footprints:LED_0603_1608Metric_G" (layer "F.Cu")
    (at 141.161 61.478 90)
    (descr "LED SMD 0603 Green")
    (tags "LED SMD 0603 Green")
    (property "Author" "Antmicro")
    (property "Color" "Green")
    (property "License" "Apache-2.0")
    (property "MPN" "LG L29K-G2J1-24-Z")
    (property "Manufacturer" "OSRAM")
    (property "Sheetfile" "interfaces.kicad_sch")
    (property "Sheetname" "Interfaces")
    (property "ki_description" "LED, Green, SMD, 0603, 20 mA, 1.7 V, 570 nm")
    (property "ki_keywords" "SMT, DIODE, SEMICONDUCTOR, LED")
    (attr smd)
    (fp_text reference "D4" (at 1.868 0.049) (layer "F.SilkS")
        (effects (font (size 0.7 0.7) (thickness 0.127)))
    )
    (fp_text value "LED_G_0603_LG_L29K-G2J1-24-Z" (at 0 1.77 90) (layer "F.Fab")
        (effects (font (size 1 1) (thickness 0.15)))
    )
    (fp_text user "License: Apache-2.0" (at -1.4224 3.599 90) (layer "F.Fab") hide
        (effects (font (size 0.7 0.7) (thickness 0.15)) (justify left bottom))
    )
    (fp_text user "Author: Antmicro" (at -1.4224 4.799 90) (layer "F.Fab") hide
        (effects (font (size 0.7 0.7) (thickness 0.15)) (justify left bottom))
    )
    (fp_text user "${REFERENCE}" (at -1.4224 5.999 90) (layer "F.Fab") hide
        (effects (font (size 0.7 0.7) (thickness 0.15)) (justify left bottom))
    )
    (fp_line (start -1.18 -0.319) (end -1.18 0.321)
      (stroke (width 0.15) (type solid)) (layer "F.SilkS"))
    (fp_line (start -0.094672 0.001008) (end -0.24 0.001008)
      (stroke (width 0.1) (type solid)) (layer "F.SilkS"))
    (fp_line (start -0.094672 0.001008) (end 0.105328 -0.198992)
      (stroke (width 0.1) (type solid)) (layer "F.SilkS"))
    (fp_line (start -0.094672 0.201008) (end -0.094672 -0.198992)
      (stroke (width 0.1) (type solid)) (layer "F.SilkS"))
    (fp_line (start 0.105328 0.001008) (end 0.24 0.001)
      (stroke (width 0.1) (type solid)) (layer "F.SilkS"))
    (fp_line (start 0.105328 0.201008) (end -0.094672 0.001008)
      (stroke (width 0.1) (type solid)) (layer "F.SilkS"))
    (fp_line (start 0.105328 0.201008) (end 0.105328 -0.198992)
      (stroke (width 0.1) (type solid)) (layer "F.SilkS"))
    (fp_line (start 0.22 -0.35) (end -0.22 -0.35)
      (stroke (width 0.15) (type solid)) (layer "F.SilkS"))
    (fp_line (start 0.22 0.35) (end -0.22 0.35)
      (stroke (width 0.15) (type solid)) (layer "F.SilkS"))
    (fp_rect (start 1.25 0.65) (end -1.25 -0.65)
      (stroke (width 0.05) (type solid)) (fill none) (layer "F.CrtYd"))
    (fp_line (start -0.199 -0.202) (end -0.199 0.1)
      (stroke (width 0.15) (type solid)) (layer "F.Fab"))
    (fp_line (start -0.199 0) (end -0.597 0)
      (stroke (width 0.15) (type solid)) (layer "F.Fab"))
    (fp_line (start -0.199 0.2) (end -0.199 0.1)
      (stroke (width 0.15) (type solid)) (layer "F.Fab"))
    (fp_line (start -0.101 0) (end 0.201 0.2)
      (stroke (width 0.15) (type solid)) (layer "F.Fab"))
    (fp_line (start 0.201 -0.202) (end -0.101 0)
      (stroke (width 0.15) (type solid)) (layer "F.Fab"))
    (fp_line (start 0.201 0) (end 0.201 -0.202)
      (stroke (width 0.15) (type solid)) (layer "F.Fab"))
    (fp_line (start 0.201 0.2) (end 0.201 0)
      (stroke (width 0.15) (type solid)) (layer "F.Fab"))
    (fp_line (start 0.599 0) (end 0.201 0)
      (stroke (width 0.15) (type solid)) (layer "F.Fab"))
    (fp_rect (start 0.848 0.4) (end -0.85 -0.402)
      (stroke (width 0.15) (type solid)) (fill none) (layer "F.Fab"))
    (pad "1" smd roundrect (at -0.7 0 270) (size 0.8 1) (layers "F.Cu" "F.Paste" "F.Mask") (roundrect_rratio 0.2)
      (net 311 "Net-(D4-C)") (pinfunction "C") (pintype "passive"))
    (pad "2" smd roundrect (at 0.7 0 270) (size 0.8 1) (layers "F.Cu" "F.Paste" "F.Mask") (roundrect_rratio 0.2)
      (net 312 "Net-(D4-A)") (pinfunction "A") (pintype "passive"))
  )

  (footprint "antmicro-footprints:LED_0603_1608Metric_G" (layer "F.Cu")
    (at 143.211 61.478 90)
    (descr "LED SMD 0603 Green")
    (tags "LED SMD 0603 Green")
    (property "Author" "Antmicro")
    (property "Color" "Green")
    (property "License" "Apache-2.0")
    (property "MPN" "LG L29K-G2J1-24-Z")
    (property "Manufacturer" "OSRAM")
    (property "Sheetfile" "interfaces.kicad_sch")
    (property "Sheetname" "Interfaces")
    (property "ki_description" "LED, Green, SMD, 0603, 20 mA, 1.7 V, 570 nm")
    (property "ki_keywords" "SMT, DIODE, SEMICONDUCTOR, LED")
    (attr smd)
    (fp_text reference "D5" (at 1.878 0.039) (layer "F.SilkS")
        (effects (font (size 0.7 0.7) (thickness 0.127)))
    )
    (fp_text value "LED_G_0603_LG_L29K-G2J1-24-Z" (at 0 1.77 90) (layer "F.Fab")
        (effects (font (size 1 1) (thickness 0.15)))
    )
    (fp_text user "Author: Antmicro" (at -1.4224 4.799 90) (layer "F.Fab") hide
        (effects (font (size 0.7 0.7) (thickness 0.15)) (justify left bottom))
    )
    (fp_text user "License: Apache-2.0" (at -1.4224 3.599 90) (layer "F.Fab") hide
        (effects (font (size 0.7 0.7) (thickness 0.15)) (justify left bottom))
    )
    (fp_text user "${REFERENCE}" (at -1.4224 5.999 90) (layer "F.Fab") hide
        (effects (font (size 0.7 0.7) (thickness 0.15)) (justify left bottom))
    )
    (fp_line (start -1.18 -0.319) (end -1.18 0.321)
      (stroke (width 0.15) (type solid)) (layer "F.SilkS"))
    (fp_line (start -0.094672 0.001008) (end -0.24 0.001008)
      (stroke (width 0.1) (type solid)) (layer "F.SilkS"))
    (fp_line (start -0.094672 0.001008) (end 0.105328 -0.198992)
      (stroke (width 0.1) (type solid)) (layer "F.SilkS"))
    (fp_line (start -0.094672 0.201008) (end -0.094672 -0.198992)
      (stroke (width 0.1) (type solid)) (layer "F.SilkS"))
    (fp_line (start 0.105328 0.001008) (end 0.24 0.001)
      (stroke (width 0.1) (type solid)) (layer "F.SilkS"))
    (fp_line (start 0.105328 0.201008) (end -0.094672 0.001008)
      (stroke (width 0.1) (type solid)) (layer "F.SilkS"))
    (fp_line (start 0.105328 0.201008) (end 0.105328 -0.198992)
      (stroke (width 0.1) (type solid)) (layer "F.SilkS"))
    (fp_line (start 0.22 -0.35) (end -0.22 -0.35)
      (stroke (width 0.15) (type solid)) (layer "F.SilkS"))
    (fp_line (start 0.22 0.35) (end -0.22 0.35)
      (stroke (width 0.15) (type solid)) (layer "F.SilkS"))
    (fp_rect (start 1.25 0.65) (end -1.25 -0.65)
      (stroke (width 0.05) (type solid)) (fill none) (layer "F.CrtYd"))
    (fp_line (start -0.199 -0.202) (end -0.199 0.1)
      (stroke (width 0.15) (type solid)) (layer "F.Fab"))
    (fp_line (start -0.199 0) (end -0.597 0)
      (stroke (width 0.15) (type solid)) (layer "F.Fab"))
    (fp_line (start -0.199 0.2) (end -0.199 0.1)
      (stroke (width 0.15) (type solid)) (layer "F.Fab"))
    (fp_line (start -0.101 0) (end 0.201 0.2)
      (stroke (width 0.15) (type solid)) (layer "F.Fab"))
    (fp_line (start 0.201 -0.202) (end -0.101 0)
      (stroke (width 0.15) (type solid)) (layer "F.Fab"))
    (fp_line (start 0.201 0) (end 0.201 -0.202)
      (stroke (width 0.15) (type solid)) (layer "F.Fab"))
    (fp_line (start 0.201 0.2) (end 0.201 0)
      (stroke (width 0.15) (type solid)) (layer "F.Fab"))
    (fp_line (start 0.599 0) (end 0.201 0)
      (stroke (width 0.15) (type solid)) (layer "F.Fab"))
    (fp_rect (start 0.848 0.4) (end -0.85 -0.402)
      (stroke (width 0.15) (type solid)) (fill none) (layer "F.Fab"))
    (pad "1" smd roundrect (at -0.7 0 270) (size 0.8 1) (layers "F.Cu" "F.Paste" "F.Mask") (roundrect_rratio 0.2)
      (net 313 "Net-(D5-C)") (pinfunction "C") (pintype "passive"))
    (pad "2" smd roundrect (at 0.7 0 270) (size 0.8 1) (layers "F.Cu" "F.Paste" "F.Mask") (roundrect_rratio 0.2)
      (net 314 "Net-(D5-A)") (pinfunction "A") (pintype "passive"))
  )

  (footprint "antmicro-footprints:SOT-23-3" (layer "F.Cu")
    (at 120.275 68.45)
    (property "Author" "Antmicro")
    (property "License" "Apache-2.0")
    (property "MPN" "2N7002")
    (property "Manufacturer" "ON Semiconductor")
    (property "Sheetfile" "interfaces.kicad_sch")
    (property "Sheetname" "Interfaces")
    (property "ki_description" "Power MOSFET, N Channel, 60 V, 115 mA, 1.2 ohm, SOT-23, Surface Mount")
    (property "ki_keywords" "SMT, TRANSISTOR, SEMICONDUCTOR, NMOS")
    (attr smd)
    (fp_text reference "Q1" (at -2.35 1.225 90) (layer "F.SilkS")
        (effects (font (size 0.7 0.7) (thickness 0.127)))
    )
    (fp_text value "2N7002_SOT-23-3" (at 0.025 3.25) (layer "F.Fab")
        (effects (font (size 1 1) (thickness 0.15)))
    )
    (fp_text user "License: Apache-2.0" (at -1.8 6.8) (layer "F.Fab") hide
        (effects (font (size 0.7 0.7) (thickness 0.15)) (justify left bottom))
    )
    (fp_text user "Author: Antmicro" (at -1.837 5.3) (layer "F.Fab") hide
        (effects (font (size 0.7 0.7) (thickness 0.15)) (justify left bottom))
    )
    (fp_text user "${REFERENCE}" (at -0.125 0.15) (layer "F.Fab")
        (effects (font (size 0.25 0.25) (thickness 0.05)))
    )
    (fp_line (start -1.45 -1.35) (end -0.85 -1.35)
      (stroke (width 0.15) (type solid)) (layer "F.SilkS"))
    (fp_line (start -0.85 -1.35) (end -0.7 -1.5)
      (stroke (width 0.15) (type solid)) (layer "F.SilkS"))
    (fp_line (start -0.7 1.5) (end -0.7 1.35)
      (stroke (width 0.15) (type solid)) (layer "F.SilkS"))
    (fp_line (start 0.7 -1.5) (end -0.7 -1.5)
      (stroke (width 0.15) (type solid)) (layer "F.SilkS"))
    (fp_line (start 0.7 -0.4) (end 0.7 -1.5)
      (stroke (width 0.15) (type solid)) (layer "F.SilkS"))
    (fp_line (start 0.7 0.4) (end 0.7 1.5)
      (stroke (width 0.15) (type solid)) (layer "F.SilkS"))
    (fp_line (start 0.7 1.5) (end -0.7 1.5)
      (stroke (width 0.15) (type solid)) (layer "F.SilkS"))
    (fp_line (start -1.75 -0.5) (end -1.75 -1.4)
      (stroke (width 0.05) (type solid)) (layer "F.CrtYd"))
    (fp_line (start -1.75 0.5) (end -0.85 0.5)
      (stroke (width 0.05) (type solid)) (layer "F.CrtYd"))
    (fp_line (start -1.75 1.4) (end -1.75 0.5)
      (stroke (width 0.05) (type solid)) (layer "F.CrtYd"))
    (fp_line (start -0.9 -1.6) (end -0.9 -1.4)
      (stroke (width 0.05) (type solid)) (layer "F.CrtYd"))
    (fp_line (start -0.9 -1.6) (end 0.825 -1.6)
      (stroke (width 0.05) (type solid)) (layer "F.CrtYd"))
    (fp_line (start -0.9 -1.4) (end -1.75 -1.4)
      (stroke (width 0.05) (type solid)) (layer "F.CrtYd"))
    (fp_line (start -0.85 -0.5) (end -1.75 -0.5)
      (stroke (width 0.05) (type solid)) (layer "F.CrtYd"))
    (fp_line (start -0.85 0.5) (end -0.85 -0.5)
      (stroke (width 0.05) (type solid)) (layer "F.CrtYd"))
    (fp_line (start -0.85 1.4) (end -1.75 1.4)
      (stroke (width 0.05) (type solid)) (layer "F.CrtYd"))
    (fp_line (start -0.85 1.65) (end -0.85 1.4)
      (stroke (width 0.05) (type solid)) (layer "F.CrtYd"))
    (fp_line (start 0.825 -1.6) (end 0.825 -0.45)
      (stroke (width 0.05) (type solid)) (layer "F.CrtYd"))
    (fp_line (start 0.825 -0.45) (end 1.75 -0.45)
      (stroke (width 0.05) (type solid)) (layer "F.CrtYd"))
    (fp_line (start 0.85 0.45) (end 0.85 1.65)
      (stroke (width 0.05) (type solid)) (layer "F.CrtYd"))
    (fp_line (start 0.85 1.65) (end -0.85 1.65)
      (stroke (width 0.05) (type solid)) (layer "F.CrtYd"))
    (fp_line (start 1.75 -0.45) (end 1.75 0.45)
      (stroke (width 0.05) (type solid)) (layer "F.CrtYd"))
    (fp_line (start 1.75 0.45) (end 0.85 0.45)
      (stroke (width 0.05) (type solid)) (layer "F.CrtYd"))
    (fp_line (start -0.712 -1.325) (end -0.712 1.523)
      (stroke (width 0.15) (type solid)) (layer "F.Fab"))
    (fp_line (start -0.712 1.519) (end 0.688 1.519)
      (stroke (width 0.15) (type solid)) (layer "F.Fab"))
    (fp_line (start -0.437 -1.526) (end -0.712 -1.325)
      (stroke (width 0.15) (type solid)) (layer "F.Fab"))
    (fp_line (start -0.437 -1.526) (end 0.688 -1.526)
      (stroke (width 0.15) (type solid)) (layer "F.Fab"))
    (fp_line (start 0.688 1.519) (end 0.688 -1.52)
      (stroke (width 0.15) (type solid)) (layer "F.Fab"))
    (pad "1" smd roundrect (at -1.1 -0.951) (size 1 0.6) (layers "F.Cu" "F.Paste" "F.Mask") (roundrect_rratio 0.15)
      (net 293 "USR_LED0") (pinfunction "G") (pintype "passive"))
    (pad "2" smd roundrect (at -1.1 0.949) (size 1 0.6) (layers "F.Cu" "F.Paste" "F.Mask") (roundrect_rratio 0.15)
      (net 1 "GND") (pinfunction "S") (pintype "passive"))
    (pad "3" smd roundrect (at 1.1 -0.0005) (size 1 0.6) (layers "F.Cu" "F.Paste" "F.Mask") (roundrect_rratio 0.15)
      (net 309 "Net-(D3-C)") (pinfunction "D") (pintype "passive"))
  )

  (footprint "antmicro-footprints:SOT-23-3" (layer "F.Cu")
    (at 120.275 72.475)
    (property "Author" "Antmicro")
    (property "License" "Apache-2.0")
    (property "MPN" "2N7002")
    (property "Manufacturer" "ON Semiconductor")
    (property "Sheetfile" "interfaces.kicad_sch")
    (property "Sheetname" "Interfaces")
    (property "ki_description" "Power MOSFET, N Channel, 60 V, 115 mA, 1.2 ohm, SOT-23, Surface Mount")
    (property "ki_keywords" "SMT, TRANSISTOR, SEMICONDUCTOR, NMOS")
    (attr smd)
    (fp_text reference "Q2" (at -2.35 1.075 90) (layer "F.SilkS")
        (effects (font (size 0.7 0.7) (thickness 0.127)))
    )
    (fp_text value "2N7002_SOT-23-3" (at 0.025 3.25) (layer "F.Fab")
        (effects (font (size 1 1) (thickness 0.15)))
    )
    (fp_text user "License: Apache-2.0" (at -1.8 6.8) (layer "F.Fab") hide
        (effects (font (size 0.7 0.7) (thickness 0.15)) (justify left bottom))
    )
    (fp_text user "Author: Antmicro" (at -1.837 5.3) (layer "F.Fab") hide
        (effects (font (size 0.7 0.7) (thickness 0.15)) (justify left bottom))
    )
    (fp_text user "${REFERENCE}" (at -0.125 0.15) (layer "F.Fab")
        (effects (font (size 0.25 0.25) (thickness 0.05)))
    )
    (fp_line (start -1.45 -1.35) (end -0.85 -1.35)
      (stroke (width 0.15) (type solid)) (layer "F.SilkS"))
    (fp_line (start -0.85 -1.35) (end -0.7 -1.5)
      (stroke (width 0.15) (type solid)) (layer "F.SilkS"))
    (fp_line (start -0.7 1.5) (end -0.7 1.35)
      (stroke (width 0.15) (type solid)) (layer "F.SilkS"))
    (fp_line (start 0.7 -1.5) (end -0.7 -1.5)
      (stroke (width 0.15) (type solid)) (layer "F.SilkS"))
    (fp_line (start 0.7 -0.4) (end 0.7 -1.5)
      (stroke (width 0.15) (type solid)) (layer "F.SilkS"))
    (fp_line (start 0.7 0.4) (end 0.7 1.5)
      (stroke (width 0.15) (type solid)) (layer "F.SilkS"))
    (fp_line (start 0.7 1.5) (end -0.7 1.5)
      (stroke (width 0.15) (type solid)) (layer "F.SilkS"))
    (fp_line (start -1.75 -0.5) (end -1.75 -1.4)
      (stroke (width 0.05) (type solid)) (layer "F.CrtYd"))
    (fp_line (start -1.75 0.5) (end -0.85 0.5)
      (stroke (width 0.05) (type solid)) (layer "F.CrtYd"))
    (fp_line (start -1.75 1.4) (end -1.75 0.5)
      (stroke (width 0.05) (type solid)) (layer "F.CrtYd"))
    (fp_line (start -0.9 -1.6) (end -0.9 -1.4)
      (stroke (width 0.05) (type solid)) (layer "F.CrtYd"))
    (fp_line (start -0.9 -1.6) (end 0.825 -1.6)
      (stroke (width 0.05) (type solid)) (layer "F.CrtYd"))
    (fp_line (start -0.9 -1.4) (end -1.75 -1.4)
      (stroke (width 0.05) (type solid)) (layer "F.CrtYd"))
    (fp_line (start -0.85 -0.5) (end -1.75 -0.5)
      (stroke (width 0.05) (type solid)) (layer "F.CrtYd"))
    (fp_line (start -0.85 0.5) (end -0.85 -0.5)
      (stroke (width 0.05) (type solid)) (layer "F.CrtYd"))
    (fp_line (start -0.85 1.4) (end -1.75 1.4)
      (stroke (width 0.05) (type solid)) (layer "F.CrtYd"))
    (fp_line (start -0.85 1.65) (end -0.85 1.4)
      (stroke (width 0.05) (type solid)) (layer "F.CrtYd"))
    (fp_line (start 0.825 -1.6) (end 0.825 -0.45)
      (stroke (width 0.05) (type solid)) (layer "F.CrtYd"))
    (fp_line (start 0.825 -0.45) (end 1.75 -0.45)
      (stroke (width 0.05) (type solid)) (layer "F.CrtYd"))
    (fp_line (start 0.85 0.45) (end 0.85 1.65)
      (stroke (width 0.05) (type solid)) (layer "F.CrtYd"))
    (fp_line (start 0.85 1.65) (end -0.85 1.65)
      (stroke (width 0.05) (type solid)) (layer "F.CrtYd"))
    (fp_line (start 1.75 -0.45) (end 1.75 0.45)
      (stroke (width 0.05) (type solid)) (layer "F.CrtYd"))
    (fp_line (start 1.75 0.45) (end 0.85 0.45)
      (stroke (width 0.05) (type solid)) (layer "F.CrtYd"))
    (fp_line (start -0.712 -1.325) (end -0.712 1.523)
      (stroke (width 0.15) (type solid)) (layer "F.Fab"))
    (fp_line (start -0.712 1.519) (end 0.688 1.519)
      (stroke (width 0.15) (type solid)) (layer "F.Fab"))
    (fp_line (start -0.437 -1.526) (end -0.712 -1.325)
      (stroke (width 0.15) (type solid)) (layer "F.Fab"))
    (fp_line (start -0.437 -1.526) (end 0.688 -1.526)
      (stroke (width 0.15) (type solid)) (layer "F.Fab"))
    (fp_line (start 0.688 1.519) (end 0.688 -1.52)
      (stroke (width 0.15) (type solid)) (layer "F.Fab"))
    (pad "1" smd roundrect (at -1.1 -0.951) (size 1 0.6) (layers "F.Cu" "F.Paste" "F.Mask") (roundrect_rratio 0.15)
      (net 294 "USR_LED1") (pinfunction "G") (pintype "passive"))
    (pad "2" smd roundrect (at -1.1 0.949) (size 1 0.6) (layers "F.Cu" "F.Paste" "F.Mask") (roundrect_rratio 0.15)
      (net 1 "GND") (pinfunction "S") (pintype "passive"))
    (pad "3" smd roundrect (at 1.1 -0.0005) (size 1 0.6) (layers "F.Cu" "F.Paste" "F.Mask") (roundrect_rratio 0.15)
      (net 311 "Net-(D4-C)") (pinfunction "D") (pintype "passive"))
  )

  (footprint "antmicro-footprints:SOT-23-3" (layer "F.Cu")
    (at 124.2 72.45)
    (property "Author" "Antmicro")
    (property "License" "Apache-2.0")
    (property "MPN" "2N7002")
    (property "Manufacturer" "ON Semiconductor")
    (property "Sheetfile" "interfaces.kicad_sch")
    (property "Sheetname" "Interfaces")
    (property "ki_description" "Power MOSFET, N Channel, 60 V, 115 mA, 1.2 ohm, SOT-23, Surface Mount")
    (property "ki_keywords" "SMT, TRANSISTOR, SEMICONDUCTOR, NMOS")
    (attr smd)
    (fp_text reference "Q3" (at 2.525 1.2 90) (layer "F.SilkS")
        (effects (font (size 0.7 0.7) (thickness 0.127)))
    )
    (fp_text value "2N7002_SOT-23-3" (at 0.025 3.25) (layer "F.Fab")
        (effects (font (size 1 1) (thickness 0.15)))
    )
    (fp_text user "License: Apache-2.0" (at -1.8 6.8) (layer "F.Fab") hide
        (effects (font (size 0.7 0.7) (thickness 0.15)) (justify left bottom))
    )
    (fp_text user "Author: Antmicro" (at -1.837 5.3) (layer "F.Fab") hide
        (effects (font (size 0.7 0.7) (thickness 0.15)) (justify left bottom))
    )
    (fp_text user "${REFERENCE}" (at -0.125 0.15) (layer "F.Fab")
        (effects (font (size 0.25 0.25) (thickness 0.05)))
    )
    (fp_line (start -1.45 -1.35) (end -0.85 -1.35)
      (stroke (width 0.15) (type solid)) (layer "F.SilkS"))
    (fp_line (start -0.85 -1.35) (end -0.7 -1.5)
      (stroke (width 0.15) (type solid)) (layer "F.SilkS"))
    (fp_line (start -0.7 1.5) (end -0.7 1.35)
      (stroke (width 0.15) (type solid)) (layer "F.SilkS"))
    (fp_line (start 0.7 -1.5) (end -0.7 -1.5)
      (stroke (width 0.15) (type solid)) (layer "F.SilkS"))
    (fp_line (start 0.7 -0.4) (end 0.7 -1.5)
      (stroke (width 0.15) (type solid)) (layer "F.SilkS"))
    (fp_line (start 0.7 0.4) (end 0.7 1.5)
      (stroke (width 0.15) (type solid)) (layer "F.SilkS"))
    (fp_line (start 0.7 1.5) (end -0.7 1.5)
      (stroke (width 0.15) (type solid)) (layer "F.SilkS"))
    (fp_line (start -1.75 -0.5) (end -1.75 -1.4)
      (stroke (width 0.05) (type solid)) (layer "F.CrtYd"))
    (fp_line (start -1.75 0.5) (end -0.85 0.5)
      (stroke (width 0.05) (type solid)) (layer "F.CrtYd"))
    (fp_line (start -1.75 1.4) (end -1.75 0.5)
      (stroke (width 0.05) (type solid)) (layer "F.CrtYd"))
    (fp_line (start -0.9 -1.6) (end -0.9 -1.4)
      (stroke (width 0.05) (type solid)) (layer "F.CrtYd"))
    (fp_line (start -0.9 -1.6) (end 0.825 -1.6)
      (stroke (width 0.05) (type solid)) (layer "F.CrtYd"))
    (fp_line (start -0.9 -1.4) (end -1.75 -1.4)
      (stroke (width 0.05) (type solid)) (layer "F.CrtYd"))
    (fp_line (start -0.85 -0.5) (end -1.75 -0.5)
      (stroke (width 0.05) (type solid)) (layer "F.CrtYd"))
    (fp_line (start -0.85 0.5) (end -0.85 -0.5)
      (stroke (width 0.05) (type solid)) (layer "F.CrtYd"))
    (fp_line (start -0.85 1.4) (end -1.75 1.4)
      (stroke (width 0.05) (type solid)) (layer "F.CrtYd"))
    (fp_line (start -0.85 1.65) (end -0.85 1.4)
      (stroke (width 0.05) (type solid)) (layer "F.CrtYd"))
    (fp_line (start 0.825 -1.6) (end 0.825 -0.45)
      (stroke (width 0.05) (type solid)) (layer "F.CrtYd"))
    (fp_line (start 0.825 -0.45) (end 1.75 -0.45)
      (stroke (width 0.05) (type solid)) (layer "F.CrtYd"))
    (fp_line (start 0.85 0.45) (end 0.85 1.65)
      (stroke (width 0.05) (type solid)) (layer "F.CrtYd"))
    (fp_line (start 0.85 1.65) (end -0.85 1.65)
      (stroke (width 0.05) (type solid)) (layer "F.CrtYd"))
    (fp_line (start 1.75 -0.45) (end 1.75 0.45)
      (stroke (width 0.05) (type solid)) (layer "F.CrtYd"))
    (fp_line (start 1.75 0.45) (end 0.85 0.45)
      (stroke (width 0.05) (type solid)) (layer "F.CrtYd"))
    (fp_line (start -0.712 -1.325) (end -0.712 1.523)
      (stroke (width 0.15) (type solid)) (layer "F.Fab"))
    (fp_line (start -0.712 1.519) (end 0.688 1.519)
      (stroke (width 0.15) (type solid)) (layer "F.Fab"))
    (fp_line (start -0.437 -1.526) (end -0.712 -1.325)
      (stroke (width 0.15) (type solid)) (layer "F.Fab"))
    (fp_line (start -0.437 -1.526) (end 0.688 -1.526)
      (stroke (width 0.15) (type solid)) (layer "F.Fab"))
    (fp_line (start 0.688 1.519) (end 0.688 -1.52)
      (stroke (width 0.15) (type solid)) (layer "F.Fab"))
    (pad "1" smd roundrect (at -1.1 -0.951) (size 1 0.6) (layers "F.Cu" "F.Paste" "F.Mask") (roundrect_rratio 0.15)
      (net 295 "USR_LED2") (pinfunction "G") (pintype "passive"))
    (pad "2" smd roundrect (at -1.1 0.949) (size 1 0.6) (layers "F.Cu" "F.Paste" "F.Mask") (roundrect_rratio 0.15)
      (net 1 "GND") (pinfunction "S") (pintype "passive"))
    (pad "3" smd roundrect (at 1.1 -0.0005) (size 1 0.6) (layers "F.Cu" "F.Paste" "F.Mask") (roundrect_rratio 0.15)
      (net 313 "Net-(D5-C)") (pinfunction "D") (pintype "passive"))
  )

  (footprint "antmicro-footprints:R_0402_1005Metric" (layer "F.Cu")
    (at 138.1 64.25 -90)
    (descr "Resistor SMD 0402")
    (tags "resistor SMD 0402")
    (property "Author" "Antmicro")
    (property "License" "Apache-2.0")
    (property "MPN" "CR0402-FX-1101GLF")
    (property "Manufacturer" "Bourns")
    (property "Public" "False")
    (property "Sheetfile" "interfaces.kicad_sch")
    (property "Sheetname" "Interfaces")
    (property "Tolerance" "1%")
    (property "Val" "1k1")
    (property "ki_description" "SMD Chip Resistor")
    (property "ki_keywords" "0402, SMT, RESISTOR, PASSIVE")
    (attr smd)
    (fp_text reference "R69" (at 0 1.05 90) (layer "F.SilkS")
        (effects (font (size 0.7 0.7) (thickness 0.127)))
    )
    (fp_text value "R_1k1_0402" (at 0 1.17 90) (layer "F.Fab")
        (effects (font (size 1 1) (thickness 0.15)))
    )
    (fp_text user "${REFERENCE}" (at 0 0 90) (layer "F.Fab")
        (effects (font (size 0.25 0.25) (thickness 0.04)))
    )
    (fp_text user "Author: Antmicro" (at -0.95 4.169 -90) (layer "F.Fab") hide
        (effects (font (size 0.7 0.7) (thickness 0.15)) (justify left bottom))
    )
    (fp_text user "License: Apache-2.0" (at -0.95 5.169 -90) (layer "F.Fab") hide
        (effects (font (size 0.7 0.7) (thickness 0.15)) (justify left bottom))
    )
    (fp_rect (start -0.925 -0.47) (end 0.925 0.47)
      (stroke (width 0.05) (type default)) (fill none) (layer "F.CrtYd"))
    (fp_rect (start -0.5 -0.25) (end 0.5 0.25)
      (stroke (width 0.15) (type solid)) (fill none) (layer "F.Fab"))
    (pad "1" smd roundrect (at -0.48 0 270) (size 0.59 0.64) (layers "F.Cu" "F.Paste" "F.Mask") (roundrect_rratio 0.25)
      (net 310 "Net-(D3-A)") (pintype "passive"))
    (pad "2" smd roundrect (at 0.48 0 270) (size 0.59 0.64) (layers "F.Cu" "F.Paste" "F.Mask") (roundrect_rratio 0.25)
      (net 2 "VCC3V3") (pintype "passive"))
  )

  (footprint "antmicro-footprints:R_0402_1005Metric" (layer "F.Cu")
    (at 140.15 64.25 -90)
    (descr "Resistor SMD 0402")
    (tags "resistor SMD 0402")
    (property "Author" "Antmicro")
    (property "License" "Apache-2.0")
    (property "MPN" "CR0402-FX-1101GLF")
    (property "Manufacturer" "Bourns")
    (property "Public" "False")
    (property "Sheetfile" "interfaces.kicad_sch")
    (property "Sheetname" "Interfaces")
    (property "Tolerance" "1%")
    (property "Val" "1k1")
    (property "ki_description" "SMD Chip Resistor")
    (property "ki_keywords" "0402, SMT, RESISTOR, PASSIVE")
    (attr smd)
    (fp_text reference "R70" (at 0 0.9 -90) (layer "F.SilkS")
        (effects (font (size 0.7 0.7) (thickness 0.127)))
    )
    (fp_text value "R_1k1_0402" (at 0 1.17 -90) (layer "F.Fab")
        (effects (font (size 1 1) (thickness 0.15)))
    )
    (fp_text user "License: Apache-2.0" (at -0.95 5.169 -90) (layer "F.Fab") hide
        (effects (font (size 0.7 0.7) (thickness 0.15)) (justify left bottom))
    )
    (fp_text user "${REFERENCE}" (at 0 0 -90) (layer "F.Fab")
        (effects (font (size 0.25 0.25) (thickness 0.04)))
    )
    (fp_text user "Author: Antmicro" (at -0.95 4.169 -90) (layer "F.Fab") hide
        (effects (font (size 0.7 0.7) (thickness 0.15)) (justify left bottom))
    )
    (fp_rect (start -0.925 -0.47) (end 0.925 0.47)
      (stroke (width 0.05) (type default)) (fill none) (layer "F.CrtYd"))
    (fp_rect (start -0.5 -0.25) (end 0.5 0.25)
      (stroke (width 0.15) (type solid)) (fill none) (layer "F.Fab"))
    (pad "1" smd roundrect (at -0.48 0 270) (size 0.59 0.64) (layers "F.Cu" "F.Paste" "F.Mask") (roundrect_rratio 0.25)
      (net 312 "Net-(D4-A)") (pintype "passive"))
    (pad "2" smd roundrect (at 0.48 0 270) (size 0.59 0.64) (layers "F.Cu" "F.Paste" "F.Mask") (roundrect_rratio 0.25)
      (net 2 "VCC3V3") (pintype "passive"))
  )

  (footprint "antmicro-footprints:R_0402_1005Metric" (layer "F.Cu")
    (at 142.2 64.25 -90)
    (descr "Resistor SMD 0402")
    (tags "resistor SMD 0402")
    (property "Author" "Antmicro")
    (property "License" "Apache-2.0")
    (property "MPN" "CR0402-FX-1101GLF")
    (property "Manufacturer" "Bourns")
    (property "Public" "False")
    (property "Sheetfile" "interfaces.kicad_sch")
    (property "Sheetname" "Interfaces")
    (property "Tolerance" "1%")
    (property "Val" "1k1")
    (property "ki_description" "SMD Chip Resistor")
    (property "ki_keywords" "0402, SMT, RESISTOR, PASSIVE")
    (attr smd)
    (fp_text reference "R71" (at 0 0.95 90) (layer "F.SilkS")
        (effects (font (size 0.7 0.7) (thickness 0.127)))
    )
    (fp_text value "R_1k1_0402" (at 0 1.17 90) (layer "F.Fab")
        (effects (font (size 1 1) (thickness 0.15)))
    )
    (fp_text user "License: Apache-2.0" (at -0.95 5.169 -90) (layer "F.Fab") hide
        (effects (font (size 0.7 0.7) (thickness 0.15)) (justify left bottom))
    )
    (fp_text user "${REFERENCE}" (at 0 0 90) (layer "F.Fab")
        (effects (font (size 0.25 0.25) (thickness 0.04)))
    )
    (fp_text user "Author: Antmicro" (at -0.95 4.169 -90) (layer "F.Fab") hide
        (effects (font (size 0.7 0.7) (thickness 0.15)) (justify left bottom))
    )
    (fp_rect (start -0.925 -0.47) (end 0.925 0.47)
      (stroke (width 0.05) (type default)) (fill none) (layer "F.CrtYd"))
    (fp_rect (start -0.5 -0.25) (end 0.5 0.25)
      (stroke (width 0.15) (type solid)) (fill none) (layer "F.Fab"))
    (pad "1" smd roundrect (at -0.48 0 270) (size 0.59 0.64) (layers "F.Cu" "F.Paste" "F.Mask") (roundrect_rratio 0.25)
      (net 314 "Net-(D5-A)") (pintype "passive"))
    (pad "2" smd roundrect (at 0.48 0 270) (size 0.59 0.64) (layers "F.Cu" "F.Paste" "F.Mask") (roundrect_rratio 0.25)
      (net 2 "VCC3V3") (pintype "passive"))
  )

  (footprint "antmicro-footprints:BGA-1024-756_27x27mm_Layout32x32_P0.8mm" locked (layer "F.Cu")
    (at 104.4 120.55)
    (property "Author" "Antmicro")
    (property "License" "Apache-2.0")
    (property "MPN" "LFE5UM5G-85F-8BG756C")
    (property "Manufacturer" "Lattice Semiconductor")
    (property "Sheetfile" "fpga-power-supply.kicad_sch")
    (property "Sheetname" "FPGA power supply")
    (property "ki_description" "ECP5-5G Field Programmable Gate Array")
    (property "ki_keywords" "SMT, FPGA, IC")
    (attr smd)
    (fp_text reference "U21" (at -12.97 -14.53) (layer "F.SilkS")
        (effects (font (size 0.7 0.7) (thickness 0.127)))
    )
    (fp_text value "ECP5UM5G_85_CABGA756" (at 0 14.5) (layer "F.Fab")
        (effects (font (size 1 1) (thickness 0.15)))
    )
    (fp_text user "Author: Antmicro" (at -14.5 16.5) (layer "F.Fab") hide
        (effects (font (size 0.7 0.7) (thickness 0.15)) (justify left bottom))
    )
    (fp_text user "${REFERENCE}" (at -14.5 17.7) (layer "F.Fab") hide
        (effects (font (size 0.7 0.7) (thickness 0.15)) (justify left bottom))
    )
    (fp_text user "License: Apache-2.0" (at -14.5 18.9) (layer "F.Fab") hide
        (effects (font (size 0.7 0.7) (thickness 0.15)) (justify left bottom))
    )
    (fp_line (start -13.65 -12.5) (end -13.65 -6.9)
      (stroke (width 0.15) (type solid)) (layer "F.SilkS"))
    (fp_line (start -13.65 13.65) (end -13.65 6.9)
      (stroke (width 0.15) (type solid)) (layer "F.SilkS"))
    (fp_line (start -12.5 -13.65) (end -13.65 -12.5)
      (stroke (width 0.15) (type solid)) (layer "F.SilkS"))
    (fp_line (start -6.9 -13.65) (end -12.5 -13.65)
      (stroke (width 0.15) (type solid)) (layer "F.SilkS"))
    (fp_line (start -6.9 13.65) (end -13.65 13.65)
      (stroke (width 0.15) (type solid)) (layer "F.SilkS"))
    (fp_line (start 6.9 -13.65) (end 13.65 -13.65)
      (stroke (width 0.15) (type solid)) (layer "F.SilkS"))
    (fp_line (start 6.9 -13.65) (end 13.65 -13.65)
      (stroke (width 0.15) (type solid)) (layer "F.SilkS"))
    (fp_line (start 6.9 -13.65) (end 13.65 -13.65)
      (stroke (width 0.15) (type solid)) (layer "F.SilkS"))
    (fp_line (start 6.9 13.65) (end 13.65 13.65)
      (stroke (width 0.15) (type solid)) (layer "F.SilkS"))
    (fp_line (start 13.65 -13.65) (end 13.65 -6.9)
      (stroke (width 0.15) (type solid)) (layer "F.SilkS"))
    (fp_line (start 13.65 -13.65) (end 13.65 -6.9)
      (stroke (width 0.15) (type solid)) (layer "F.SilkS"))
    (fp_line (start 13.65 -13.65) (end 13.65 -6.9)
      (stroke (width 0.15) (type solid)) (layer "F.SilkS"))
    (fp_line (start 13.65 13.65) (end 13.65 6.9)
      (stroke (width 0.15) (type solid)) (layer "F.SilkS"))
    (fp_circle (center -13.8 -13.8) (end -13.75 -13.8)
      (stroke (width 0.15) (type solid)) (fill none) (layer "F.SilkS"))
    (fp_rect (start -14 -14) (end 14 14)
      (stroke (width 0.05) (type solid)) (fill none) (layer "F.CrtYd"))
    (fp_line (start -13.5 -12.5) (end -13.5 13.5)
      (stroke (width 0.15) (type solid)) (layer "F.Fab"))
    (fp_line (start -13.5 13.5) (end 13.5 13.5)
      (stroke (width 0.15) (type solid)) (layer "F.Fab"))
    (fp_line (start -12.5 -13.5) (end -13.5 -12.5)
      (stroke (width 0.15) (type solid)) (layer "F.Fab"))
    (fp_line (start 13.5 -13.5) (end -12.5 -13.5)
      (stroke (width 0.15) (type solid)) (layer "F.Fab"))
    (fp_line (start 13.5 13.5) (end 13.5 -13.5)
      (stroke (width 0.15) (type solid)) (layer "F.Fab"))
    (pad "A2" smd circle locked (at -11.6 -12.4) (size 0.4 0.4) (layers "F.Cu" "F.Paste" "F.Mask")
      (net 410 "PIRQ#") (pinfunction "PT6A") (pintype "bidirectional"))
    (pad "A3" smd circle locked (at -10.8 -12.4) (size 0.4 0.4) (layers "F.Cu" "F.Paste" "F.Mask")
      (net 411 "RST") (pinfunction "PT6B") (pintype "bidirectional"))
    (pad "A4" smd circle locked (at -10 -12.4) (size 0.4 0.4) (layers "F.Cu" "F.Paste" "F.Mask")
      (net 412 "GPIO") (pinfunction "PT9A") (pintype "bidirectional"))
    (pad "A5" smd circle locked (at -9.2 -12.4) (size 0.4 0.4) (layers "F.Cu" "F.Paste" "F.Mask")
      (net 413 "PP") (pinfunction "PT9B") (pintype "bidirectional"))
    (pad "A7" smd circle locked (at -7.6 -12.4) (size 0.4 0.4) (layers "F.Cu" "F.Paste" "F.Mask")
      (net 547 "unconnected-(U21B-PT13B-PadA7)") (pinfunction "PT13B") (pintype "bidirectional+no_connect"))
    (pad "A8" smd circle locked (at -6.8 -12.4) (size 0.4 0.4) (layers "F.Cu" "F.Paste" "F.Mask")
      (net 198 "RGMII_TXD1") (pinfunction "PT20B") (pintype "bidirectional"))
    (pad "A9" smd circle locked (at -6 -12.4) (size 0.4 0.4) (layers "F.Cu" "F.Paste" "F.Mask")
      (net 548 "unconnected-(U21B-PT24B-PadA9)") (pinfunction "PT24B") (pintype "bidirectional+no_connect"))
    (pad "A10" smd circle locked (at -5.2 -12.4) (size 0.4 0.4) (layers "F.Cu" "F.Paste" "F.Mask")
      (net 549 "unconnected-(U21B-PT31B-PadA10)") (pinfunction "PT31B") (pintype "bidirectional+no_connect"))
    (pad "A11" smd circle locked (at -4.4 -12.4) (size 0.4 0.4) (layers "F.Cu" "F.Paste" "F.Mask")
      (net 550 "unconnected-(U21B-PT38B-PadA11)") (pinfunction "PT38B") (pintype "bidirectional+no_connect"))
    (pad "A13" smd circle locked (at -2.8 -12.4) (size 0.4 0.4) (layers "F.Cu" "F.Paste" "F.Mask")
      (net 551 "unconnected-(U21B-PT42B-PadA13)") (pinfunction "PT42B") (pintype "bidirectional+no_connect"))
    (pad "A14" smd circle locked (at -2 -12.4) (size 0.4 0.4) (layers "F.Cu" "F.Paste" "F.Mask")
      (net 202 "RGMII_TXD0") (pinfunction "PT49B") (pintype "bidirectional"))
    (pad "A15" smd circle locked (at -1.2 -12.4) (size 0.4 0.4) (layers "F.Cu" "F.Paste" "F.Mask")
      (net 552 "unconnected-(U21B-PT54B-PadA15)") (pinfunction "PT54B") (pintype "bidirectional+no_connect"))
    (pad "A16" smd circle locked (at -0.4 -12.4) (size 0.4 0.4) (layers "F.Cu" "F.Paste" "F.Mask")
      (net 154 "RGMII_RXD0") (pinfunction "PT60B") (pintype "bidirectional"))
    (pad "A17" smd circle locked (at 0.4 -12.4) (size 0.4 0.4) (layers "F.Cu" "F.Paste" "F.Mask")
      (net 159 "RGMII_RX_CLK") (pinfunction "PT63A") (pintype "bidirectional"))
    (pad "A18" smd circle locked (at 1.2 -12.4) (size 0.4 0.4) (layers "F.Cu" "F.Paste" "F.Mask")
      (net 553 "unconnected-(U21C-PT71A-PadA18)") (pinfunction "PT71A") (pintype "bidirectional+no_connect"))
    (pad "A19" smd circle locked (at 2 -12.4) (size 0.4 0.4) (layers "F.Cu" "F.Paste" "F.Mask")
      (net 197 "ETH_INT_N") (pinfunction "PT76A") (pintype "bidirectional"))
    (pad "A20" smd circle locked (at 2.8 -12.4) (size 0.4 0.4) (layers "F.Cu" "F.Paste" "F.Mask")
      (net 168 "I3C[0]_SCL_3V3") (pinfunction "PT83A") (pintype "bidirectional"))
    (pad "A22" smd circle locked (at 4.4 -12.4) (size 0.4 0.4) (layers "F.Cu" "F.Paste" "F.Mask")
      (net 295 "USR_LED2") (pinfunction "PT87A") (pintype "bidirectional"))
    (pad "A23" smd circle locked (at 5.2 -12.4) (size 0.4 0.4) (layers "F.Cu" "F.Paste" "F.Mask")
      (net 49 "I2C[12]_SDA") (pinfunction "PT94A") (pintype "bidirectional"))
    (pad "A24" smd circle locked (at 6 -12.4) (size 0.4 0.4) (layers "F.Cu" "F.Paste" "F.Mask")
      (net 50 "I2C[12]_SCL") (pinfunction "PT101A") (pintype "bidirectional"))
    (pad "A25" smd circle locked (at 6.8 -12.4) (size 0.4 0.4) (layers "F.Cu" "F.Paste" "F.Mask")
      (net 42 "I2C[11]_SDA") (pinfunction "PT105A") (pintype "bidirectional"))
    (pad "A26" smd circle locked (at 7.6 -12.4) (size 0.4 0.4) (layers "F.Cu" "F.Paste" "F.Mask")
      (net 40 "I2C[11]_SCL") (pinfunction "PT112A") (pintype "bidirectional"))
    (pad "A28" smd circle locked (at 9.2 -12.4) (size 0.4 0.4) (layers "F.Cu" "F.Paste" "F.Mask")
      (net 26 "I2C[7]_SCL") (pinfunction "PT116A") (pintype "bidirectional"))
    (pad "A29" smd circle locked (at 10 -12.4) (size 0.4 0.4) (layers "F.Cu" "F.Paste" "F.Mask")
      (net 35 "I2C[6]_SDA") (pinfunction "PT116B") (pintype "bidirectional"))
    (pad "A30" smd circle locked (at 10.8 -12.4) (size 0.4 0.4) (layers "F.Cu" "F.Paste" "F.Mask")
      (net 34 "I2C[6]_SCL") (pinfunction "PT119A") (pintype "bidirectional"))
    (pad "A31" smd circle locked (at 11.6 -12.4) (size 0.4 0.4) (layers "F.Cu" "F.Paste" "F.Mask")
      (net 24 "I2C[5]_SCL") (pinfunction "PT119B") (pintype "bidirectional"))
    (pad "AA10" smd circle locked (at -5.2 3.6) (size 0.4 0.4) (layers "F.Cu" "F.Paste" "F.Mask")
      (net 3 "VCC1V35") (pinfunction "VCCIO6") (pintype "power_in"))
    (pad "AA11" smd circle locked (at -4.4 3.6) (size 0.4 0.4) (layers "F.Cu" "F.Paste" "F.Mask")
      (net 1 "GND") (pinfunction "GND") (pintype "power_in"))
    (pad "AA12" smd circle locked (at -3.6 3.6) (size 0.4 0.4) (layers "F.Cu" "F.Paste" "F.Mask")
      (net 211 "VCC1V2") (pinfunction "VCC") (pintype "power_in"))
    (pad "AA13" smd circle locked (at -2.8 3.6) (size 0.4 0.4) (layers "F.Cu" "F.Paste" "F.Mask")
      (net 211 "VCC1V2") (pinfunction "VCC") (pintype "passive"))
    (pad "AA14" smd circle locked (at -2 3.6) (size 0.4 0.4) (layers "F.Cu" "F.Paste" "F.Mask")
      (net 211 "VCC1V2") (pinfunction "VCC") (pintype "passive"))
    (pad "AA15" smd circle locked (at -1.2 3.6) (size 0.4 0.4) (layers "F.Cu" "F.Paste" "F.Mask")
      (net 211 "VCC1V2") (pinfunction "VCC") (pintype "passive"))
    (pad "AA16" smd circle locked (at -0.4 3.6) (size 0.4 0.4) (layers "F.Cu" "F.Paste" "F.Mask")
      (net 211 "VCC1V2") (pinfunction "VCC") (pintype "passive"))
    (pad "AA17" smd circle locked (at 0.4 3.6) (size 0.4 0.4) (layers "F.Cu" "F.Paste" "F.Mask")
      (net 211 "VCC1V2") (pinfunction "VCC") (pintype "passive"))
    (pad "AA18" smd circle locked (at 1.2 3.6) (size 0.4 0.4) (layers "F.Cu" "F.Paste" "F.Mask")
      (net 211 "VCC1V2") (pinfunction "VCC") (pintype "passive"))
    (pad "AA19" smd circle locked (at 2 3.6) (size 0.4 0.4) (layers "F.Cu" "F.Paste" "F.Mask")
      (net 211 "VCC1V2") (pinfunction "VCC") (pintype "passive"))
    (pad "AA20" smd circle locked (at 2.8 3.6) (size 0.4 0.4) (layers "F.Cu" "F.Paste" "F.Mask")
      (net 211 "VCC1V2") (pinfunction "VCC") (pintype "passive"))
    (pad "AA21" smd circle locked (at 3.6 3.6) (size 0.4 0.4) (layers "F.Cu" "F.Paste" "F.Mask")
      (net 211 "VCC1V2") (pinfunction "VCC") (pintype "passive"))
    (pad "AA22" smd circle locked (at 4.4 3.6) (size 0.4 0.4) (layers "F.Cu" "F.Paste" "F.Mask")
      (net 1 "GND") (pinfunction "GND") (pintype "passive"))
    (pad "AA23" smd circle locked (at 5.2 3.6) (size 0.4 0.4) (layers "F.Cu" "F.Paste" "F.Mask")
      (net 2 "VCC3V3") (pinfunction "VCCIO3") (pintype "power_in"))
    (pad "AB1" smd circle locked (at -12.4 4.4) (size 0.4 0.4) (layers "F.Cu" "F.Paste" "F.Mask")
      (net 187 "DDR3_DQ11") (pinfunction "PL92A") (pintype "bidirectional"))
    (pad "AB2" smd circle locked (at -11.6 4.4) (size 0.4 0.4) (layers "F.Cu" "F.Paste" "F.Mask")
      (net 176 "DDR3_DQS1-") (pinfunction "PL89B") (pintype "bidirectional"))
    (pad "AB3" smd circle locked (at -10.8 4.4) (size 0.4 0.4) (layers "F.Cu" "F.Paste" "F.Mask")
      (net 258 "DDR3_RAS") (pinfunction "PL83A") (pintype "bidirectional"))
    (pad "AB4" smd circle locked (at -10 4.4) (size 0.4 0.4) (layers "F.Cu" "F.Paste" "F.Mask")
      (net 185 "DDR3_DQ12") (pinfunction "PL83B") (pintype "bidirectional"))
    (pad "AB5" smd circle locked (at -9.2 4.4) (size 0.4 0.4) (layers "F.Cu" "F.Paste" "F.Mask")
      (net 183 "DDR3_DQS0+") (pinfunction "PL77A") (pintype "bidirectional"))
    (pad "AB6" smd circle locked (at -8.4 4.4) (size 0.4 0.4) (layers "F.Cu" "F.Paste" "F.Mask")
      (net 177 "DDR3_DQS0-") (pinfunction "PL77B") (pintype "bidirectional"))
    (pad "AB7" smd circle locked (at -7.6 4.4) (size 0.4 0.4) (layers "F.Cu" "F.Paste" "F.Mask")
      (net 192 "DDR3_DQ4") (pinfunction "PL74C") (pintype "bidirectional"))
    (pad "AB10" smd circle locked (at -5.2 4.4) (size 0.4 0.4) (layers "F.Cu" "F.Paste" "F.Mask")
      (net 2 "VCC3V3") (pinfunction "VCCIO8") (pintype "power_in"))
    (pad "AB11" smd circle locked (at -4.4 4.4) (size 0.4 0.4) (layers "F.Cu" "F.Paste" "F.Mask")
      (net 1 "GND") (pinfunction "GND") (pintype "passive"))
    (pad "AB12" smd circle locked (at -3.6 4.4) (size 0.4 0.4) (layers "F.Cu" "F.Paste" "F.Mask")
      (net 1 "GND") (pinfunction "GND") (pintype "passive"))
    (pad "AB13" smd circle locked (at -2.8 4.4) (size 0.4 0.4) (layers "F.Cu" "F.Paste" "F.Mask")
      (net 1 "GND") (pinfunction "GND") (pintype "passive"))
    (pad "AB14" smd circle locked (at -2 4.4) (size 0.4 0.4) (layers "F.Cu" "F.Paste" "F.Mask")
      (net 1 "GND") (pinfunction "GND") (pintype "passive"))
    (pad "AB15" smd circle locked (at -1.2 4.4) (size 0.4 0.4) (layers "F.Cu" "F.Paste" "F.Mask")
      (net 1 "GND") (pinfunction "GND") (pintype "passive"))
    (pad "AB16" smd circle locked (at -0.4 4.4) (size 0.4 0.4) (layers "F.Cu" "F.Paste" "F.Mask")
      (net 1 "GND") (pinfunction "GND") (pintype "passive"))
    (pad "AB17" smd circle locked (at 0.4 4.4) (size 0.4 0.4) (layers "F.Cu" "F.Paste" "F.Mask")
      (net 1 "GND") (pinfunction "GND") (pintype "passive"))
    (pad "AB18" smd circle locked (at 1.2 4.4) (size 0.4 0.4) (layers "F.Cu" "F.Paste" "F.Mask")
      (net 1 "GND") (pinfunction "GND") (pintype "passive"))
    (pad "AB19" smd circle locked (at 2 4.4) (size 0.4 0.4) (layers "F.Cu" "F.Paste" "F.Mask")
      (net 1 "GND") (pinfunction "GND") (pintype "passive"))
    (pad "AB20" smd circle locked (at 2.8 4.4) (size 0.4 0.4) (layers "F.Cu" "F.Paste" "F.Mask")
      (net 1 "GND") (pinfunction "GND") (pintype "passive"))
    (pad "AB21" smd circle locked (at 3.6 4.4) (size 0.4 0.4) (layers "F.Cu" "F.Paste" "F.Mask")
      (net 1 "GND") (pinfunction "GND") (pintype "passive"))
    (pad "AB22" smd circle locked (at 4.4 4.4) (size 0.4 0.4) (layers "F.Cu" "F.Paste" "F.Mask")
      (net 1 "GND") (pinfunction "GND") (pintype "passive"))
    (pad "AB23" smd circle locked (at 5.2 4.4) (size 0.4 0.4) (layers "F.Cu" "F.Paste" "F.Mask")
      (net 2 "VCC3V3") (pinfunction "VCCIO4") (pintype "power_in"))
    (pad "AB26" smd circle locked (at 7.6 4.4) (size 0.4 0.4) (layers "F.Cu" "F.Paste" "F.Mask")
      (net 554 "unconnected-(U21E-PR74C-PadAB26)") (pinfunction "PR74C") (pintype "bidirectional+no_connect"))
    (pad "AB27" smd circle locked (at 8.4 4.4) (size 0.4 0.4) (layers "F.Cu" "F.Paste" "F.Mask")
      (net 109 "HPM_FW_RECOVERY") (pinfunction "PR77B") (pintype "bidirectional"))
    (pad "AB28" smd circle locked (at 9.2 4.4) (size 0.4 0.4) (layers "F.Cu" "F.Paste" "F.Mask")
      (net 110 "HPM_STBY_RDY") (pinfunction "PR77A") (pintype "bidirectional"))
    (pad "AB29" smd circle locked (at 10 4.4) (size 0.4 0.4) (layers "F.Cu" "F.Paste" "F.Mask")
      (net 111 "HPM_STBY_EN") (pinfunction "PR83B") (pintype "bidirectional"))
    (pad "AB30" smd circle locked (at 10.8 4.4) (size 0.4 0.4) (layers "F.Cu" "F.Paste" "F.Mask")
      (net 322 "ULPI2_D7") (pinfunction "PR83A") (pintype "bidirectional"))
    (pad "AB31" smd circle locked (at 11.6 4.4) (size 0.4 0.4) (layers "F.Cu" "F.Paste" "F.Mask")
      (net 324 "ULPI2_D5") (pinfunction "PR89B") (pintype "bidirectional"))
    (pad "AB32" smd circle locked (at 12.4 4.4) (size 0.4 0.4) (layers "F.Cu" "F.Paste" "F.Mask")
      (net 323 "ULPI2_D6") (pinfunction "PR92A") (pintype "bidirectional"))
    (pad "AC1" smd circle locked (at -12.4 5.2) (size 0.4 0.4) (layers "F.Cu" "F.Paste" "F.Mask")
      (net 180 "DDR3_DQ13") (pinfunction "PL92B") (pintype "bidirectional"))
    (pad "AC2" smd circle locked (at -11.6 5.2) (size 0.4 0.4) (layers "F.Cu" "F.Paste" "F.Mask")
      (net 184 "DDR3_DM1") (pinfunction "PL89C") (pintype "bidirectional"))
    (pad "AC3" smd circle locked (at -10.8 5.2) (size 0.4 0.4) (layers "F.Cu" "F.Paste" "F.Mask")
      (net 175 "DDR3_DQS1+") (pinfunction "PL89A") (pintype "bidirectional"))
    (pad "AC4" smd circle locked (at -10 5.2) (size 0.4 0.4) (layers "F.Cu" "F.Paste" "F.Mask")
      (net 555 "unconnected-(U21A-NC-PadAC4)") (pinfunction "NC") (pintype "no_connect"))
    (pad "AC5" smd circle locked (at -9.2 5.2) (size 0.4 0.4) (layers "F.Cu" "F.Paste" "F.Mask")
      (net 251 "DDR3_WE") (pinfunction "PL83C") (pintype "bidirectional"))
    (pad "AC6" smd circle locked (at -8.4 5.2) (size 0.4 0.4) (layers "F.Cu" "F.Paste" "F.Mask")
      (net 196 "DDR3_DQ0") (pinfunction "PL74D") (pintype "bidirectional"))
    (pad "AC7" smd circle locked (at -7.6 5.2) (size 0.4 0.4) (layers "F.Cu" "F.Paste" "F.Mask")
      (net 256 "DDR3_BA0") (pinfunction "PL77C") (pintype "bidirectional"))
    (pad "AC10" smd circle locked (at -5.2 5.2) (size 0.4 0.4) (layers "F.Cu" "F.Paste" "F.Mask")
      (net 2 "VCC3V3") (pinfunction "VCCIO8") (pintype "passive"))
    (pad "AC11" smd circle locked (at -4.4 5.2) (size 0.4 0.4) (layers "F.Cu" "F.Paste" "F.Mask")
      (net 304 "/FPGA power supply/VCCAUX") (pinfunction "VCCAUX") (pintype "power_in"))
    (pad "AC12" smd circle locked (at -3.6 5.2) (size 0.4 0.4) (layers "F.Cu" "F.Paste" "F.Mask")
      (net 1 "GND") (pinfunction "GND") (pintype "passive"))
    (pad "AC13" smd circle locked (at -2.8 5.2) (size 0.4 0.4) (layers "F.Cu" "F.Paste" "F.Mask")
      (net 5 "/FPGA power supply/VCCHTX0") (pinfunction "VCCHTX0_D0CH0") (pintype "power_in"))
    (pad "AC14" smd circle locked (at -2 5.2) (size 0.4 0.4) (layers "F.Cu" "F.Paste" "F.Mask")
      (net 302 "/FPGA power supply/VCCA0") (pinfunction "VCCHRX0_D0CH0") (pintype "power_in"))
    (pad "AC15" smd circle locked (at -1.2 5.2) (size 0.4 0.4) (layers "F.Cu" "F.Paste" "F.Mask")
      (net 303 "/FPGA power supply/VCCA1") (pinfunction "VCCHRX1_D0CH1") (pintype "power_in"))
    (pad "AC16" smd circle locked (at -0.4 5.2) (size 0.4 0.4) (layers "F.Cu" "F.Paste" "F.Mask")
      (net 6 "/FPGA power supply/VCCHTX1") (pinfunction "VCCHTX1_D0CH1") (pintype "power_in"))
    (pad "AC17" smd circle locked (at 0.4 5.2) (size 0.4 0.4) (layers "F.Cu" "F.Paste" "F.Mask")
      (net 5 "/FPGA power supply/VCCHTX0") (pinfunction "VCCHTX0_D1CH0") (pintype "power_in"))
    (pad "AC18" smd circle locked (at 1.2 5.2) (size 0.4 0.4) (layers "F.Cu" "F.Paste" "F.Mask")
      (net 302 "/FPGA power supply/VCCA0") (pinfunction "VCCHRX0_D1CH0") (pintype "power_in"))
    (pad "AC19" smd circle locked (at 2 5.2) (size 0.4 0.4) (layers "F.Cu" "F.Paste" "F.Mask")
      (net 303 "/FPGA power supply/VCCA1") (pinfunction "VCCHRX1_D1CH1") (pintype "power_in"))
    (pad "AC20" smd circle locked (at 2.8 5.2) (size 0.4 0.4) (layers "F.Cu" "F.Paste" "F.Mask")
      (net 6 "/FPGA power supply/VCCHTX1") (pinfunction "VCCHTX1_D1CH1") (pintype "power_in"))
    (pad "AC21" smd circle locked (at 3.6 5.2) (size 0.4 0.4) (layers "F.Cu" "F.Paste" "F.Mask")
      (net 1 "GND") (pinfunction "GND") (pintype "passive"))
    (pad "AC22" smd circle locked (at 4.4 5.2) (size 0.4 0.4) (layers "F.Cu" "F.Paste" "F.Mask")
      (net 304 "/FPGA power supply/VCCAUX") (pinfunction "VCCAUX") (pintype "passive"))
    (pad "AC23" smd circle locked (at 5.2 5.2) (size 0.4 0.4) (layers "F.Cu" "F.Paste" "F.Mask")
      (net 2 "VCC3V3") (pinfunction "VCCIO4") (pintype "passive"))
    (pad "AC26" smd circle locked (at 7.6 5.2) (size 0.4 0.4) (layers "F.Cu" "F.Paste" "F.Mask")
      (net 556 "unconnected-(U21E-PR77C-PadAC26)") (pinfunction "PR77C") (pintype "bidirectional+no_connect"))
    (pad "AC27" smd circle locked (at 8.4 5.2) (size 0.4 0.4) (layers "F.Cu" "F.Paste" "F.Mask")
      (net 557 "unconnected-(U21E-PR74D-PadAC27)") (pinfunction "PR74D") (pintype "bidirectional+no_connect"))
    (pad "AC28" smd circle locked (at 9.2 5.2) (size 0.4 0.4) (layers "F.Cu" "F.Paste" "F.Mask")
      (net 558 "unconnected-(U21E-PR83C-PadAC28)") (pinfunction "PR83C") (pintype "bidirectional+no_connect"))
    (pad "AC29" smd circle locked (at 10 5.2) (size 0.4 0.4) (layers "F.Cu" "F.Paste" "F.Mask")
      (net 559 "unconnected-(U21A-NC-PadAC29)") (pinfunction "NC") (pintype "no_connect"))
    (pad "AC30" smd circle locked (at 10.8 5.2) (size 0.4 0.4) (layers "F.Cu" "F.Paste" "F.Mask")
      (net 560 "unconnected-(U21E-PR89A-PadAC30)") (pinfunction "PR89A") (pintype "bidirectional+no_connect"))
    (pad "AC31" smd circle locked (at 11.6 5.2) (size 0.4 0.4) (layers "F.Cu" "F.Paste" "F.Mask")
      (net 326 "ULPI2_D3") (pinfunction "PR89C") (pintype "bidirectional"))
    (pad "AC32" smd circle locked (at 12.4 5.2) (size 0.4 0.4) (layers "F.Cu" "F.Paste" "F.Mask")
      (net 325 "ULPI2_D4") (pinfunction "PR92B") (pintype "bidirectional"))
    (pad "AD1" smd circle locked (at -12.4 6) (size 0.4 0.4) (layers "F.Cu" "F.Paste" "F.Mask")
      (net 179 "DDR3_DQ15") (pinfunction "PL92C") (pintype "bidirectional"))
    (pad "AD2" smd circle locked (at -11.6 6) (size 0.4 0.4) (layers "F.Cu" "F.Paste" "F.Mask")
      (net 1 "GND") (pinfunction "GND") (pintype "passive"))
    (pad "AD3" smd circle locked (at -10.8 6) (size 0.4 0.4) (layers "F.Cu" "F.Paste" "F.Mask")
      (net 186 "DDR3_DQ10") (pinfunction "PL86C") (pintype "bidirectional"))
    (pad "AD4" smd circle locked (at -10 6) (size 0.4 0.4) (layers "F.Cu" "F.Paste" "F.Mask")
      (net 259 "DDR3_ODT") (pinfunction "PL83D") (pintype "bidirectional"))
    (pad "AD5" smd circle locked (at -9.2 6) (size 0.4 0.4) (layers "F.Cu" "F.Paste" "F.Mask")
      (net 1 "GND") (pinfunction "GND") (pintype "passive"))
    (pad "AD6" smd circle locked (at -8.4 6) (size 0.4 0.4) (layers "F.Cu" "F.Paste" "F.Mask")
      (net 191 "DDR3_DQ1") (pinfunction "PL80A") (pintype "bidirectional"))
    (pad "AD7" smd circle locked (at -7.6 6) (size 0.4 0.4) (layers "F.Cu" "F.Paste" "F.Mask")
      (net 178 "DDR3_DM0") (pinfunction "PL77D") (pintype "bidirectional"))
    (pad "AD26" smd circle locked (at 7.6 6) (size 0.4 0.4) (layers "F.Cu" "F.Paste" "F.Mask")
      (net 561 "unconnected-(U21E-PR77D-PadAD26)") (pinfunction "PR77D") (pintype "bidirectional+no_connect"))
    (pad "AD27" smd circle locked (at 8.4 6) (size 0.4 0.4) (layers "F.Cu" "F.Paste" "F.Mask")
      (net 562 "unconnected-(U21E-PR80A-PadAD27)") (pinfunction "PR80A") (pintype "bidirectional+no_connect"))
    (pad "AD28" smd circle locked (at 9.2 6) (size 0.4 0.4) (layers "F.Cu" "F.Paste" "F.Mask")
      (net 1 "GND") (pinfunction "GND") (pintype "passive"))
    (pad "AD29" smd circle locked (at 10 6) (size 0.4 0.4) (layers "F.Cu" "F.Paste" "F.Mask")
      (net 563 "unconnected-(U21E-PR83D-PadAD29)") (pinfunction "PR83D") (pintype "bidirectional+no_connect"))
    (pad "AD30" smd circle locked (at 10.8 6) (size 0.4 0.4) (layers "F.Cu" "F.Paste" "F.Mask")
      (net 564 "unconnected-(U21E-PR86C-PadAD30)") (pinfunction "PR86C") (pintype "bidirectional+no_connect"))
    (pad "AD31" smd circle locked (at 11.6 6) (size 0.4 0.4) (layers "F.Cu" "F.Paste" "F.Mask")
      (net 1 "GND") (pinfunction "GND") (pintype "passive"))
    (pad "AD32" smd circle locked (at 12.4 6) (size 0.4 0.4) (layers "F.Cu" "F.Paste" "F.Mask")
      (net 327 "ULPI2_D2") (pinfunction "PR92C") (pintype "bidirectional"))
    (pad "AE1" smd circle locked (at -12.4 6.8) (size 0.4 0.4) (layers "F.Cu" "F.Paste" "F.Mask")
      (net 182 "DDR3_DQ9") (pinfunction "PL92D") (pintype "bidirectional"))
    (pad "AE2" smd circle locked (at -11.6 6.8) (size 0.4 0.4) (layers "F.Cu" "F.Paste" "F.Mask")
      (net 181 "DDR3_DQ14") (pinfunction "PL89D") (pintype "bidirectional"))
    (pad "AE3" smd circle locked (at -10.8 6.8) (size 0.4 0.4) (layers "F.Cu" "F.Paste" "F.Mask")
      (net 195 "DDR3_DQ8") (pinfunction "PL86D") (pintype "bidirectional"))
    (pad "AE4" smd circle locked (at -10 6.8) (size 0.4 0.4) (layers "F.Cu" "F.Paste" "F.Mask")
      (net 253 "DDR3_A5") (pinfunction "PL80D") (pintype "bidirectional"))
    (pad "AE5" smd circle locked (at -9.2 6.8) (size 0.4 0.4) (layers "F.Cu" "F.Paste" "F.Mask")
      (net 193 "DDR3_DQ3") (pinfunction "PL80C") (pintype "bidirectional"))
    (pad "AE6" smd circle locked (at -8.4 6.8) (size 0.4 0.4) (layers "F.Cu" "F.Paste" "F.Mask")
      (net 255 "DDR3_A3") (pinfunction "PL80B") (pintype "bidirectional"))
    (pad "AE7" smd circle locked (at -7.6 6.8) (size 0.4 0.4) (layers "F.Cu" "F.Paste" "F.Mask")
      (net 565 "unconnected-(U21A-NC-PadAE7)") (pinfunction "NC") (pintype "no_connect"))
    (pad "AE26" smd circle locked (at 7.6 6.8) (size 0.4 0.4) (layers "F.Cu" "F.Paste" "F.Mask")
      (net 566 "unconnected-(U21A-NC-PadAE26)") (pinfunction "NC") (pintype "no_connect"))
    (pad "AE27" smd circle locked (at 8.4 6.8) (size 0.4 0.4) (layers "F.Cu" "F.Paste" "F.Mask")
      (net 567 "unconnected-(U21E-PR80B-PadAE27)") (pinfunction "PR80B") (pintype "bidirectional+no_connect"))
    (pad "AE28" smd circle locked (at 9.2 6.8) (size 0.4 0.4) (layers "F.Cu" "F.Paste" "F.Mask")
      (net 568 "unconnected-(U21E-PR80C-PadAE28)") (pinfunction "PR80C") (pintype "bidirectional+no_connect"))
    (pad "AE29" smd circle locked (at 10 6.8) (size 0.4 0.4) (layers "F.Cu" "F.Paste" "F.Mask")
      (net 569 "unconnected-(U21E-PR80D-PadAE29)") (pinfunction "PR80D") (pintype "bidirectional+no_connect"))
    (pad "AE30" smd circle locked (at 10.8 6.8) (size 0.4 0.4) (layers "F.Cu" "F.Paste" "F.Mask")
      (net 570 "unconnected-(U21E-PR86D-PadAE30)") (pinfunction "PR86D") (pintype "bidirectional+no_connect"))
    (pad "AE31" smd circle locked (at 11.6 6.8) (size 0.4 0.4) (layers "F.Cu" "F.Paste" "F.Mask")
      (net 328 "ULPI2_D1") (pinfunction "PR89D") (pintype "bidirectional"))
    (pad "AE32" smd circle locked (at 12.4 6.8) (size 0.4 0.4) (layers "F.Cu" "F.Paste" "F.Mask")
      (net 329 "ULPI2_D0") (pinfunction "PR92D") (pintype "bidirectional"))
    (pad "AF11" smd circle locked (at -4.4 7.6) (size 0.4 0.4) (layers "F.Cu" "F.Paste" "F.Mask")
      (net 1 "GND") (pinfunction "GND") (pintype "passive"))
    (pad "AF12" smd circle locked (at -3.6 7.6) (size 0.4 0.4) (layers "F.Cu" "F.Paste" "F.Mask")
      (net 1 "GND") (pinfunction "GND") (pintype "passive"))
    (pad "AF14" smd circle locked (at -2 7.6) (size 0.4 0.4) (layers "F.Cu" "F.Paste" "F.Mask")
      (net 1 "GND") (pinfunction "GND") (pintype "passive"))
    (pad "AF15" smd circle locked (at -1.2 7.6) (size 0.4 0.4) (layers "F.Cu" "F.Paste" "F.Mask")
      (net 1 "GND") (pinfunction "GND") (pintype "passive"))
    (pad "AF16" smd circle locked (at -0.4 7.6) (size 0.4 0.4) (layers "F.Cu" "F.Paste" "F.Mask")
      (net 1 "GND") (pinfunction "GND") (pintype "passive"))
    (pad "AF17" smd circle locked (at 0.4 7.6) (size 0.4 0.4) (layers "F.Cu" "F.Paste" "F.Mask")
      (net 1 "GND") (pinfunction "GND") (pintype "passive"))
    (pad "AF19" smd circle locked (at 2 7.6) (size 0.4 0.4) (layers "F.Cu" "F.Paste" "F.Mask")
      (net 1 "GND") (pinfunction "GND") (pintype "passive"))
    (pad "AF20" smd circle locked (at 2.8 7.6) (size 0.4 0.4) (layers "F.Cu" "F.Paste" "F.Mask")
      (net 1 "GND") (pinfunction "GND") (pintype "passive"))
    (pad "AF22" smd circle locked (at 4.4 7.6) (size 0.4 0.4) (layers "F.Cu" "F.Paste" "F.Mask")
      (net 303 "/FPGA power supply/VCCA1") (pinfunction "VCCA1") (pintype "power_in"))
    (pad "AF23" smd circle locked (at 5.2 7.6) (size 0.4 0.4) (layers "F.Cu" "F.Paste" "F.Mask")
      (net 1 "GND") (pinfunction "GND") (pintype "passive"))
    (pad "AG1" smd circle locked (at -12.4 8.4) (size 0.4 0.4) (layers "F.Cu" "F.Paste" "F.Mask")
      (net 427 "Net-(U21I-PB4A)") (pinfunction "PB4A") (pintype "bidirectional"))
    (pad "AG2" smd circle locked (at -11.6 8.4) (size 0.4 0.4) (layers "F.Cu" "F.Paste" "F.Mask")
      (net 571 "unconnected-(U21A-NC-PadAG2)") (pinfunction "NC") (pintype "no_connect"))
    (pad "AG3" smd circle locked (at -10.8 8.4) (size 0.4 0.4) (layers "F.Cu" "F.Paste" "F.Mask")
      (net 271 "ROT_QSPI_CS_N") (pinfunction "PB13A") (pintype "bidirectional"))
    (pad "AG4" smd circle locked (at -10 8.4) (size 0.4 0.4) (layers "F.Cu" "F.Paste" "F.Mask")
      (net 269 "INIT_N") (pinfunction "INITN") (pintype "bidirectional"))
    (pad "AG5" smd circle locked (at -9.2 8.4) (size 0.4 0.4) (layers "F.Cu" "F.Paste" "F.Mask")
      (net 20 "JTAG_TDO") (pinfunction "TDO") (pintype "bidirectional"))
    (pad "AG9" smd circle locked (at -6 8.4) (size 0.4 0.4) (layers "F.Cu" "F.Paste" "F.Mask")
      (net 302 "/FPGA power supply/VCCA0") (pinfunction "VCCA0") (pintype "passive"))
    (pad "AG11" smd circle locked (at -4.4 8.4) (size 0.4 0.4) (layers "F.Cu" "F.Paste" "F.Mask")
      (net 1 "GND") (pinfunction "GND") (pintype "passive"))
    (pad "AG12" smd circle locked (at -3.6 8.4) (size 0.4 0.4) (layers "F.Cu" "F.Paste" "F.Mask")
      (net 302 "/FPGA power supply/VCCA0") (pinfunction "VCCA0") (pintype "power_in"))
    (pad "AG14" smd circle locked (at -2 8.4) (size 0.4 0.4) (layers "F.Cu" "F.Paste" "F.Mask")
      (net 1 "GND") (pinfunction "GND") (pintype "passive"))
    (pad "AG15" smd circle locked (at -1.2 8.4) (size 0.4 0.4) (layers "F.Cu" "F.Paste" "F.Mask")
      (net 1 "GND") (pinfunction "GND") (pintype "passive"))
    (pad "AG16" smd circle locked (at -0.4 8.4) (size 0.4 0.4) (layers "F.Cu" "F.Paste" "F.Mask")
      (net 1 "GND") (pinfunction "GND") (pintype "passive"))
    (pad "AG17" smd circle locked (at 0.4 8.4) (size 0.4 0.4) (layers "F.Cu" "F.Paste" "F.Mask")
      (net 1 "GND") (pinfunction "GND") (pintype "passive"))
    (pad "AG19" smd circle locked (at 2 8.4) (size 0.4 0.4) (layers "F.Cu" "F.Paste" "F.Mask")
      (net 303 "/FPGA power supply/VCCA1") (pinfunction "VCCA1") (pintype "passive"))
    (pad "AG20" smd circle locked (at 2.8 8.4) (size 0.4 0.4) (layers "F.Cu" "F.Paste" "F.Mask")
      (net 1 "GND") (pinfunction "GND") (pintype "passive"))
    (pad "AG22" smd circle locked (at 4.4 8.4) (size 0.4 0.4) (layers "F.Cu" "F.Paste" "F.Mask")
      (net 303 "/FPGA power supply/VCCA1") (pinfunction "VCCA1") (pintype "passive"))
    (pad "AG23" smd circle locked (at 5.2 8.4) (size 0.4 0.4) (layers "F.Cu" "F.Paste" "F.Mask")
      (net 1 "GND") (pinfunction "GND") (pintype "passive"))
    (pad "AG24" smd circle locked (at 6 8.4) (size 0.4 0.4) (layers "F.Cu" "F.Paste" "F.Mask")
      (net 572 "unconnected-(U21A-NC-PadAG24)") (pinfunction "NC") (pintype "no_connect"))
    (pad "AG28" smd circle locked (at 9.2 8.4) (size 0.4 0.4) (layers "F.Cu" "F.Paste" "F.Mask")
      (net 94 "QSPI1_D0") (pinfunction "PB110A") (pintype "bidirectional"))
    (pad "AG29" smd circle locked (at 10 8.4) (size 0.4 0.4) (layers "F.Cu" "F.Paste" "F.Mask")
      (net 95 "QSPI1_D1") (pinfunction "PB110B") (pintype "bidirectional"))
    (pad "AG30" smd circle locked (at 10.8 8.4) (size 0.4 0.4) (layers "F.Cu" "F.Paste" "F.Mask")
      (net 96 "QSPI1_D2") (pinfunction "PB114B") (pintype "bidirectional"))
    (pad "AG31" smd circle locked (at 11.6 8.4) (size 0.4 0.4) (layers "F.Cu" "F.Paste" "F.Mask")
      (net 573 "unconnected-(U21A-NC-PadAG31)") (pinfunction "NC") (pintype "no_connect"))
    (pad "AG32" smd circle locked (at 12.4 8.4) (size 0.4 0.4) (layers "F.Cu" "F.Paste" "F.Mask")
      (net 97 "QSPI1_D3") (pinfunction "PB119B") (pintype "bidirectional"))
    (pad "AH1" smd circle locked (at -12.4 9.2) (size 0.4 0.4) (layers "F.Cu" "F.Paste" "F.Mask")
      (net 428 "Net-(U21I-PB4B)") (pinfunction "PB4B") (pintype "bidirectional"))
    (pad "AH2" smd circle locked (at -11.6 9.2) (size 0.4 0.4) (layers "F.Cu" "F.Paste" "F.Mask")
      (net 1 "GND") (pinfunction "GND") (pintype "passive"))
    (pad "AH3" smd circle locked (at -10.8 9.2) (size 0.4 0.4) (layers "F.Cu" "F.Paste" "F.Mask")
      (net 574 "unconnected-(U21I-PB13B-PadAH3)") (pinfunction "PB13B") (pintype "bidirectional+no_connect"))
    (pad "AH4" smd circle locked (at -10 9.2) (size 0.4 0.4) (layers "F.Cu" "F.Paste" "F.Mask")
      (net 268 "PROGRAM_N") (pinfunction "PROGRAMN") (pintype "bidirectional"))
    (pad "AH5" smd circle locked (at -9.2 9.2) (size 0.4 0.4) (layers "F.Cu" "F.Paste" "F.Mask")
      (net 1 "GND") (pinfunction "GND") (pintype "passive"))
    (pad "AH7" smd circle locked (at -7.6 9.2) (size 0.4 0.4) (layers "F.Cu" "F.Paste" "F.Mask")
      (net 1 "GND") (pinfunction "GND") (pintype "passive"))
    (pad "AH8" smd circle locked (at -6.8 9.2) (size 0.4 0.4) (layers "F.Cu" "F.Paste" "F.Mask")
      (net 1 "GND") (pinfunction "GND") (pintype "passive"))
    (pad "AH9" smd circle locked (at -6 9.2) (size 0.4 0.4) (layers "F.Cu" "F.Paste" "F.Mask")
      (net 302 "/FPGA power supply/VCCA0") (pinfunction "VCCA0") (pintype "passive"))
    (pad "AH11" smd circle locked (at -4.4 9.2) (size 0.4 0.4) (layers "F.Cu" "F.Paste" "F.Mask")
      (net 1 "GND") (pinfunction "GND") (pintype "passive"))
    (pad "AH12" smd circle locked (at -3.6 9.2) (size 0.4 0.4) (layers "F.Cu" "F.Paste" "F.Mask")
      (net 302 "/FPGA power supply/VCCA0") (pinfunction "VCCA0") (pintype "passive"))
    (pad "AH14" smd circle locked (at -2 9.2) (size 0.4 0.4) (layers "F.Cu" "F.Paste" "F.Mask")
      (net 1 "GND") (pinfunction "GND") (pintype "passive"))
    (pad "AH15" smd circle locked (at -1.2 9.2) (size 0.4 0.4) (layers "F.Cu" "F.Paste" "F.Mask")
      (net 1 "GND") (pinfunction "GND") (pintype "passive"))
    (pad "AH16" smd circle locked (at -0.4 9.2) (size 0.4 0.4) (layers "F.Cu" "F.Paste" "F.Mask")
      (net 1 "GND") (pinfunction "GND") (pintype "passive"))
    (pad "AH17" smd circle locked (at 0.4 9.2) (size 0.4 0.4) (layers "F.Cu" "F.Paste" "F.Mask")
      (net 1 "GND") (pinfunction "GND") (pintype "passive"))
    (pad "AH19" smd circle locked (at 2 9.2) (size 0.4 0.4) (layers "F.Cu" "F.Paste" "F.Mask")
      (net 303 "/FPGA power supply/VCCA1") (pinfunction "VCCA1") (pintype "passive"))
    (pad "AH20" smd circle locked (at 2.8 9.2) (size 0.4 0.4) (layers "F.Cu" "F.Paste" "F.Mask")
      (net 1 "GND") (pinfunction "GND") (pintype "passive"))
    (pad "AH22" smd circle locked (at 4.4 9.2) (size 0.4 0.4) (layers "F.Cu" "F.Paste" "F.Mask")
      (net 303 "/FPGA power supply/VCCA1") (pinfunction "VCCA1") (pintype "passive"))
    (pad "AH23" smd circle locked (at 5.2 9.2) (size 0.4 0.4) (layers "F.Cu" "F.Paste" "F.Mask")
      (net 1 "GND") (pinfunction "GND") (pintype "passive"))
    (pad "AH24" smd circle locked (at 6 9.2) (size 0.4 0.4) (layers "F.Cu" "F.Paste" "F.Mask")
      (net 1 "GND") (pinfunction "GND") (pintype "passive"))
    (pad "AH25" smd circle locked (at 6.8 9.2) (size 0.4 0.4) (layers "F.Cu" "F.Paste" "F.Mask")
      (net 1 "GND") (pinfunction "GND") (pintype "passive"))
    (pad "AH26" smd circle locked (at 7.6 9.2) (size 0.4 0.4) (layers "F.Cu" "F.Paste" "F.Mask")
      (net 1 "GND") (pinfunction "GND") (pintype "passive"))
    (pad "AH28" smd circle locked (at 9.2 9.2) (size 0.4 0.4) (layers "F.Cu" "F.Paste" "F.Mask")
      (net 78 "NCSI_TXD1") (pinfunction "PB112B") (pintype "bidirectional"))
    (pad "AH29" smd circle locked (at 10 9.2) (size 0.4 0.4) (layers "F.Cu" "F.Paste" "F.Mask")
      (net 1 "GND") (pinfunction "GND") (pintype "passive"))
    (pad "AH30" smd circle locked (at 10.8 9.2) (size 0.4 0.4) (layers "F.Cu" "F.Paste" "F.Mask")
      (net 79 "NCSI_RXER") (pinfunction "PB114A") (pintype "bidirectional"))
    (pad "AH31" smd circle locked (at 11.6 9.2) (size 0.4 0.4) (layers "F.Cu" "F.Paste" "F.Mask")
      (net 1 "GND") (pinfunction "GND") (pintype "passive"))
    (pad "AH32" smd circle locked (at 12.4 9.2) (size 0.4 0.4) (layers "F.Cu" "F.Paste" "F.Mask")
      (net 90 "SGPIO_INTR_N") (pinfunction "PB119A") (pintype "bidirectional"))
    (pad "AJ1" smd circle locked (at -12.4 10) (size 0.4 0.4) (layers "F.Cu" "F.Paste" "F.Mask")
      (net 431 "Net-(U21I-PB6A)") (pinfunction "PB6A") (pintype "bidirectional"))
    (pad "AJ2" smd circle locked (at -11.6 10) (size 0.4 0.4) (layers "F.Cu" "F.Paste" "F.Mask")
      (net 275 "ROT_QSPI_DQ1") (pinfunction "PB11A") (pintype "bidirectional"))
    (pad "AJ3" smd circle locked (at -10.8 10) (size 0.4 0.4) (layers "F.Cu" "F.Paste" "F.Mask")
      (net 575 "unconnected-(U21I-PB15A-PadAJ3)") (pinfunction "PB15A") (pintype "bidirectional+no_connect"))
    (pad "AJ4" smd circle locked (at -10 10) (size 0.4 0.4) (layers "F.Cu" "F.Paste" "F.Mask")
      (net 278 "DONE") (pinfunction "DONE") (pintype "bidirectional"))
    (pad "AJ5" smd circle locked (at -9.2 10) (size 0.4 0.4) (layers "F.Cu" "F.Paste" "F.Mask")
      (net 19 "JTAG_TDI") (pinfunction "TDI") (pintype "bidirectional"))
    (pad "AJ7" smd circle locked (at -7.6 10) (size 0.4 0.4) (layers "F.Cu" "F.Paste" "F.Mask")
      (net 1 "GND") (pinfunction "GND") (pintype "passive"))
    (pad "AJ8" smd circle locked (at -6.8 10) (size 0.4 0.4) (layers "F.Cu" "F.Paste" "F.Mask")
      (net 1 "GND") (pinfunction "GND") (pintype "passive"))
    (pad "AJ9" smd circle locked (at -6 10) (size 0.4 0.4) (layers "F.Cu" "F.Paste" "F.Mask")
      (net 302 "/FPGA power supply/VCCA0") (pinfunction "VCCA0") (pintype "passive"))
    (pad "AJ10" smd circle locked (at -5.2 10) (size 0.4 0.4) (layers "F.Cu" "F.Paste" "F.Mask")
      (net 302 "/FPGA power supply/VCCA0") (pinfunction "VCCA0") (pintype "passive"))
    (pad "AJ11" smd circle locked (at -4.4 10) (size 0.4 0.4) (layers "F.Cu" "F.Paste" "F.Mask")
      (net 1 "GND") (pinfunction "GND") (pintype "passive"))
    (pad "AJ12" smd circle locked (at -3.6 10) (size 0.4 0.4) (layers "F.Cu" "F.Paste" "F.Mask")
      (net 302 "/FPGA power supply/VCCA0") (pinfunction "VCCA0") (pintype "passive"))
    (pad "AJ13" smd circle locked (at -2.8 10) (size 0.4 0.4) (layers "F.Cu" "F.Paste" "F.Mask")
      (net 302 "/FPGA power supply/VCCA0") (pinfunction "VCCA0") (pintype "passive"))
    (pad "AJ14" smd circle locked (at -2 10) (size 0.4 0.4) (layers "F.Cu" "F.Paste" "F.Mask")
      (net 1 "GND") (pinfunction "GND") (pintype "passive"))
    (pad "AJ15" smd circle locked (at -1.2 10) (size 0.4 0.4) (layers "F.Cu" "F.Paste" "F.Mask")
      (net 304 "/FPGA power supply/VCCAUX") (pinfunction "VCCAUXA0") (pintype "power_in"))
    (pad "AJ16" smd circle locked (at -0.4 10) (size 0.4 0.4) (layers "F.Cu" "F.Paste" "F.Mask")
      (net 304 "/FPGA power supply/VCCAUX") (pinfunction "VCCAUXA0") (pintype "passive"))
    (pad "AJ17" smd circle locked (at 0.4 10) (size 0.4 0.4) (layers "F.Cu" "F.Paste" "F.Mask")
      (net 1 "GND") (pinfunction "GND") (pintype "passive"))
    (pad "AJ18" smd circle locked (at 1.2 10) (size 0.4 0.4) (layers "F.Cu" "F.Paste" "F.Mask")
      (net 303 "/FPGA power supply/VCCA1") (pinfunction "VCCA1") (pintype "passive"))
    (pad "AJ19" smd circle locked (at 2 10) (size 0.4 0.4) (layers "F.Cu" "F.Paste" "F.Mask")
      (net 303 "/FPGA power supply/VCCA1") (pinfunction "VCCA1") (pintype "passive"))
    (pad "AJ20" smd circle locked (at 2.8 10) (size 0.4 0.4) (layers "F.Cu" "F.Paste" "F.Mask")
      (net 1 "GND") (pinfunction "GND") (pintype "passive"))
    (pad "AJ21" smd circle locked (at 3.6 10) (size 0.4 0.4) (layers "F.Cu" "F.Paste" "F.Mask")
      (net 303 "/FPGA power supply/VCCA1") (pinfunction "VCCA1") (pintype "passive"))
    (pad "AJ22" smd circle locked (at 4.4 10) (size 0.4 0.4) (layers "F.Cu" "F.Paste" "F.Mask")
      (net 303 "/FPGA power supply/VCCA1") (pinfunction "VCCA1") (pintype "passive"))
    (pad "AJ23" smd circle locked (at 5.2 10) (size 0.4 0.4) (layers "F.Cu" "F.Paste" "F.Mask")
      (net 1 "GND") (pinfunction "GND") (pintype "passive"))
    (pad "AJ24" smd circle locked (at 6 10) (size 0.4 0.4) (layers "F.Cu" "F.Paste" "F.Mask")
      (net 304 "/FPGA power supply/VCCAUX") (pinfunction "VCCAUXA1") (pintype "power_in"))
    (pad "AJ25" smd circle locked (at 6.8 10) (size 0.4 0.4) (layers "F.Cu" "F.Paste" "F.Mask")
      (net 304 "/FPGA power supply/VCCAUX") (pinfunction "VCCAUXA1") (pintype "passive"))
    (pad "AJ26" smd circle locked (at 7.6 10) (size 0.4 0.4) (layers "F.Cu" "F.Paste" "F.Mask")
      (net 1 "GND") (pinfunction "GND") (pintype "passive"))
    (pad "AJ28" smd circle locked (at 9.2 10) (size 0.4 0.4) (layers "F.Cu" "F.Paste" "F.Mask")
      (net 74 "NCSI_CLK") (pinfunction "PB112A") (pintype "bidirectional"))
    (pad "AJ29" smd circle locked (at 10 10) (size 0.4 0.4) (layers "F.Cu" "F.Paste" "F.Mask")
      (net 80 "NCSI_RXD0") (pinfunction "PB121A") (pintype "bidirectional"))
    (pad "AJ30" smd circle locked (at 10.8 10) (size 0.4 0.4) (layers "F.Cu" "F.Paste" "F.Mask")
      (net 86 "SGPIO1_DO") (pinfunction "PB121B") (pintype "bidirectional"))
    (pad "AJ31" smd circle locked (at 11.6 10) (size 0.4 0.4) (layers "F.Cu" "F.Paste" "F.Mask")
      (net 92 "QSPI1_CLK") (pinfunction "PB105B") (pintype "bidirectional"))
    (pad "AJ32" smd circle locked (at 12.4 10) (size 0.4 0.4) (layers "F.Cu" "F.Paste" "F.Mask")
      (net 89 "SGPIO_RESET_N") (pinfunction "PB101B") (pintype "bidirectional"))
    (pad "AK1" smd circle locked (at -12.4 10.8) (size 0.4 0.4) (layers "F.Cu" "F.Paste" "F.Mask")
      (net 429 "Net-(U21I-PB6B)") (pinfunction "PB6B") (pintype "bidirectional"))
    (pad "AK2" smd circle locked (at -11.6 10.8) (size 0.4 0.4) (layers "F.Cu" "F.Paste" "F.Mask")
      (net 276 "ROT_QSPI_DQ0") (pinfunction "PB11B") (pintype "bidirectional"))
    (pad "AK3" smd circle locked (at -10.8 10.8) (size 0.4 0.4) (layers "F.Cu" "F.Paste" "F.Mask")
      (net 102 "VIRTUAL_RESEAT") (pinfunction "PB15B") (pintype "bidirectional"))
    (pad "AK4" smd circle locked (at -10 10.8) (size 0.4 0.4) (layers "F.Cu" "F.Paste" "F.Mask")
      (net 576 "unconnected-(U21I-CFG_2-PadAK4)") (pinfunction "CFG_2") (pintype "bidirectional+no_connect"))
    (pad "AK5" smd circle locked (at -9.2 10.8) (size 0.4 0.4) (layers "F.Cu" "F.Paste" "F.Mask")
      (net 21 "JTAG_TCK") (pinfunction "TCK") (pintype "bidirectional"))
    (pad "AK7" smd circle locked (at -7.6 10.8) (size 0.4 0.4) (layers "F.Cu" "F.Paste" "F.Mask")
      (net 1 "GND") (pinfunction "GND") (pintype "passive"))
    (pad "AK8" smd circle locked (at -6.8 10.8) (size 0.4 0.4) (layers "F.Cu" "F.Paste" "F.Mask")
      (net 1 "GND") (pinfunction "GND") (pintype "passive"))
    (pad "AK9" smd circle locked (at -6 10.8) (size 0.4 0.4) (layers "F.Cu" "F.Paste" "F.Mask")
      (net 687 "/FPGA banks/PCIE_BMC_TX_C_DP") (pinfunction "HDTXP0_D0CH0") (pintype "bidirectional"))
    (pad "AK10" smd circle locked (at -5.2 10.8) (size 0.4 0.4) (layers "F.Cu" "F.Paste" "F.Mask")
      (net 686 "/FPGA banks/PCIE_BMC_TX_C_DN") (pinfunction "HDTXN0_D0CH0") (pintype "bidirectional"))
    (pad "AK11" smd circle locked (at -4.4 10.8) (size 0.4 0.4) (layers "F.Cu" "F.Paste" "F.Mask")
      (net 1 "GND") (pinfunction "GND") (pintype "passive"))
    (pad "AK12" smd circle locked (at -3.6 10.8) (size 0.4 0.4) (layers "F.Cu" "F.Paste" "F.Mask")
      (net 577 "unconnected-(U21K-HDTXP0_D0CH1-PadAK12)") (pinfunction "HDTXP0_D0CH1") (pintype "bidirectional+no_connect"))
    (pad "AK13" smd circle locked (at -2.8 10.8) (size 0.4 0.4) (layers "F.Cu" "F.Paste" "F.Mask")
      (net 578 "unconnected-(U21K-HDTXN0_D0CH1-PadAK13)") (pinfunction "HDTXN0_D0CH1") (pintype "bidirectional+no_connect"))
    (pad "AK14" smd circle locked (at -2 10.8) (size 0.4 0.4) (layers "F.Cu" "F.Paste" "F.Mask")
      (net 1 "GND") (pinfunction "GND") (pintype "passive"))
    (pad "AK15" smd circle locked (at -1.2 10.8) (size 0.4 0.4) (layers "F.Cu" "F.Paste" "F.Mask")
      (net 579 "unconnected-(U21A-RESERVED-PadAK15)") (pinfunction "RESERVED") (pintype "no_connect"))
    (pad "AK16" smd circle locked (at -0.4 10.8) (size 0.4 0.4) (layers "F.Cu" "F.Paste" "F.Mask")
      (net 580 "unconnected-(U21A-RESERVED-PadAK16)") (pinfunction "RESERVED") (pintype "no_connect"))
    (pad "AK17" smd circle locked (at 0.4 10.8) (size 0.4 0.4) (layers "F.Cu" "F.Paste" "F.Mask")
      (net 1 "GND") (pinfunction "GND") (pintype "passive"))
    (pad "AK18" smd circle locked (at 1.2 10.8) (size 0.4 0.4) (layers "F.Cu" "F.Paste" "F.Mask")
      (net 581 "unconnected-(U21L-HDTXP0_D1CH0-PadAK18)") (pinfunction "HDTXP0_D1CH0") (pintype "bidirectional+no_connect"))
    (pad "AK19" smd circle locked (at 2 10.8) (size 0.4 0.4) (layers "F.Cu" "F.Paste" "F.Mask")
      (net 582 "unconnected-(U21L-HDTXN0_D1CH0-PadAK19)") (pinfunction "HDTXN0_D1CH0") (pintype "bidirectional+no_connect"))
    (pad "AK20" smd circle locked (at 2.8 10.8) (size 0.4 0.4) (layers "F.Cu" "F.Paste" "F.Mask")
      (net 1 "GND") (pinfunction "GND") (pintype "passive"))
    (pad "AK21" smd circle locked (at 3.6 10.8) (size 0.4 0.4) (layers "F.Cu" "F.Paste" "F.Mask")
      (net 583 "unconnected-(U21L-HDTXP0_D1CH1-PadAK21)") (pinfunction "HDTXP0_D1CH1") (pintype "bidirectional+no_connect"))
    (pad "AK22" smd circle locked (at 4.4 10.8) (size 0.4 0.4) (layers "F.Cu" "F.Paste" "F.Mask")
      (net 584 "unconnected-(U21L-HDTXN0_D1CH1-PadAK22)") (pinfunction "HDTXN0_D1CH1") (pintype "bidirectional+no_connect"))
    (pad "AK23" smd circle locked (at 5.2 10.8) (size 0.4 0.4) (layers "F.Cu" "F.Paste" "F.Mask")
      (net 1 "GND") (pinfunction "GND") (pintype "passive"))
    (pad "AK24" smd circle locked (at 6 10.8) (size 0.4 0.4) (layers "F.Cu" "F.Paste" "F.Mask")
      (net 585 "unconnected-(U21A-RESERVED-PadAK24)") (pinfunction "RESERVED") (pintype "no_connect"))
    (pad "AK25" smd circle locked (at 6.8 10.8) (size 0.4 0.4) (layers "F.Cu" "F.Paste" "F.Mask")
      (net 586 "unconnected-(U21A-RESERVED-PadAK25)") (pinfunction "RESERVED") (pintype "no_connect"))
    (pad "AK26" smd circle locked (at 7.6 10.8) (size 0.4 0.4) (layers "F.Cu" "F.Paste" "F.Mask")
      (net 1 "GND") (pinfunction "GND") (pintype "passive"))
    (pad "AK28" smd circle locked (at 9.2 10.8) (size 0.4 0.4) (layers "F.Cu" "F.Paste" "F.Mask")
      (net 75 "NCSI_CRS_DV") (pinfunction "PB98B") (pintype "bidirectional"))
    (pad "AK29" smd circle locked (at 10 10.8) (size 0.4 0.4) (layers "F.Cu" "F.Paste" "F.Mask")
      (net 81 "NCSI_RXD1") (pinfunction "PB116A") (pintype "bidirectional"))
    (pad "AK30" smd circle locked (at 10.8 10.8) (size 0.4 0.4) (layers "F.Cu" "F.Paste" "F.Mask")
      (net 83 "SGPIO0_CLK") (pinfunction "PB116B") (pintype "bidirectional"))
    (pad "AK31" smd circle locked (at 11.6 10.8) (size 0.4 0.4) (layers "F.Cu" "F.Paste" "F.Mask")
      (net 87 "SGPIO1_DI") (pinfunction "PB105A") (pintype "bidirectional"))
    (pad "AK32" smd circle locked (at 12.4 10.8) (size 0.4 0.4) (layers "F.Cu" "F.Paste" "F.Mask")
      (net 93 "QSPI1_CS0_N") (pinfunction "PB101A") (pintype "bidirectional"))
    (pad "AL1" smd circle locked (at -12.4 11.6) (size 0.4 0.4) (layers "F.Cu" "F.Paste" "F.Mask")
      (net 273 "ROT_QSPI_DQ3") (pinfunction "PB9A") (pintype "bidirectional"))
    (pad "AL2" smd circle locked (at -11.6 11.6) (size 0.4 0.4) (layers "F.Cu" "F.Paste" "F.Mask")
      (net 1 "GND") (pinfunction "GND") (pintype "passive"))
    (pad "AL3" smd circle locked (at -10.8 11.6) (size 0.4 0.4) (layers "F.Cu" "F.Paste" "F.Mask")
      (net 58 "PRSNT0_N") (pinfunction "PB18A") (pintype "bidirectional"))
    (pad "AL4" smd circle locked (at -10 11.6) (size 0.4 0.4) (layers "F.Cu" "F.Paste" "F.Mask")
      (net 587 "unconnected-(U21I-CFG_1-PadAL4)") (pinfunction "CFG_1") (pintype "bidirectional+no_connect"))
    (pad "AL5" smd circle locked (at -9.2 11.6) (size 0.4 0.4) (layers "F.Cu" "F.Paste" "F.Mask")
      (net 1 "GND") (pinfunction "GND") (pintype "passive"))
    (pad "AL7" smd circle locked (at -7.6 11.6) (size 0.4 0.4) (layers "F.Cu" "F.Paste" "F.Mask")
      (net 1 "GND") (pinfunction "GND") (pintype "passive"))
    (pad "AL8" smd circle locked (at -6.8 11.6) (size 0.4 0.4) (layers "F.Cu" "F.Paste" "F.Mask")
      (net 1 "GND") (pinfunction "GND") (pintype "passive"))
    (pad "AL9" smd circle locked (at -6 11.6) (size 0.4 0.4) (layers "F.Cu" "F.Paste" "F.Mask")
      (net 1 "GND") (pinfunction "GND") (pintype "passive"))
    (pad "AL11" smd circle locked (at -4.4 11.6) (size 0.4 0.4) (layers "F.Cu" "F.Paste" "F.Mask")
      (net 1 "GND") (pinfunction "GND") (pintype "passive"))
    (pad "AL12" smd circle locked (at -3.6 11.6) (size 0.4 0.4) (layers "F.Cu" "F.Paste" "F.Mask")
      (net 1 "GND") (pinfunction "GND") (pintype "passive"))
    (pad "AL14" smd circle locked (at -2 11.6) (size 0.4 0.4) (layers "F.Cu" "F.Paste" "F.Mask")
      (net 1 "GND") (pinfunction "GND") (pintype "passive"))
    (pad "AL15" smd circle locked (at -1.2 11.6) (size 0.4 0.4) (layers "F.Cu" "F.Paste" "F.Mask")
      (net 1 "GND") (pinfunction "GND") (pintype "passive"))
    (pad "AL17" smd circle locked (at 0.4 11.6) (size 0.4 0.4) (layers "F.Cu" "F.Paste" "F.Mask")
      (net 1 "GND") (pinfunction "GND") (pintype "passive"))
    (pad "AL18" smd circle locked (at 1.2 11.6) (size 0.4 0.4) (layers "F.Cu" "F.Paste" "F.Mask")
      (net 1 "GND") (pinfunction "GND") (pintype "passive"))
    (pad "AL20" smd circle locked (at 2.8 11.6) (size 0.4 0.4) (layers "F.Cu" "F.Paste" "F.Mask")
      (net 1 "GND") (pinfunction "GND") (pintype "passive"))
    (pad "AL21" smd circle locked (at 3.6 11.6) (size 0.4 0.4) (layers "F.Cu" "F.Paste" "F.Mask")
      (net 1 "GND") (pinfunction "GND") (pintype "passive"))
    (pad "AL23" smd circle locked (at 5.2 11.6) (size 0.4 0.4) (layers "F.Cu" "F.Paste" "F.Mask")
      (net 1 "GND") (pinfunction "GND") (pintype "passive"))
    (pad "AL24" smd circle locked (at 6 11.6) (size 0.4 0.4) (layers "F.Cu" "F.Paste" "F.Mask")
      (net 1 "GND") (pinfunction "GND") (pintype "passive"))
    (pad "AL26" smd circle locked (at 7.6 11.6) (size 0.4 0.4) (layers "F.Cu" "F.Paste" "F.Mask")
      (net 1 "GND") (pinfunction "GND") (pintype "passive"))
    (pad "AL28" smd circle locked (at 9.2 11.6) (size 0.4 0.4) (layers "F.Cu" "F.Paste" "F.Mask")
      (net 76 "NCSI_TXEN") (pinfunction "PB98A") (pintype "bidirectional"))
    (pad "AL29" smd circle locked (at 10 11.6) (size 0.4 0.4) (layers "F.Cu" "F.Paste" "F.Mask")
      (net 1 "GND") (pinfunction "GND") (pintype "passive"))
    (pad "AL30" smd circle locked (at 10.8 11.6) (size 0.4 0.4) (layers "F.Cu" "F.Paste" "F.Mask")
      (net 85 "SGPIO0_LD") (pinfunction "PB103B") (pintype "bidirectional"))
    (pad "AL31" smd circle locked (at 11.6 11.6) (size 0.4 0.4) (layers "F.Cu" "F.Paste" "F.Mask")
      (net 1 "GND") (pinfunction "GND") (pintype "passive"))
    (pad "AL32" smd circle locked (at 12.4 11.6) (size 0.4 0.4) (layers "F.Cu" "F.Paste" "F.Mask")
      (net 88 "SGPIO1_LD") (pinfunction "PB107B") (pintype "bidirectional"))
    (pad "AM2" smd circle locked (at -11.6 12.4) (size 0.4 0.4) (layers "F.Cu" "F.Paste" "F.Mask")
      (net 274 "ROT_QSPI_DQ2") (pinfunction "PB9B") (pintype "bidirectional"))
    (pad "AM3" smd circle locked (at -10.8 12.4) (size 0.4 0.4) (layers "F.Cu" "F.Paste" "F.Mask")
      (net 272 "ROT_QSPI_SCK") (pinfunction "CCLK") (pintype "bidirectional"))
    (pad "AM4" smd circle locked (at -10 12.4) (size 0.4 0.4) (layers "F.Cu" "F.Paste" "F.Mask")
      (net 588 "unconnected-(U21I-CFG_0-PadAM4)") (pinfunction "CFG_0") (pintype "bidirectional+no_connect"))
    (pad "AM5" smd circle locked (at -9.2 12.4) (size 0.4 0.4) (layers "F.Cu" "F.Paste" "F.Mask")
      (net 22 "JTAG_TMS") (pinfunction "TMS") (pintype "bidirectional"))
    (pad "AM7" smd circle locked (at -7.6 12.4) (size 0.4 0.4) (layers "F.Cu" "F.Paste" "F.Mask")
      (net 1 "GND") (pinfunction "GND") (pintype "passive"))
    (pad "AM8" smd circle locked (at -6.8 12.4) (size 0.4 0.4) (layers "F.Cu" "F.Paste" "F.Mask")
      (net 107 "PCIE_BMC_RX_DP") (pinfunction "HDRXP0_D0CH0") (pintype "bidirectional"))
    (pad "AM9" smd circle locked (at -6 12.4) (size 0.4 0.4) (layers "F.Cu" "F.Paste" "F.Mask")
      (net 108 "PCIE_BMC_RX_DN") (pinfunction "HDRXN0_D0CH0") (pintype "bidirectional"))
    (pad "AM11" smd circle locked (at -4.4 12.4) (size 0.4 0.4) (layers "F.Cu" "F.Paste" "F.Mask")
      (net 589 "unconnected-(U21K-HDRXP0_D0CH1-PadAM11)") (pinfunction "HDRXP0_D0CH1") (pintype "bidirectional+no_connect"))
    (pad "AM12" smd circle locked (at -3.6 12.4) (size 0.4 0.4) (layers "F.Cu" "F.Paste" "F.Mask")
      (net 590 "unconnected-(U21K-HDRXN0_D0CH1-PadAM12)") (pinfunction "HDRXN0_D0CH1") (pintype "bidirectional+no_connect"))
    (pad "AM14" smd circle locked (at -2 12.4) (size 0.4 0.4) (layers "F.Cu" "F.Paste" "F.Mask")
      (net 103 "CLK_100M_PCIE_DP") (pinfunction "REFCLKP_D0") (pintype "bidirectional"))
    (pad "AM15" smd circle locked (at -1.2 12.4) (size 0.4 0.4) (layers "F.Cu" "F.Paste" "F.Mask")
      (net 104 "CLK_100M_PCIE_DN") (pinfunction "REFCLKN_D0") (pintype "bidirectional"))
    (pad "AM17" smd circle locked (at 0.4 12.4) (size 0.4 0.4) (layers "F.Cu" "F.Paste" "F.Mask")
      (net 591 "unconnected-(U21L-HDRXP0_D1CH0-PadAM17)") (pinfunction "HDRXP0_D1CH0") (pintype "bidirectional+no_connect"))
    (pad "AM18" smd circle locked (at 1.2 12.4) (size 0.4 0.4) (layers "F.Cu" "F.Paste" "F.Mask")
      (net 592 "unconnected-(U21L-HDRXN0_D1CH0-PadAM18)") (pinfunction "HDRXN0_D1CH0") (pintype "bidirectional+no_connect"))
    (pad "AM20" smd circle locked (at 2.8 12.4) (size 0.4 0.4) (layers "F.Cu" "F.Paste" "F.Mask")
      (net 593 "unconnected-(U21L-HDRXP0_D1CH1-PadAM20)") (pinfunction "HDRXP0_D1CH1") (pintype "bidirectional+no_connect"))
    (pad "AM21" smd circle locked (at 3.6 12.4) (size 0.4 0.4) (layers "F.Cu" "F.Paste" "F.Mask")
      (net 594 "unconnected-(U21L-HDRXN0_D1CH1-PadAM21)") (pinfunction "HDRXN0_D1CH1") (pintype "bidirectional+no_connect"))
    (pad "AM23" smd circle locked (at 5.2 12.4) (size 0.4 0.4) (layers "F.Cu" "F.Paste" "F.Mask")
      (net 595 "unconnected-(U21L-REFCLKP_D1-PadAM23)") (pinfunction "REFCLKP_D1") (pintype "bidirectional+no_connect"))
    (pad "AM24" smd circle locked (at 6 12.4) (size 0.4 0.4) (layers "F.Cu" "F.Paste" "F.Mask")
      (net 596 "unconnected-(U21L-REFCLKN_D1-PadAM24)") (pinfunction "REFCLKN_D1") (pintype "bidirectional+no_connect"))
    (pad "AM26" smd circle locked (at 7.6 12.4) (size 0.4 0.4) (layers "F.Cu" "F.Paste" "F.Mask")
      (net 1 "GND") (pinfunction "GND") (pintype "passive"))
    (pad "AM28" smd circle locked (at 9.2 12.4) (size 0.4 0.4) (layers "F.Cu" "F.Paste" "F.Mask")
      (net 77 "NCSI_TXD0") (pinfunction "PB96A") (pintype "bidirectional"))
    (pad "AM29" smd circle locked (at 10 12.4) (size 0.4 0.4) (layers "F.Cu" "F.Paste" "F.Mask")
      (net 82 "SGPIO0_DO") (pinfunction "PB96B") (pintype "bidirectional"))
    (pad "AM30" smd circle locked (at 10.8 12.4) (size 0.4 0.4) (layers "F.Cu" "F.Paste" "F.Mask")
      (net 84 "SGPIO0_DI") (pinfunction "PB103A") (pintype "bidirectional"))
    (pad "AM31" smd circle locked (at 11.6 12.4) (size 0.4 0.4) (layers "F.Cu" "F.Paste" "F.Mask")
      (net 277 "SGPIO1_CLK") (pinfunction "PB107A") (pintype "bidirectional"))
    (pad "B1" smd circle locked (at -12.4 -11.6) (size 0.4 0.4) (layers "F.Cu" "F.Paste" "F.Mask")
      (net 666 "ROT_GPIO1") (pinfunction "PL17A") (pintype "bidirectional"))
    (pad "B2" smd circle locked (at -11.6 -11.6) (size 0.4 0.4) (layers "F.Cu" "F.Paste" "F.Mask")
      (net 1 "GND") (pinfunction "GND") (pintype "passive"))
    (pad "B3" smd circle locked (at -10.8 -11.6) (size 0.4 0.4) (layers "F.Cu" "F.Paste" "F.Mask")
      (net 597 "unconnected-(U21B-PT4A-PadB3)") (pinfunction "PT4A") (pintype "bidirectional+no_connect"))
    (pad "B4" smd circle locked (at -10 -11.6) (size 0.4 0.4) (layers "F.Cu" "F.Paste" "F.Mask")
      (net 598 "unconnected-(U21B-PT4B-PadB4)") (pinfunction "PT4B") (pintype "bidirectional+no_connect"))
    (pad "B5" smd circle locked (at -9.2 -11.6) (size 0.4 0.4) (layers "F.Cu" "F.Paste" "F.Mask")
      (net 1 "GND") (pinfunction "GND") (pintype "passive"))
    (pad "B7" smd circle locked (at -7.6 -11.6) (size 0.4 0.4) (layers "F.Cu" "F.Paste" "F.Mask")
      (net 599 "unconnected-(U21B-PT13A-PadB7)") (pinfunction "PT13A") (pintype "bidirectional+no_connect"))
    (pad "B8" smd circle locked (at -6.8 -11.6) (size 0.4 0.4) (layers "F.Cu" "F.Paste" "F.Mask")
      (net 199 "RGMII_TXD2") (pinfunction "PT20A") (pintype "bidirectional"))
    (pad "B9" smd circle locked (at -6 -11.6) (size 0.4 0.4) (layers "F.Cu" "F.Paste" "F.Mask")
      (net 1 "GND") (pinfunction "GND") (pintype "passive"))
    (pad "B10" smd circle locked (at -5.2 -11.6) (size 0.4 0.4) (layers "F.Cu" "F.Paste" "F.Mask")
      (net 600 "unconnected-(U21B-PT31A-PadB10)") (pinfunction "PT31A") (pintype "bidirectional+no_connect"))
    (pad "B11" smd circle locked (at -4.4 -11.6) (size 0.4 0.4) (layers "F.Cu" "F.Paste" "F.Mask")
      (net 601 "unconnected-(U21B-PT38A-PadB11)") (pinfunction "PT38A") (pintype "bidirectional+no_connect"))
    (pad "B13" smd circle locked (at -2.8 -11.6) (size 0.4 0.4) (layers "F.Cu" "F.Paste" "F.Mask")
      (net 1 "GND") (pinfunction "GND") (pintype "passive"))
    (pad "B14" smd circle locked (at -2 -11.6) (size 0.4 0.4) (layers "F.Cu" "F.Paste" "F.Mask")
      (net 602 "unconnected-(U21B-PT49A-PadB14)") (pinfunction "PT49A") (pintype "bidirectional+no_connect"))
    (pad "B15" smd circle locked (at -1.2 -11.6) (size 0.4 0.4) (layers "F.Cu" "F.Paste" "F.Mask")
      (net 1 "GND") (pinfunction "GND") (pintype "passive"))
    (pad "B16" smd circle locked (at -0.4 -11.6) (size 0.4 0.4) (layers "F.Cu" "F.Paste" "F.Mask")
      (net 161 "ETH_MDC") (pinfunction "PT60A") (pintype "bidirectional"))
    (pad "B17" smd circle locked (at 0.4 -11.6) (size 0.4 0.4) (layers "F.Cu" "F.Paste" "F.Mask")
      (net 160 "RGMII_REF_CLK") (pinfunction "PT63B") (pintype "bidirectional"))
    (pad "B18" smd circle locked (at 1.2 -11.6) (size 0.4 0.4) (layers "F.Cu" "F.Paste" "F.Mask")
      (net 1 "GND") (pinfunction "GND") (pintype "passive"))
    (pad "B19" smd circle locked (at 2 -11.6) (size 0.4 0.4) (layers "F.Cu" "F.Paste" "F.Mask")
      (net 293 "USR_LED0") (pinfunction "PT76B") (pintype "bidirectional"))
    (pad "B20" smd circle locked (at 2.8 -11.6) (size 0.4 0.4) (layers "F.Cu" "F.Paste" "F.Mask")
      (net 1 "GND") (pinfunction "GND") (pintype "passive"))
    (pad "B22" smd circle locked (at 4.4 -11.6) (size 0.4 0.4) (layers "F.Cu" "F.Paste" "F.Mask")
      (net 47 "I2C[10]_SDA") (pinfunction "PT87B") (pintype "bidirectional"))
    (pad "B23" smd circle locked (at 5.2 -11.6) (size 0.4 0.4) (layers "F.Cu" "F.Paste" "F.Mask")
      (net 48 "I2C[10]_SCL") (pinfunction "PT94B") (pintype "bidirectional"))
    (pad "B24" smd circle locked (at 6 -11.6) (size 0.4 0.4) (layers "F.Cu" "F.Paste" "F.Mask")
      (net 1 "GND") (pinfunction "GND") (pintype "passive"))
    (pad "B25" smd circle locked (at 6.8 -11.6) (size 0.4 0.4) (layers "F.Cu" "F.Paste" "F.Mask")
      (net 51 "I2C[8]_SCL") (pinfunction "PT105B") (pintype "bidirectional"))
    (pad "B26" smd circle locked (at 7.6 -11.6) (size 0.4 0.4) (layers "F.Cu" "F.Paste" "F.Mask")
      (net 52 "I2C[8]_SDA") (pinfunction "PT112B") (pintype "bidirectional"))
    (pad "B28" smd circle locked (at 9.2 -11.6) (size 0.4 0.4) (layers "F.Cu" "F.Paste" "F.Mask")
      (net 1 "GND") (pinfunction "GND") (pintype "passive"))
    (pad "B29" smd circle locked (at 10 -11.6) (size 0.4 0.4) (layers "F.Cu" "F.Paste" "F.Mask")
      (net 33 "I2C[4]_SDA") (pinfunction "PT121A") (pintype "bidirectional"))
    (pad "B30" smd circle locked (at 10.8 -11.6) (size 0.4 0.4) (layers "F.Cu" "F.Paste" "F.Mask")
      (net 23 "I2C[5]_SDA") (pinfunction "PT121B") (pintype "bidirectional"))
    (pad "B31" smd circle locked (at 11.6 -11.6) (size 0.4 0.4) (layers "F.Cu" "F.Paste" "F.Mask")
      (net 1 "GND") (pinfunction "GND") (pintype "passive"))
    (pad "B32" smd circle locked (at 12.4 -11.6) (size 0.4 0.4) (layers "F.Cu" "F.Paste" "F.Mask")
      (net 603 "unconnected-(U21D-PR17A-PadB32)") (pinfunction "PR17A") (pintype "bidirectional+no_connect"))
    (pad "C1" smd circle locked (at -12.4 -10.8) (size 0.4 0.4) (layers "F.Cu" "F.Paste" "F.Mask")
      (net 409 "ROT_RDY\\ROT_GPIO0") (pinfunction "PL20C") (pintype "bidirectional"))
    (pad "C2" smd circle locked (at -11.6 -10.8) (size 0.4 0.4) (layers "F.Cu" "F.Paste" "F.Mask")
      (net 665 "ROT_GPIO2") (pinfunction "PL17B") (pintype "bidirectional"))
    (pad "C3" smd circle locked (at -10.8 -10.8) (size 0.4 0.4) (layers "F.Cu" "F.Paste" "F.Mask")
      (net 604 "unconnected-(U21H-PL11D-PadC3)") (pinfunction "PL11D") (pintype "bidirectional+no_connect"))
    (pad "C4" smd circle locked (at -10 -10.8) (size 0.4 0.4) (layers "F.Cu" "F.Paste" "F.Mask")
      (net 605 "unconnected-(U21H-PL11C-PadC4)") (pinfunction "PL11C") (pintype "bidirectional+no_connect"))
    (pad "C5" smd circle locked (at -9.2 -10.8) (size 0.4 0.4) (layers "F.Cu" "F.Paste" "F.Mask")
      (net 606 "unconnected-(U21H-PL11A-PadC5)") (pinfunction "PL11A") (pintype "bidirectional+no_connect"))
    (pad "C7" smd circle locked (at -7.6 -10.8) (size 0.4 0.4) (layers "F.Cu" "F.Paste" "F.Mask")
      (net 607 "unconnected-(U21B-PT11B-PadC7)") (pinfunction "PT11B") (pintype "bidirectional+no_connect"))
    (pad "C8" smd circle locked (at -6.8 -10.8) (size 0.4 0.4) (layers "F.Cu" "F.Paste" "F.Mask")
      (net 157 "RGMII_RXD3") (pinfunction "PT18B") (pintype "bidirectional"))
    (pad "C9" smd circle locked (at -6 -10.8) (size 0.4 0.4) (layers "F.Cu" "F.Paste" "F.Mask")
      (net 608 "unconnected-(U21B-PT24A-PadC9)") (pinfunction "PT24A") (pintype "bidirectional+no_connect"))
    (pad "C10" smd circle locked (at -5.2 -10.8) (size 0.4 0.4) (layers "F.Cu" "F.Paste" "F.Mask")
      (net 609 "unconnected-(U21B-PT29B-PadC10)") (pinfunction "PT29B") (pintype "bidirectional+no_connect"))
    (pad "C11" smd circle locked (at -4.4 -10.8) (size 0.4 0.4) (layers "F.Cu" "F.Paste" "F.Mask")
      (net 610 "unconnected-(U21B-PT36B-PadC11)") (pinfunction "PT36B") (pintype "bidirectional+no_connect"))
    (pad "C13" smd circle locked (at -2.8 -10.8) (size 0.4 0.4) (layers "F.Cu" "F.Paste" "F.Mask")
      (net 611 "unconnected-(U21B-PT42A-PadC13)") (pinfunction "PT42A") (pintype "bidirectional+no_connect"))
    (pad "C14" smd circle locked (at -2 -10.8) (size 0.4 0.4) (layers "F.Cu" "F.Paste" "F.Mask")
      (net 612 "unconnected-(U21B-PT47B-PadC14)") (pinfunction "PT47B") (pintype "bidirectional+no_connect"))
    (pad "C15" smd circle locked (at -1.2 -10.8) (size 0.4 0.4) (layers "F.Cu" "F.Paste" "F.Mask")
      (net 613 "unconnected-(U21B-PT54A-PadC15)") (pinfunction "PT54A") (pintype "bidirectional+no_connect"))
    (pad "C16" smd circle locked (at -0.4 -10.8) (size 0.4 0.4) (layers "F.Cu" "F.Paste" "F.Mask")
      (net 158 "RGMII_RX_DV") (pinfunction "PT58B") (pintype "bidirectional"))
    (pad "C17" smd circle locked (at 0.4 -10.8) (size 0.4 0.4) (layers "F.Cu" "F.Paste" "F.Mask")
      (net 200 "RGMII_TX_CLK") (pinfunction "PT65A") (pintype "bidirectional"))
    (pad "C18" smd circle locked (at 1.2 -10.8) (size 0.4 0.4) (layers "F.Cu" "F.Paste" "F.Mask")
      (net 614 "unconnected-(U21C-PT71B-PadC18)") (pinfunction "PT71B") (pintype "bidirectional+no_connect"))
    (pad "C19" smd circle locked (at 2 -10.8) (size 0.4 0.4) (layers "F.Cu" "F.Paste" "F.Mask")
      (net 167 "I3C[0]_SDA_3V3") (pinfunction "PT78A") (pintype "bidirectional"))
    (pad "C20" smd circle locked (at 2.8 -10.8) (size 0.4 0.4) (layers "F.Cu" "F.Paste" "F.Mask")
      (net 173 "I3C[3]_SDA_3V3") (pinfunction "PT83B") (pintype "bidirectional"))
    (pad "C22" smd circle locked (at 4.4 -10.8) (size 0.4 0.4) (layers "F.Cu" "F.Paste" "F.Mask")
      (net 294 "USR_LED1") (pinfunction "PT89A") (pintype "bidirectional"))
    (pad "C23" smd circle locked (at 5.2 -10.8) (size 0.4 0.4) (layers "F.Cu" "F.Paste" "F.Mask")
      (net 43 "I2C[9]_SCL") (pinfunction "PT96A") (pintype "bidirectional"))
    (pad "C24" smd circle locked (at 6 -10.8) (size 0.4 0.4) (layers "F.Cu" "F.Paste" "F.Mask")
      (net 44 "I2C[9]_SDA") (pinfunction "PT101B") (pintype "bidirectional"))
    (pad "C25" smd circle locked (at 6.8 -10.8) (size 0.4 0.4) (layers "F.Cu" "F.Paste" "F.Mask")
      (net 30 "I2C[7]_SDA") (pinfunction "PT107A") (pintype "bidirectional"))
    (pad "C26" smd circle locked (at 7.6 -10.8) (size 0.4 0.4) (layers "F.Cu" "F.Paste" "F.Mask")
      (net 36 "I2C[4]_SCL") (pinfunction "PT114A") (pintype "bidirectional"))
    (pad "C28" smd circle locked (at 9.2 -10.8) (size 0.4 0.4) (layers "F.Cu" "F.Paste" "F.Mask")
      (net 615 "unconnected-(U21D-PR11A-PadC28)") (pinfunction "PR11A") (pintype "bidirectional+no_connect"))
    (pad "C29" smd circle locked (at 10 -10.8) (size 0.4 0.4) (layers "F.Cu" "F.Paste" "F.Mask")
      (net 616 "unconnected-(U21D-PR11C-PadC29)") (pinfunction "PR11C") (pintype "bidirectional+no_connect"))
    (pad "C30" smd circle locked (at 10.8 -10.8) (size 0.4 0.4) (layers "F.Cu" "F.Paste" "F.Mask")
      (net 1 "GND") (pinfunction "PR11D") (pintype "bidirectional"))
    (pad "C31" smd circle locked (at 11.6 -10.8) (size 0.4 0.4) (layers "F.Cu" "F.Paste" "F.Mask")
      (net 617 "unconnected-(U21D-PR17B-PadC31)") (pinfunction "PR17B") (pintype "bidirectional+no_connect"))
    (pad "C32" smd circle locked (at 12.4 -10.8) (size 0.4 0.4) (layers "F.Cu" "F.Paste" "F.Mask")
      (net 618 "unconnected-(U21D-PR20C-PadC32)") (pinfunction "PR20C") (pintype "bidirectional+no_connect"))
    (pad "D1" smd circle locked (at -12.4 -10) (size 0.4 0.4) (layers "F.Cu" "F.Paste" "F.Mask")
      (net 659 "ROT_MISO") (pinfunction "PL20D") (pintype "bidirectional"))
    (pad "D2" smd circle locked (at -11.6 -10) (size 0.4 0.4) (layers "F.Cu" "F.Paste" "F.Mask")
      (net 661 "ROT_SS") (pinfunction "PL17D") (pintype "bidirectional"))
    (pad "D3" smd circle locked (at -10.8 -10) (size 0.4 0.4) (layers "F.Cu" "F.Paste" "F.Mask")
      (net 619 "unconnected-(U21H-PL17C-PadD3)") (pinfunction "PL17C") (pintype "bidirectional+no_connect"))
    (pad "D4" smd circle locked (at -10 -10) (size 0.4 0.4) (layers "F.Cu" "F.Paste" "F.Mask")
      (net 620 "unconnected-(U21H-PL14A-PadD4)") (pinfunction "PL14A") (pintype "bidirectional+no_connect"))
    (pad "D5" smd circle locked (at -9.2 -10) (size 0.4 0.4) (layers "F.Cu" "F.Paste" "F.Mask")
      (net 621 "unconnected-(U21H-PL11B-PadD5)") (pinfunction "PL11B") (pintype "bidirectional+no_connect"))
    (pad "D7" smd circle locked (at -7.6 -10) (size 0.4 0.4) (layers "F.Cu" "F.Paste" "F.Mask")
      (net 622 "unconnected-(U21B-PT11A-PadD7)") (pinfunction "PT11A") (pintype "bidirectional+no_connect"))
    (pad "D8" smd circle locked (at -6.8 -10) (size 0.4 0.4) (layers "F.Cu" "F.Paste" "F.Mask")
      (net 201 "RGMII_TXD3") (pinfunction "PT18A") (pintype "bidirectional"))
    (pad "D9" smd circle locked (at -6 -10) (size 0.4 0.4) (layers "F.Cu" "F.Paste" "F.Mask")
      (net 623 "unconnected-(U21B-PT22B-PadD9)") (pinfunction "PT22B") (pintype "bidirectional+no_connect"))
    (pad "D10" smd circle locked (at -5.2 -10) (size 0.4 0.4) (layers "F.Cu" "F.Paste" "F.Mask")
      (net 624 "unconnected-(U21B-PT29A-PadD10)") (pinfunction "PT29A") (pintype "bidirectional+no_connect"))
    (pad "D11" smd circle locked (at -4.4 -10) (size 0.4 0.4) (layers "F.Cu" "F.Paste" "F.Mask")
      (net 625 "unconnected-(U21B-PT36A-PadD11)") (pinfunction "PT36A") (pintype "bidirectional+no_connect"))
    (pad "D13" smd circle locked (at -2.8 -10) (size 0.4 0.4) (layers "F.Cu" "F.Paste" "F.Mask")
      (net 626 "unconnected-(U21B-PT40B-PadD13)") (pinfunction "PT40B") (pintype "bidirectional+no_connect"))
    (pad "D14" smd circle locked (at -2 -10) (size 0.4 0.4) (layers "F.Cu" "F.Paste" "F.Mask")
      (net 627 "unconnected-(U21B-PT47A-PadD14)") (pinfunction "PT47A") (pintype "bidirectional+no_connect"))
    (pad "D15" smd circle locked (at -1.2 -10) (size 0.4 0.4) (layers "F.Cu" "F.Paste" "F.Mask")
      (net 296 "RGMII_TX_EN") (pinfunction "PT51B") (pintype "bidirectional"))
    (pad "D16" smd circle locked (at -0.4 -10) (size 0.4 0.4) (layers "F.Cu" "F.Paste" "F.Mask")
      (net 155 "RGMII_RXD1") (pinfunction "PT58A") (pintype "bidirectional"))
    (pad "D17" smd circle locked (at 0.4 -10) (size 0.4 0.4) (layers "F.Cu" "F.Paste" "F.Mask")
      (net 162 "ETH_MDIO") (pinfunction "PT65B") (pintype "bidirectional"))
    (pad "D18" smd circle locked (at 1.2 -10) (size 0.4 0.4) (layers "F.Cu" "F.Paste" "F.Mask")
      (net 163 "ETH_~{RESET}") (pinfunction "PT74A") (pintype "bidirectional"))
    (pad "D19" smd circle locked (at 2 -10) (size 0.4 0.4) (layers "F.Cu" "F.Paste" "F.Mask")
      (net 169 "I3C[1]_SDA_3V3") (pinfunction "PT78B") (pintype "bidirectional"))
    (pad "D20" smd circle locked (at 2.8 -10) (size 0.4 0.4) (layers "F.Cu" "F.Paste" "F.Mask")
      (net 174 "I3C[3]_SCL_3V3") (pinfunction "PT85A") (pintype "bidirectional"))
    (pad "D22" smd circle locked (at 4.4 -10) (size 0.4 0.4) (layers "F.Cu" "F.Paste" "F.Mask")
      (net 32 "I2C[2]_SCL") (pinfunction "PT89B") (pintype "bidirectional"))
    (pad "D23" smd circle locked (at 5.2 -10) (size 0.4 0.4) (layers "F.Cu" "F.Paste" "F.Mask")
      (net 31 "I2C[2]_SDA") (pinfunction "PT96B") (pintype "bidirectional"))
    (pad "D24" smd circle locked (at 6 -10) (size 0.4 0.4) (layers "F.Cu" "F.Paste" "F.Mask")
      (net 27 "I2C[3]_SDA") (pinfunction "PT103A") (pintype "bidirectional"))
    (pad "D25" smd circle locked (at 6.8 -10) (size 0.4 0.4) (layers "F.Cu" "F.Paste" "F.Mask")
      (net 25 "I2C[3]_SCL") (pinfunction "PT107B") (pintype "bidirectional"))
    (pad "D26" smd circle locked (at 7.6 -10) (size 0.4 0.4) (layers "F.Cu" "F.Paste" "F.Mask")
      (net 38 "I2C[0]_SDA") (pinfunction "PT114B") (pintype "bidirectional"))
    (pad "D28" smd circle locked (at 9.2 -10) (size 0.4 0.4) (layers "F.Cu" "F.Paste" "F.Mask")
      (net 628 "unconnected-(U21D-PR11B-PadD28)") (pinfunction "PR11B") (pintype "bidirectional+no_connect"))
    (pad "D29" smd circle locked (at 10 -10) (size 0.4 0.4) (layers "F.Cu" "F.Paste" "F.Mask")
      (net 629 "unconnected-(U21D-PR14A-PadD29)") (pinfunction "PR14A") (pintype "bidirectional+no_connect"))
    (pad "D30" smd circle locked (at 10.8 -10) (size 0.4 0.4) (layers "F.Cu" "F.Paste" "F.Mask")
      (net 630 "unconnected-(U21D-PR17C-PadD30)") (pinfunction "PR17C") (pintype "bidirectional+no_connect"))
    (pad "D31" smd circle locked (at 11.6 -10) (size 0.4 0.4) (layers "F.Cu" "F.Paste" "F.Mask")
      (net 631 "unconnected-(U21D-PR17D-PadD31)") (pinfunction "PR17D") (pintype "bidirectional+no_connect"))
    (pad "D32" smd circle locked (at 12.4 -10) (size 0.4 0.4) (layers "F.Cu" "F.Paste" "F.Mask")
      (net 632 "unconnected-(U21D-PR20D-PadD32)") (pinfunction "PR20D") (pintype "bidirectional+no_connect"))
    (pad "E1" smd circle locked (at -12.4 -9.2) (size 0.4 0.4) (layers "F.Cu" "F.Paste" "F.Mask")
      (net 664 "ROT_SCLK") (pinfunction "PL23B") (pintype "bidirectional"))
    (pad "E2" smd circle locked (at -11.6 -9.2) (size 0.4 0.4) (layers "F.Cu" "F.Paste" "F.Mask")
      (net 1 "GND") (pinfunction "GND") (pintype "passive"))
    (pad "E3" smd circle locked (at -10.8 -9.2) (size 0.4 0.4) (layers "F.Cu" "F.Paste" "F.Mask")
      (net 660 "ROT_MOSI") (pinfunction "PL20B") (pintype "bidirectional"))
    (pad "E4" smd circle locked (at -10 -9.2) (size 0.4 0.4) (layers "F.Cu" "F.Paste" "F.Mask")
      (net 633 "unconnected-(U21H-PL14B-PadE4)") (pinfunction "PL14B") (pintype "bidirectional+no_connect"))
    (pad "E5" smd circle locked (at -9.2 -9.2) (size 0.4 0.4) (layers "F.Cu" "F.Paste" "F.Mask")
      (net 1 "GND") (pinfunction "GND") (pintype "passive"))
    (pad "E7" smd circle locked (at -7.6 -9.2) (size 0.4 0.4) (layers "F.Cu" "F.Paste" "F.Mask")
      (net 634 "unconnected-(U21A-NC-PadE7)") (pinfunction "NC") (pintype "no_connect"))
    (pad "E8" smd circle locked (at -6.8 -9.2) (size 0.4 0.4) (layers "F.Cu" "F.Paste" "F.Mask")
      (net 635 "unconnected-(U21B-PT15B-PadE8)") (pinfunction "PT15B") (pintype "bidirectional+no_connect"))
    (pad "E9" smd circle locked (at -6 -9.2) (size 0.4 0.4) (layers "F.Cu" "F.Paste" "F.Mask")
      (net 1 "GND") (pinfunction "GND") (pintype "passive"))
    (pad "E10" smd circle locked (at -5.2 -9.2) (size 0.4 0.4) (layers "F.Cu" "F.Paste" "F.Mask")
      (net 636 "unconnected-(U21B-PT27B-PadE10)") (pinfunction "PT27B") (pintype "bidirectional+no_connect"))
    (pad "E11" smd circle locked (at -4.4 -9.2) (size 0.4 0.4) (layers "F.Cu" "F.Paste" "F.Mask")
      (net 637 "unconnected-(U21B-PT33B-PadE11)") (pinfunction "PT33B") (pintype "bidirectional+no_connect"))
    (pad "E13" smd circle locked (at -2.8 -9.2) (size 0.4 0.4) (layers "F.Cu" "F.Paste" "F.Mask")
      (net 1 "GND") (pinfunction "GND") (pintype "passive"))
    (pad "E14" smd circle locked (at -2 -9.2) (size 0.4 0.4) (layers "F.Cu" "F.Paste" "F.Mask")
      (net 638 "unconnected-(U21B-PT45B-PadE14)") (pinfunction "PT45B") (pintype "bidirectional+no_connect"))
    (pad "E15" smd circle locked (at -1.2 -9.2) (size 0.4 0.4) (layers "F.Cu" "F.Paste" "F.Mask")
      (net 1 "GND") (pinfunction "GND") (pintype "passive"))
    (pad "E16" smd circle locked (at -0.4 -9.2) (size 0.4 0.4) (layers "F.Cu" "F.Paste" "F.Mask")
      (net 156 "RGMII_RXD2") (pinfunction "PT56B") (pintype "bidirectional"))
    (pad "E17" smd circle locked (at 0.4 -9.2) (size 0.4 0.4) (layers "F.Cu" "F.Paste" "F.Mask")
      (net 639 "unconnected-(U21C-PT69A-PadE17)") (pinfunction "PT69A") (pintype "bidirectional+no_connect"))
    (pad "E18" smd circle locked (at 1.2 -9.2) (size 0.4 0.4) (layers "F.Cu" "F.Paste" "F.Mask")
      (net 1 "GND") (pinfunction "GND") (pintype "passive"))
    (pad "E19" smd circle locked (at 2 -9.2) (size 0.4 0.4) (layers "F.Cu" "F.Paste" "F.Mask")
      (net 172 "I3C[2]_SCL_3V3") (pinfunction "PT80A") (pintype "bidirectional"))
    (pad "E20" smd circle locked (at 2.8 -9.2) (size 0.4 0.4) (layers "F.Cu" "F.Paste" "F.Mask")
      (net 1 "GND") (pinfunction "GND") (pintype "passive"))
    (pad "E22" smd circle locked (at 4.4 -9.2) (size 0.4 0.4) (layers "F.Cu" "F.Paste" "F.Mask")
      (net 28 "I2C[1]_SCL") (pinfunction "PT92A") (pintype "bidirectional"))
    (pad "E23" smd circle locked (at 5.2 -9.2) (size 0.4 0.4) (layers "F.Cu" "F.Paste" "F.Mask")
      (net 29 "I2C[1]_SDA") (pinfunction "PT98A") (pintype "bidirectional"))
    (pad "E24" smd circle locked (at 6 -9.2) (size 0.4 0.4) (layers "F.Cu" "F.Paste" "F.Mask")
      (net 1 "GND") (pinfunction "GND") (pintype "passive"))
    (pad "E25" smd circle locked (at 6.8 -9.2) (size 0.4 0.4) (layers "F.Cu" "F.Paste" "F.Mask")
      (net 37 "I2C[0]_SCL") (pinfunction "PT110A") (pintype "bidirectional"))
    (pad "E26" smd circle locked (at 7.6 -9.2) (size 0.4 0.4) (layers "F.Cu" "F.Paste" "F.Mask")
      (net 640 "unconnected-(U21A-NC-PadE26)") (pinfunction "NC") (pintype "no_connect"))
    (pad "E28" smd circle locked (at 9.2 -9.2) (size 0.4 0.4) (layers "F.Cu" "F.Paste" "F.Mask")
      (net 1 "GND") (pinfunction "GND") (pintype "passive"))
    (pad "E29" smd circle locked (at 10 -9.2) (size 0.4 0.4) (layers "F.Cu" "F.Paste" "F.Mask")
      (net 641 "unconnected-(U21D-PR14B-PadE29)") (pinfunction "PR14B") (pintype "bidirectional+no_connect"))
    (pad "E30" smd circle locked (at 10.8 -9.2) (size 0.4 0.4) (layers "F.Cu" "F.Paste" "F.Mask")
      (net 642 "unconnected-(U21D-PR20B-PadE30)") (pinfunction "PR20B") (pintype "bidirectional+no_connect"))
    (pad "E31" smd circle locked (at 11.6 -9.2) (size 0.4 0.4) (layers "F.Cu" "F.Paste" "F.Mask")
      (net 1 "GND") (pinfunction "GND") (pintype "passive"))
    (pad "E32" smd circle locked (at 12.4 -9.2) (size 0.4 0.4) (layers "F.Cu" "F.Paste" "F.Mask")
      (net 643 "unconnected-(U21D-PR23B-PadE32)") (pinfunction "PR23B") (pintype "bidirectional+no_connect"))
    (pad "F1" smd circle locked (at -12.4 -8.4) (size 0.4 0.4) (layers "F.Cu" "F.Paste" "F.Mask")
      (net 662 "ROT_TX") (pinfunction "PL23C") (pintype "bidirectional"))
    (pad "F2" smd circle locked (at -11.6 -8.4) (size 0.4 0.4) (layers "F.Cu" "F.Paste" "F.Mask")
      (net 663 "ROT_RX") (pinfunction "PL23A") (pintype "bidirectional"))
    (pad "F3" smd circle locked (at -10.8 -8.4) (size 0.4 0.4) (layers "F.Cu" "F.Paste" "F.Mask")
      (net 644 "unconnected-(U21H-PL20A-PadF3)") (pinfunction "PL20A") (pintype "bidirectional+no_connect"))
    (pad "F4" smd circle locked (at -10 -8.4) (size 0.4 0.4) (layers "F.Cu" "F.Paste" "F.Mask")
      (net 645 "unconnected-(U21H-PL14C-PadF4)") (pinfunction "PL14C") (pintype "bidirectional+no_connect"))
    (pad "F5" smd circle locked (at -9.2 -8.4) (size 0.4 0.4) (layers "F.Cu" "F.Paste" "F.Mask")
      (net 646 "unconnected-(U21H-PL14D-PadF5)") (pinfunction "PL14D") (pintype "bidirectional+no_connect"))
    (pad "F8" smd circle locked (at -6.8 -8.4) (size 0.4 0.4) (layers "F.Cu" "F.Paste" "F.Mask")
      (net 647 "unconnected-(U21B-PT15A-PadF8)") (pinfunction "PT15A") (pintype "bidirectional+no_connect"))
    (pad "F9" smd circle locked (at -6 -8.4) (size 0.4 0.4) (layers "F.Cu" "F.Paste" "F.Mask")
      (net 648 "unconnected-(U21B-PT22A-PadF9)") (pinfunction "PT22A") (pintype "bidirectional+no_connect"))
    (pad "F10" smd circle locked (at -5.2 -8.4) (size 0.4 0.4) (layers "F.Cu" "F.Paste" "F.Mask")
      (net 649 "unconnected-(U21B-PT27A-PadF10)") (pinfunction "PT27A") (pintype "bidirectional+no_connect"))
    (pad "F11" smd circle locked (at -4.4 -8.4) (size 0.4 0.4) (layers "F.Cu" "F.Paste" "F.Mask")
      (net 650 "unconnected-(U21B-PT33A-PadF11)") (pinfunction "PT33A") (pintype "bidirectional+no_connect"))
    (pad "F13" smd circle locked (at -2.8 -8.4) (size 0.4 0.4) (layers "F.Cu" "F.Paste" "F.Mask")
      (net 651 "unconnected-(U21B-PT40A-PadF13)") (pinfunction "PT40A") (pintype "bidirectional+no_connect"))
    (pad "F14" smd circle locked (at -2 -8.4) (size 0.4 0.4) (layers "F.Cu" "F.Paste" "F.Mask")
      (net 652 "unconnected-(U21B-PT45A-PadF14)") (pinfunction "PT45A") (pintype "bidirectional+no_connect"))
    (pad "F15" smd circle locked (at -1.2 -8.4) (size 0.4 0.4) (layers "F.Cu" "F.Paste" "F.Mask")
      (net 653 "unconnected-(U21B-PT51A-PadF15)") (pinfunction "PT51A") (pintype "bidirectional+no_connect"))
    (pad "F16" smd circle locked (at -0.4 -8.4) (size 0.4 0.4) (layers "F.Cu" "F.Paste" "F.Mask")
      (net 654 "unconnected-(U21B-PT56A-PadF16)") (pinfunction "PT56A") (pintype "bidirectional+no_connect"))
    (pad "F17" smd circle locked (at 0.4 -8.4) (size 0.4 0.4) (layers "F.Cu" "F.Paste" "F.Mask")
      (net 655 "unconnected-(U21C-PT69B-PadF17)") (pinfunction "PT69B") (pintype "bidirectional+no_connect"))
    (pad "F18" smd circle locked (at 1.2 -8.4) (size 0.4 0.4) (layers "F.Cu" "F.Paste" "F.Mask")
      (net 656 "unconnected-(U21C-PT74B-PadF18)") (pinfunction "PT74B") (pintype "bidirectional+no_connect"))
    (pad "F19" smd circle locked (at 2 -8.4) (size 0.4 0.4) (layers "F.Cu" "F.Paste" "F.Mask")
      (net 171 "I3C[2]_SDA_3V3") (pinfunction "PT80B") (pintype "bidirectional"))
    (pad "F20" smd circle locked (at 2.8 -8.4) (size 0.4 0.4) (layers "F.Cu" "F.Paste" "F.Mask")
      (net 170 "I3C[1]_SCL_3V3") (pinfunction "PT85B") (pintype "bidirectional"))
    (pad "F22" smd circle locked (at 4.4 -8.4) (size 0.4 0.4) (layers "F.Cu" "F.Paste" "F.Mask")
      (net 46 "UART1_SCM_TX") (pinfunction "PT92B") (pintype "bidirectional"))
    (pad "F23" smd circle locked (at 5.2 -8.4) (size 0.4 0.4) (layers "F.Cu" "F.Paste" "F.Mask")
      (net 39 "UART1_SCM_RX") (pinfunction "PT98B") (pintype "bidirectional"))
    (pad "F24" smd circle locked (at 6 -8.4) (size 0.4 0.4) (layers "F.Cu" "F.Paste" "F.Mask")
      (net 41 "UART0_SCM_TX") (pinfunction "PT103B") (pintype "bidirectional"))
    (pad "F25" smd circle locked (at 6.8 -8.4) (size 0.4 0.4) (layers "F.Cu" "F.Paste" "F.Mask")
      (net 45 "UART0_SCM_RX") (pinfunction "PT110B") (pintype "bidirectional"))
    (pad "F28" smd circle locked (at 9.2 -8.4) (size 0.4 0.4) (layers "F.Cu" "F.Paste" "F.Mask")
      (net 658 "unconnected-(U21D-PR14D-PadF28)") (pinfunction "PR14D") (pintype "bidirectional+no_connect"))
    (pad "F29" smd circle locked (at 10 -8.4) (size 0.4 0.4) (layers "F.Cu" "F.Paste" "F.Mask")
      (net 667 "unconnected-(U21D-PR14C-PadF29)") (pinfunction "PR14C") (pintype "bidirectional+no_connect"))
    (pad "F30" smd circle locked (at 10.8 -8.4) (size 0.4 0.4) (layers "F.Cu" "F.Paste" "F.Mask")
      (net 668 "unconnected-(U21D-PR20A-PadF30)") (pinfunction "PR20A") (pintype "bidirectional+no_connect"))
    (pad "F31" smd circle locked (at 11.6 -8.4) (size 0.4 0.4) (layers "F.Cu" "F.Paste" "F.Mask")
      (net 669 "unconnected-(U21D-PR23A-PadF31)") (pinfunction "PR23A") (pintype "bidirectional+no_connect"))
    (pad "F32" smd circle locked (at 12.4 -8.4) (size 0.4 0.4) (layers "F.Cu" "F.Paste" "F.Mask")
      (net 670 "unconnected-(U21D-PR23C-PadF32)") (pinfunction "PR23C") (pintype "bidirectional+no_connect"))
    (pad "G9" smd circle locked (at -6 -7.6) (size 0.4 0.4) (layers "F.Cu" "F.Paste" "F.Mask")
      (net 671 "unconnected-(U21A-NC-PadG9)") (pinfunction "NC") (pintype "no_connect"))
    (pad "G10" smd circle locked (at -5.2 -7.6) (size 0.4 0.4) (layers "F.Cu" "F.Paste" "F.Mask")
      (net 673 "unconnected-(U21A-NC-PadG10)") (pinfunction "NC") (pintype "no_connect"))
    (pad "G11" smd circle locked (at -4.4 -7.6) (size 0.4 0.4) (layers "F.Cu" "F.Paste" "F.Mask")
      (net 674 "unconnected-(U21A-NC-PadG11)") (pinfunction "NC") (pintype "no_connect"))
    (pad "G14" smd circle locked (at -2 -7.6) (size 0.4 0.4) (layers "F.Cu" "F.Paste" "F.Mask")
      (net 675 "unconnected-(U21A-NC-PadG14)") (pinfunction "NC") (pintype "no_connect"))
    (pad "G15" smd circle locked (at -1.2 -7.6) (size 0.4 0.4) (layers "F.Cu" "F.Paste" "F.Mask")
      (net 677 "unconnected-(U21A-NC-PadG15)") (pinfunction "NC") (pintype "no_connect"))
    (pad "G16" smd circle locked (at -0.4 -7.6) (size 0.4 0.4) (layers "F.Cu" "F.Paste" "F.Mask")
      (net 682 "unconnected-(U21A-NC-PadG16)") (pinfunction "NC") (pintype "no_connect"))
    (pad "G17" smd circle locked (at 0.4 -7.6) (size 0.4 0.4) (layers "F.Cu" "F.Paste" "F.Mask")
      (net 683 "unconnected-(U21A-NC-PadG17)") (pinfunction "NC") (pintype "no_connect"))
    (pad "G18" smd circle locked (at 1.2 -7.6) (size 0.4 0.4) (layers "F.Cu" "F.Paste" "F.Mask")
      (net 684 "unconnected-(U21A-NC-PadG18)") (pinfunction "NC") (pintype "no_connect"))
    (pad "G19" smd circle locked (at 2 -7.6) (size 0.4 0.4) (layers "F.Cu" "F.Paste" "F.Mask")
      (net 685 "unconnected-(U21A-NC-PadG19)") (pinfunction "NC") (pintype "no_connect"))
    (pad "G22" smd circle locked (at 4.4 -7.6) (size 0.4 0.4) (layers "F.Cu" "F.Paste" "F.Mask")
      (net 704 "unconnected-(U21A-NC-PadG22)") (pinfunction "NC") (pintype "no_connect"))
    (pad "G23" smd circle locked (at 5.2 -7.6) (size 0.4 0.4) (layers "F.Cu" "F.Paste" "F.Mask")
      (net 705 "unconnected-(U21A-NC-PadG23)") (pinfunction "NC") (pintype "no_connect"))
    (pad "G24" smd circle locked (at 6 -7.6) (size 0.4 0.4) (layers "F.Cu" "F.Paste" "F.Mask")
      (net 706 "unconnected-(U21A-NC-PadG24)") (pinfunction "NC") (pintype "no_connect"))
    (pad "H1" smd circle locked (at -12.4 -6.8) (size 0.4 0.4) (layers "F.Cu" "F.Paste" "F.Mask")
      (net 707 "unconnected-(U21H-PL23D-PadH1)") (pinfunction "PL23D") (pintype "bidirectional+no_connect"))
    (pad "H2" smd circle locked (at -11.6 -6.8) (size 0.4 0.4) (layers "F.Cu" "F.Paste" "F.Mask")
      (net 708 "unconnected-(U21H-PL26A-PadH2)") (pinfunction "PL26A") (pintype "bidirectional+no_connect"))
    (pad "H3" smd circle locked (at -10.8 -6.8) (size 0.4 0.4) (layers "F.Cu" "F.Paste" "F.Mask")
      (net 709 "unconnected-(U21H-PL26B-PadH3)") (pinfunction "PL26B") (pintype "bidirectional+no_connect"))
    (pad "H4" smd circle locked (at -10 -6.8) (size 0.4 0.4) (layers "F.Cu" "F.Paste" "F.Mask")
      (net 710 "unconnected-(U21A-NC-PadH4)") (pinfunction "NC") (pintype "no_connect"))
    (pad "H5" smd circle locked (at -9.2 -6.8) (size 0.4 0.4) (layers "F.Cu" "F.Paste" "F.Mask")
      (net 711 "unconnected-(U21H-PL35B-PadH5)") (pinfunction "PL35B") (pintype "bidirectional+no_connect"))
    (pad "H6" smd circle locked (at -8.4 -6.8) (size 0.4 0.4) (layers "F.Cu" "F.Paste" "F.Mask")
      (net 712 "unconnected-(U21H-PL35A-PadH6)") (pinfunction "PL35A") (pintype "bidirectional+no_connect"))
    (pad "H27" smd circle locked (at 8.4 -6.8) (size 0.4 0.4) (layers "F.Cu" "F.Paste" "F.Mask")
      (net 713 "unconnected-(U21D-PR35A-PadH27)") (pinfunction "PR35A") (pintype "bidirectional+no_connect"))
    (pad "H28" smd circle locked (at 9.2 -6.8) (size 0.4 0.4) (layers "F.Cu" "F.Paste" "F.Mask")
      (net 714 "unconnected-(U21D-PR35B-PadH28)") (pinfunction "PR35B") (pintype "bidirectional+no_connect"))
    (pad "H29" smd circle locked (at 10 -6.8) (size 0.4 0.4) (layers "F.Cu" "F.Paste" "F.Mask")
      (net 715 "unconnected-(U21A-NC-PadH29)") (pinfunction "NC") (pintype "no_connect"))
    (pad "H30" smd circle locked (at 10.8 -6.8) (size 0.4 0.4) (layers "F.Cu" "F.Paste" "F.Mask")
      (net 62 "ESPI_RESET_N") (pinfunction "PR26B") (pintype "bidirectional"))
    (pad "H31" smd circle locked (at 11.6 -6.8) (size 0.4 0.4) (layers "F.Cu" "F.Paste" "F.Mask")
      (net 66 "ESPI_IO3") (pinfunction "PR26A") (pintype "bidirectional"))
    (pad "H32" smd circle locked (at 12.4 -6.8) (size 0.4 0.4) (layers "F.Cu" "F.Paste" "F.Mask")
      (net 67 "ESPI_CS1_N") (pinfunction "PR23D") (pintype "bidirectional"))
    (pad "J1" smd circle locked (at -12.4 -6) (size 0.4 0.4) (layers "F.Cu" "F.Paste" "F.Mask")
      (net 716 "unconnected-(U21H-PL29B-PadJ1)") (pinfunction "PL29B") (pintype "bidirectional+no_connect"))
    (pad "J2" smd circle locked (at -11.6 -6) (size 0.4 0.4) (layers "F.Cu" "F.Paste" "F.Mask")
      (net 1 "GND") (pinfunction "GND") (pintype "passive"))
    (pad "J3" smd circle locked (at -10.8 -6) (size 0.4 0.4) (layers "F.Cu" "F.Paste" "F.Mask")
      (net 717 "unconnected-(U21H-PL26C-PadJ3)") (pinfunction "PL26C") (pintype "bidirectional+no_connect"))
    (pad "J4" smd circle locked (at -10 -6) (size 0.4 0.4) (layers "F.Cu" "F.Paste" "F.Mask")
      (net 718 "unconnected-(U21H-PL32C-PadJ4)") (pinfunction "PL32C") (pintype "bidirectional+no_connect"))
    (pad "J5" smd circle locked (at -9.2 -6) (size 0.4 0.4) (layers "F.Cu" "F.Paste" "F.Mask")
      (net 1 "GND") (pinfunction "GND") (pintype "passive"))
    (pad "J6" smd circle locked (at -8.4 -6) (size 0.4 0.4) (layers "F.Cu" "F.Paste" "F.Mask")
      (net 286 "MMC_DAT7") (pinfunction "PL35D") (pintype "bidirectional"))
    (pad "J7" smd circle locked (at -7.6 -6) (size 0.4 0.4) (layers "F.Cu" "F.Paste" "F.Mask")
      (net 287 "MMC_CMD") (pinfunction "PL35C") (pintype "bidirectional"))
    (pad "J26" smd circle locked (at 7.6 -6) (size 0.4 0.4) (layers "F.Cu" "F.Paste" "F.Mask")
      (net 719 "unconnected-(U21D-PR35C-PadJ26)") (pinfunction "PR35C") (pintype "bidirectional+no_connect"))
    (pad "J27" smd circle locked (at 8.4 -6) (size 0.4 0.4) (layers "F.Cu" "F.Paste" "F.Mask")
      (net 720 "unconnected-(U21D-PR35D-PadJ27)") (pinfunction "PR35D") (pintype "bidirectional+no_connect"))
    (pad "J28" smd circle locked (at 9.2 -6) (size 0.4 0.4) (layers "F.Cu" "F.Paste" "F.Mask")
      (net 1 "GND") (pinfunction "GND") (pintype "passive"))
    (pad "J29" smd circle locked (at 10 -6) (size 0.4 0.4) (layers "F.Cu" "F.Paste" "F.Mask")
      (net 721 "unconnected-(U21D-PR32C-PadJ29)") (pinfunction "PR32C") (pintype "bidirectional+no_connect"))
    (pad "J30" smd circle locked (at 10.8 -6) (size 0.4 0.4) (layers "F.Cu" "F.Paste" "F.Mask")
      (net 722 "unconnected-(U21D-PR26C-PadJ30)") (pinfunction "PR26C") (pintype "bidirectional+no_connect"))
    (pad "J31" smd circle locked (at 11.6 -6) (size 0.4 0.4) (layers "F.Cu" "F.Paste" "F.Mask")
      (net 1 "GND") (pinfunction "GND") (pintype "passive"))
    (pad "J32" smd circle locked (at 12.4 -6) (size 0.4 0.4) (layers "F.Cu" "F.Paste" "F.Mask")
      (net 65 "ESPI_IO2") (pinfunction "PR29B") (pintype "bidirectional"))
    (pad "K1" smd circle locked (at -12.4 -5.2) (size 0.4 0.4) (layers "F.Cu" "F.Paste" "F.Mask")
      (net 723 "unconnected-(U21H-PL29C-PadK1)") (pinfunction "PL29C") (pintype "bidirectional+no_connect"))
    (pad "K2" smd circle locked (at -11.6 -5.2) (size 0.4 0.4) (layers "F.Cu" "F.Paste" "F.Mask")
      (net 724 "unconnected-(U21H-PL29A-PadK2)") (pinfunction "PL29A") (pintype "bidirectional+no_connect"))
    (pad "K3" smd circle locked (at -10.8 -5.2) (size 0.4 0.4) (layers "F.Cu" "F.Paste" "F.Mask")
      (net 725 "unconnected-(U21H-PL26D-PadK3)") (pinfunction "PL26D") (pintype "bidirectional+no_connect"))
    (pad "K4" smd circle locked (at -10 -5.2) (size 0.4 0.4) (layers "F.Cu" "F.Paste" "F.Mask")
      (net 726 "unconnected-(U21H-PL32D-PadK4)") (pinfunction "PL32D") (pintype "bidirectional+no_connect"))
    (pad "K5" smd circle locked (at -9.2 -5.2) (size 0.4 0.4) (layers "F.Cu" "F.Paste" "F.Mask")
      (net 284 "MMC_DAT5") (pinfunction "PL38C") (pintype "bidirectional"))
    (pad "K6" smd circle locked (at -8.4 -5.2) (size 0.4 0.4) (layers "F.Cu" "F.Paste" "F.Mask")
      (net 285 "MMC_DAT6") (pinfunction "PL38A") (pintype "bidirectional"))
    (pad "K7" smd circle locked (at -7.6 -5.2) (size 0.4 0.4) (layers "F.Cu" "F.Paste" "F.Mask")
      (net 283 "MMC_DAT4") (pinfunction "PL38B") (pintype "bidirectional"))
    (pad "K10" smd circle locked (at -5.2 -5.2) (size 0.4 0.4) (layers "F.Cu" "F.Paste" "F.Mask")
      (net 1 "GND") (pinfunction "GND") (pintype "passive"))
    (pad "K11" smd circle locked (at -4.4 -5.2) (size 0.4 0.4) (layers "F.Cu" "F.Paste" "F.Mask")
      (net 1 "GND") (pinfunction "GND") (pintype "passive"))
    (pad "K12" smd circle locked (at -3.6 -5.2) (size 0.4 0.4) (layers "F.Cu" "F.Paste" "F.Mask")
      (net 2 "VCC3V3") (pinfunction "VCCIO0") (pintype "power_in"))
    (pad "K13" smd circle locked (at -2.8 -5.2) (size 0.4 0.4) (layers "F.Cu" "F.Paste" "F.Mask")
      (net 304 "/FPGA power supply/VCCAUX") (pinfunction "VCCAUX") (pintype "passive"))
    (pad "K14" smd circle locked (at -2 -5.2) (size 0.4 0.4) (layers "F.Cu" "F.Paste" "F.Mask")
      (net 2 "VCC3V3") (pinfunction "VCCIO0") (pintype "passive"))
    (pad "K15" smd circle locked (at -1.2 -5.2) (size 0.4 0.4) (layers "F.Cu" "F.Paste" "F.Mask")
      (net 2 "VCC3V3") (pinfunction "VCCIO0") (pintype "passive"))
    (pad "K16" smd circle locked (at -0.4 -5.2) (size 0.4 0.4) (layers "F.Cu" "F.Paste" "F.Mask")
      (net 2 "VCC3V3") (pinfunction "VCCIO0") (pintype "passive"))
    (pad "K17" smd circle locked (at 0.4 -5.2) (size 0.4 0.4) (layers "F.Cu" "F.Paste" "F.Mask")
      (net 2 "VCC3V3") (pinfunction "VCCIO1") (pintype "power_in"))
    (pad "K18" smd circle locked (at 1.2 -5.2) (size 0.4 0.4) (layers "F.Cu" "F.Paste" "F.Mask")
      (net 2 "VCC3V3") (pinfunction "VCCIO1") (pintype "passive"))
    (pad "K19" smd circle locked (at 2 -5.2) (size 0.4 0.4) (layers "F.Cu" "F.Paste" "F.Mask")
      (net 2 "VCC3V3") (pinfunction "VCCIO1") (pintype "passive"))
    (pad "K20" smd circle locked (at 2.8 -5.2) (size 0.4 0.4) (layers "F.Cu" "F.Paste" "F.Mask")
      (net 304 "/FPGA power supply/VCCAUX") (pinfunction "VCCAUX") (pintype "passive"))
    (pad "K21" smd circle locked (at 3.6 -5.2) (size 0.4 0.4) (layers "F.Cu" "F.Paste" "F.Mask")
      (net 2 "VCC3V3") (pinfunction "VCCIO1") (pintype "passive"))
    (pad "K22" smd circle locked (at 4.4 -5.2) (size 0.4 0.4) (layers "F.Cu" "F.Paste" "F.Mask")
      (net 1 "GND") (pinfunction "GND") (pintype "passive"))
    (pad "K23" smd circle locked (at 5.2 -5.2) (size 0.4 0.4) (layers "F.Cu" "F.Paste" "F.Mask")
      (net 1 "GND") (pinfunction "GND") (pintype "passive"))
    (pad "K26" smd circle locked (at 7.6 -5.2) (size 0.4 0.4) (layers "F.Cu" "F.Paste" "F.Mask")
      (net 727 "unconnected-(U21D-PR38B-PadK26)") (pinfunction "PR38B") (pintype "bidirectional+no_connect"))
    (pad "K27" smd circle locked (at 8.4 -5.2) (size 0.4 0.4) (layers "F.Cu" "F.Paste" "F.Mask")
      (net 728 "unconnected-(U21D-PR38A-PadK27)") (pinfunction "PR38A") (pintype "bidirectional+no_connect"))
    (pad "K28" smd circle locked (at 9.2 -5.2) (size 0.4 0.4) (layers "F.Cu" "F.Paste" "F.Mask")
      (net 729 "unconnected-(U21D-PR38C-PadK28)") (pinfunction "PR38C") (pintype "bidirectional+no_connect"))
    (pad "K29" smd circle locked (at 10 -5.2) (size 0.4 0.4) (layers "F.Cu" "F.Paste" "F.Mask")
      (net 730 "unconnected-(U21D-PR32D-PadK29)") (pinfunction "PR32D") (pintype "bidirectional+no_connect"))
    (pad "K30" smd circle locked (at 10.8 -5.2) (size 0.4 0.4) (layers "F.Cu" "F.Paste" "F.Mask")
      (net 61 "ESPI_ALERT_N") (pinfunction "PR26D") (pintype "bidirectional"))
    (pad "K31" smd circle locked (at 11.6 -5.2) (size 0.4 0.4) (layers "F.Cu" "F.Paste" "F.Mask")
      (net 64 "ESPI_IO1") (pinfunction "PR29A") (pintype "bidirectional"))
    (pad "K32" smd circle locked (at 12.4 -5.2) (size 0.4 0.4) (layers "F.Cu" "F.Paste" "F.Mask")
      (net 63 "ESPI_IO0") (pinfunction "PR29C") (pintype "bidirectional"))
    (pad "L1" smd circle locked (at -12.4 -4.4) (size 0.4 0.4) (layers "F.Cu" "F.Paste" "F.Mask")
      (net 731 "unconnected-(U21H-PL29D-PadL1)") (pinfunction "PL29D") (pintype "bidirectional+no_connect"))
    (pad "L2" smd circle locked (at -11.6 -4.4) (size 0.4 0.4) (layers "F.Cu" "F.Paste" "F.Mask")
      (net 732 "unconnected-(U21H-PL32A-PadL2)") (pinfunction "PL32A") (pintype "bidirectional+no_connect"))
    (pad "L3" smd circle locked (at -10.8 -4.4) (size 0.4 0.4) (layers "F.Cu" "F.Paste" "F.Mask")
      (net 377 "MMC_RSTN") (pinfunction "PL32B") (pintype "bidirectional"))
    (pad "L4" smd circle locked (at -10 -4.4) (size 0.4 0.4) (layers "F.Cu" "F.Paste" "F.Mask")
      (net 282 "MMC_DAT3") (pinfunction "PL38D") (pintype "bidirectional"))
    (pad "L5" smd circle locked (at -9.2 -4.4) (size 0.4 0.4) (layers "F.Cu" "F.Paste" "F.Mask")
      (net 733 "unconnected-(U21A-NC-PadL5)") (pinfunction "NC") (pintype "no_connect"))
    (pad "L6" smd circle locked (at -8.4 -4.4) (size 0.4 0.4) (layers "F.Cu" "F.Paste" "F.Mask")
      (net 734 "unconnected-(U21H-PL41D-PadL6)") (pinfunction "PL41D") (pintype "bidirectional+no_connect"))
    (pad "L7" smd circle locked (at -7.6 -4.4) (size 0.4 0.4) (layers "F.Cu" "F.Paste" "F.Mask")
      (net 280 "MMC_DAT1") (pinfunction "PL41C") (pintype "bidirectional"))
    (pad "L10" smd circle locked (at -5.2 -4.4) (size 0.4 0.4) (layers "F.Cu" "F.Paste" "F.Mask")
      (net 1 "GND") (pinfunction "GND") (pintype "passive"))
    (pad "L11" smd circle locked (at -4.4 -4.4) (size 0.4 0.4) (layers "F.Cu" "F.Paste" "F.Mask")
      (net 1 "GND") (pinfunction "GND") (pintype "passive"))
    (pad "L12" smd circle locked (at -3.6 -4.4) (size 0.4 0.4) (layers "F.Cu" "F.Paste" "F.Mask")
      (net 1 "GND") (pinfunction "GND") (pintype "passive"))
    (pad "L13" smd circle locked (at -2.8 -4.4) (size 0.4 0.4) (layers "F.Cu" "F.Paste" "F.Mask")
      (net 1 "GND") (pinfunction "GND") (pintype "passive"))
    (pad "L14" smd circle locked (at -2 -4.4) (size 0.4 0.4) (layers "F.Cu" "F.Paste" "F.Mask")
      (net 1 "GND") (pinfunction "GND") (pintype "passive"))
    (pad "L15" smd circle locked (at -1.2 -4.4) (size 0.4 0.4) (layers "F.Cu" "F.Paste" "F.Mask")
      (net 1 "GND") (pinfunction "GND") (pintype "passive"))
    (pad "L16" smd circle locked (at -0.4 -4.4) (size 0.4 0.4) (layers "F.Cu" "F.Paste" "F.Mask")
      (net 1 "GND") (pinfunction "GND") (pintype "passive"))
    (pad "L17" smd circle locked (at 0.4 -4.4) (size 0.4 0.4) (layers "F.Cu" "F.Paste" "F.Mask")
      (net 1 "GND") (pinfunction "GND") (pintype "passive"))
    (pad "L18" smd circle locked (at 1.2 -4.4) (size 0.4 0.4) (layers "F.Cu" "F.Paste" "F.Mask")
      (net 1 "GND") (pinfunction "GND") (pintype "passive"))
    (pad "L19" smd circle locked (at 2 -4.4) (size 0.4 0.4) (layers "F.Cu" "F.Paste" "F.Mask")
      (net 1 "GND") (pinfunction "GND") (pintype "passive"))
    (pad "L20" smd circle locked (at 2.8 -4.4) (size 0.4 0.4) (layers "F.Cu" "F.Paste" "F.Mask")
      (net 1 "GND") (pinfunction "GND") (pintype "passive"))
    (pad "L21" smd circle locked (at 3.6 -4.4) (size 0.4 0.4) (layers "F.Cu" "F.Paste" "F.Mask")
      (net 1 "GND") (pinfunction "GND") (pintype "passive"))
    (pad "L22" smd circle locked (at 4.4 -4.4) (size 0.4 0.4) (layers "F.Cu" "F.Paste" "F.Mask")
      (net 1 "GND") (pinfunction "GND") (pintype "passive"))
    (pad "L23" smd circle locked (at 5.2 -4.4) (size 0.4 0.4) (layers "F.Cu" "F.Paste" "F.Mask")
      (net 1 "GND") (pinfunction "GND") (pintype "passive"))
    (pad "L26" smd circle locked (at 7.6 -4.4) (size 0.4 0.4) (layers "F.Cu" "F.Paste" "F.Mask")
      (net 735 "unconnected-(U21D-PR41C-PadL26)") (pinfunction "PR41C") (pintype "bidirectional+no_connect"))
    (pad "L27" smd circle locked (at 8.4 -4.4) (size 0.4 0.4) (layers "F.Cu" "F.Paste" "F.Mask")
      (net 736 "unconnected-(U21D-PR41D-PadL27)") (pinfunction "PR41D") (pintype "bidirectional+no_connect"))
    (pad "L28" smd circle locked (at 9.2 -4.4) (size 0.4 0.4) (layers "F.Cu" "F.Paste" "F.Mask")
      (net 737 "unconnected-(U21A-NC-PadL28)") (pinfunction "NC") (pintype "no_connect"))
    (pad "L29" smd circle locked (at 10 -4.4) (size 0.4 0.4) (layers "F.Cu" "F.Paste" "F.Mask")
      (net 738 "unconnected-(U21D-PR38D-PadL29)") (pinfunction "PR38D") (pintype "bidirectional+no_connect"))
    (pad "L30" smd circle locked (at 10.8 -4.4) (size 0.4 0.4) (layers "F.Cu" "F.Paste" "F.Mask")
      (net 739 "unconnected-(U21D-PR32B-PadL30)") (pinfunction "PR32B") (pintype "bidirectional+no_connect"))
    (pad "L31" smd circle locked (at 11.6 -4.4) (size 0.4 0.4) (layers "F.Cu" "F.Paste" "F.Mask")
      (net 59 "ESPI_CLK") (pinfunction "PR32A") (pintype "bidirectional"))
    (pad "L32" smd circle locked (at 12.4 -4.4) (size 0.4 0.4) (layers "F.Cu" "F.Paste" "F.Mask")
      (net 60 "ESPI_CS0_N") (pinfunction "PR29D") (pintype "bidirectional"))
    (pad "M10" smd circle locked (at -5.2 -3.6) (size 0.4 0.4) (layers "F.Cu" "F.Paste" "F.Mask")
      (net 2 "VCC3V3") (pinfunction "VCCIO7") (pintype "power_in"))
    (pad "M11" smd circle locked (at -4.4 -3.6) (size 0.4 0.4) (layers "F.Cu" "F.Paste" "F.Mask")
      (net 1 "GND") (pinfunction "GND") (pintype "passive"))
    (pad "M12" smd circle locked (at -3.6 -3.6) (size 0.4 0.4) (layers "F.Cu" "F.Paste" "F.Mask")
      (net 211 "VCC1V2") (pinfunction "VCC") (pintype "passive"))
    (pad "M13" smd circle locked (at -2.8 -3.6) (size 0.4 0.4) (layers "F.Cu" "F.Paste" "F.Mask")
      (net 211 "VCC1V2") (pinfunction "VCC") (pintype "passive"))
    (pad "M14" smd circle locked (at -2 -3.6) (size 0.4 0.4) (layers "F.Cu" "F.Paste" "F.Mask")
      (net 211 "VCC1V2") (pinfunction "VCC") (pintype "passive"))
    (pad "M15" smd circle locked (at -1.2 -3.6) (size 0.4 0.4) (layers "F.Cu" "F.Paste" "F.Mask")
      (net 211 "VCC1V2") (pinfunction "VCC") (pintype "passive"))
    (pad "M16" smd circle locked (at -0.4 -3.6) (size 0.4 0.4) (layers "F.Cu" "F.Paste" "F.Mask")
      (net 211 "VCC1V2") (pinfunction "VCC") (pintype "passive"))
    (pad "M17" smd circle locked (at 0.4 -3.6) (size 0.4 0.4) (layers "F.Cu" "F.Paste" "F.Mask")
      (net 211 "VCC1V2") (pinfunction "VCC") (pintype "passive"))
    (pad "M18" smd circle locked (at 1.2 -3.6) (size 0.4 0.4) (layers "F.Cu" "F.Paste" "F.Mask")
      (net 211 "VCC1V2") (pinfunction "VCC") (pintype "passive"))
    (pad "M19" smd circle locked (at 2 -3.6) (size 0.4 0.4) (layers "F.Cu" "F.Paste" "F.Mask")
      (net 211 "VCC1V2") (pinfunction "VCC") (pintype "passive"))
    (pad "M20" smd circle locked (at 2.8 -3.6) (size 0.4 0.4) (layers "F.Cu" "F.Paste" "F.Mask")
      (net 211 "VCC1V2") (pinfunction "VCC") (pintype "passive"))
    (pad "M21" smd circle locked (at 3.6 -3.6) (size 0.4 0.4) (layers "F.Cu" "F.Paste" "F.Mask")
      (net 211 "VCC1V2") (pinfunction "VCC") (pintype "passive"))
    (pad "M22" smd circle locked (at 4.4 -3.6) (size 0.4 0.4) (layers "F.Cu" "F.Paste" "F.Mask")
      (net 1 "GND") (pinfunction "GND") (pintype "passive"))
    (pad "M23" smd circle locked (at 5.2 -3.6) (size 0.4 0.4) (layers "F.Cu" "F.Paste" "F.Mask")
      (net 218 "VCC1V8") (pinfunction "VCCIO2") (pintype "power_in"))
    (pad "N1" smd circle locked (at -12.4 -2.8) (size 0.4 0.4) (layers "F.Cu" "F.Paste" "F.Mask")
      (net 740 "unconnected-(U21G-PL62A-PadN1)") (pinfunction "PL62A") (pintype "bidirectional+no_connect"))
    (pad "N2" smd circle locked (at -11.6 -2.8) (size 0.4 0.4) (layers "F.Cu" "F.Paste" "F.Mask")
      (net 1 "GND") (pinfunction "GND") (pintype "passive"))
    (pad "N3" smd circle locked (at -10.8 -2.8) (size 0.4 0.4) (layers "F.Cu" "F.Paste" "F.Mask")
      (net 281 "MMC_DAT2") (pinfunction "PL41A") (pintype "bidirectional"))
    (pad "N4" smd circle locked (at -10 -2.8) (size 0.4 0.4) (layers "F.Cu" "F.Paste" "F.Mask")
      (net 279 "MMC_DAT0") (pinfunction "PL41B") (pintype "bidirectional"))
    (pad "N5" smd circle locked (at -9.2 -2.8) (size 0.4 0.4) (layers "F.Cu" "F.Paste" "F.Mask")
      (net 1 "GND") (pinfunction "GND") (pintype "passive"))
    (pad "N6" smd circle locked (at -8.4 -2.8) (size 0.4 0.4) (layers "F.Cu" "F.Paste" "F.Mask")
      (net 367 "GCLK100") (pinfunction "PL44A") (pintype "bidirectional"))
    (pad "N7" smd circle locked (at -7.6 -2.8) (size 0.4 0.4) (layers "F.Cu" "F.Paste" "F.Mask")
      (net 741 "unconnected-(U21H-PL44B-PadN7)") (pinfunction "PL44B") (pintype "bidirectional+no_connect"))
    (pad "N10" smd circle locked (at -5.2 -2.8) (size 0.4 0.4) (layers "F.Cu" "F.Paste" "F.Mask")
      (net 304 "/FPGA power supply/VCCAUX") (pinfunction "VCCAUX") (pintype "passive"))
    (pad "N11" smd circle locked (at -4.4 -2.8) (size 0.4 0.4) (layers "F.Cu" "F.Paste" "F.Mask")
      (net 1 "GND") (pinfunction "GND") (pintype "passive"))
    (pad "N12" smd circle locked (at -3.6 -2.8) (size 0.4 0.4) (layers "F.Cu" "F.Paste" "F.Mask")
      (net 211 "VCC1V2") (pinfunction "VCC") (pintype "passive"))
    (pad "N13" smd circle locked (at -2.8 -2.8) (size 0.4 0.4) (layers "F.Cu" "F.Paste" "F.Mask")
      (net 1 "GND") (pinfunction "GND") (pintype "passive"))
    (pad "N14" smd circle locked (at -2 -2.8) (size 0.4 0.4) (layers "F.Cu" "F.Paste" "F.Mask")
      (net 1 "GND") (pinfunction "GND") (pintype "passive"))
    (pad "N15" smd circle locked (at -1.2 -2.8) (size 0.4 0.4) (layers "F.Cu" "F.Paste" "F.Mask")
      (net 1 "GND") (pinfunction "GND") (pintype "passive"))
    (pad "N16" smd circle locked (at -0.4 -2.8) (size 0.4 0.4) (layers "F.Cu" "F.Paste" "F.Mask")
      (net 1 "GND") (pinfunction "GND") (pintype "passive"))
    (pad "N17" smd circle locked (at 0.4 -2.8) (size 0.4 0.4) (layers "F.Cu" "F.Paste" "F.Mask")
      (net 1 "GND") (pinfunction "GND") (pintype "passive"))
    (pad "N18" smd circle locked (at 1.2 -2.8) (size 0.4 0.4) (layers "F.Cu" "F.Paste" "F.Mask")
      (net 1 "GND") (pinfunction "GND") (pintype "passive"))
    (pad "N19" smd circle locked (at 2 -2.8) (size 0.4 0.4) (layers "F.Cu" "F.Paste" "F.Mask")
      (net 1 "GND") (pinfunction "GND") (pintype "passive"))
    (pad "N20" smd circle locked (at 2.8 -2.8) (size 0.4 0.4) (layers "F.Cu" "F.Paste" "F.Mask")
      (net 1 "GND") (pinfunction "GND") (pintype "passive"))
    (pad "N21" smd circle locked (at 3.6 -2.8) (size 0.4 0.4) (layers "F.Cu" "F.Paste" "F.Mask")
      (net 211 "VCC1V2") (pinfunction "VCC") (pintype "passive"))
    (pad "N22" smd circle locked (at 4.4 -2.8) (size 0.4 0.4) (layers "F.Cu" "F.Paste" "F.Mask")
      (net 1 "GND") (pinfunction "GND") (pintype "passive"))
    (pad "N23" smd circle locked (at 5.2 -2.8) (size 0.4 0.4) (layers "F.Cu" "F.Paste" "F.Mask")
      (net 304 "/FPGA power supply/VCCAUX") (pinfunction "VCCAUX") (pintype "passive"))
    (pad "N26" smd circle locked (at 7.6 -2.8) (size 0.4 0.4) (layers "F.Cu" "F.Paste" "F.Mask")
      (net 742 "unconnected-(U21D-PR44B-PadN26)") (pinfunction "PR44B") (pintype "bidirectional+no_connect"))
    (pad "N27" smd circle locked (at 8.4 -2.8) (size 0.4 0.4) (layers "F.Cu" "F.Paste" "F.Mask")
      (net 743 "unconnected-(U21D-PR44A-PadN27)") (pinfunction "PR44A") (pintype "bidirectional+no_connect"))
    (pad "N28" smd circle locked (at 9.2 -2.8) (size 0.4 0.4) (layers "F.Cu" "F.Paste" "F.Mask")
      (net 1 "GND") (pinfunction "GND") (pintype "passive"))
    (pad "N29" smd circle locked (at 10 -2.8) (size 0.4 0.4) (layers "F.Cu" "F.Paste" "F.Mask")
      (net 744 "unconnected-(U21D-PR41B-PadN29)") (pinfunction "PR41B") (pintype "bidirectional+no_connect"))
    (pad "N30" smd circle locked (at 10.8 -2.8) (size 0.4 0.4) (layers "F.Cu" "F.Paste" "F.Mask")
      (net 745 "unconnected-(U21D-PR41A-PadN30)") (pinfunction "PR41A") (pintype "bidirectional+no_connect"))
    (pad "N31" smd circle locked (at 11.6 -2.8) (size 0.4 0.4) (layers "F.Cu" "F.Paste" "F.Mask")
      (net 1 "GND") (pinfunction "GND") (pintype "passive"))
    (pad "N32" smd circle locked (at 12.4 -2.8) (size 0.4 0.4) (layers "F.Cu" "F.Paste" "F.Mask")
      (net 331 "ULPI1_NXT") (pinfunction "PR62A") (pintype "bidirectional"))
    (pad "P1" smd circle locked (at -12.4 -2) (size 0.4 0.4) (layers "F.Cu" "F.Paste" "F.Mask")
      (net 746 "unconnected-(U21G-PL62B-PadP1)") (pinfunction "PL62B") (pintype "bidirectional+no_connect"))
    (pad "P2" smd circle locked (at -11.6 -2) (size 0.4 0.4) (layers "F.Cu" "F.Paste" "F.Mask")
      (net 747 "unconnected-(U21G-PL59A-PadP2)") (pinfunction "PL59A") (pintype "bidirectional+no_connect"))
    (pad "P3" smd circle locked (at -10.8 -2) (size 0.4 0.4) (layers "F.Cu" "F.Paste" "F.Mask")
      (net 748 "unconnected-(U21G-PL59B-PadP3)") (pinfunction "PL59B") (pintype "bidirectional+no_connect"))
    (pad "P4" smd circle locked (at -10 -2) (size 0.4 0.4) (layers "F.Cu" "F.Paste" "F.Mask")
      (net 262 "DDR3_CLK-") (pinfunction "PL47B") (pintype "bidirectional"))
    (pad "P5" smd circle locked (at -9.2 -2) (size 0.4 0.4) (layers "F.Cu" "F.Paste" "F.Mask")
      (net 261 "DDR3_CLK+") (pinfunction "PL47A") (pintype "bidirectional"))
    (pad "P6" smd circle locked (at -8.4 -2) (size 0.4 0.4) (layers "F.Cu" "F.Paste" "F.Mask")
      (net 288 "MMC_CLK") (pinfunction "PL44C") (pintype "bidirectional"))
    (pad "P7" smd circle locked (at -7.6 -2) (size 0.4 0.4) (layers "F.Cu" "F.Paste" "F.Mask")
      (net 749 "unconnected-(U21H-PL44D-PadP7)") (pinfunction "PL44D") (pintype "bidirectional+no_connect"))
    (pad "P10" smd circle locked (at -5.2 -2) (size 0.4 0.4) (layers "F.Cu" "F.Paste" "F.Mask")
      (net 2 "VCC3V3") (pinfunction "VCCIO7") (pintype "passive"))
    (pad "P11" smd circle locked (at -4.4 -2) (size 0.4 0.4) (layers "F.Cu" "F.Paste" "F.Mask")
      (net 1 "GND") (pinfunction "GND") (pintype "passive"))
    (pad "P12" smd circle locked (at -3.6 -2) (size 0.4 0.4) (layers "F.Cu" "F.Paste" "F.Mask")
      (net 211 "VCC1V2") (pinfunction "VCC") (pintype "passive"))
    (pad "P13" smd circle locked (at -2.8 -2) (size 0.4 0.4) (layers "F.Cu" "F.Paste" "F.Mask")
      (net 1 "GND") (pinfunction "GND") (pintype "passive"))
    (pad "P14" smd circle locked (at -2 -2) (size 0.4 0.4) (layers "F.Cu" "F.Paste" "F.Mask")
      (net 1 "GND") (pinfunction "GND") (pintype "passive"))
    (pad "P15" smd circle locked (at -1.2 -2) (size 0.4 0.4) (layers "F.Cu" "F.Paste" "F.Mask")
      (net 1 "GND") (pinfunction "GND") (pintype "passive"))
    (pad "P16" smd circle locked (at -0.4 -2) (size 0.4 0.4) (layers "F.Cu" "F.Paste" "F.Mask")
      (net 1 "GND") (pinfunction "GND") (pintype "passive"))
    (pad "P17" smd circle locked (at 0.4 -2) (size 0.4 0.4) (layers "F.Cu" "F.Paste" "F.Mask")
      (net 1 "GND") (pinfunction "GND") (pintype "passive"))
    (pad "P18" smd circle locked (at 1.2 -2) (size 0.4 0.4) (layers "F.Cu" "F.Paste" "F.Mask")
      (net 1 "GND") (pinfunction "GND") (pintype "passive"))
    (pad "P19" smd circle locked (at 2 -2) (size 0.4 0.4) (layers "F.Cu" "F.Paste" "F.Mask")
      (net 1 "GND") (pinfunction "GND") (pintype "passive"))
    (pad "P20" smd circle locked (at 2.8 -2) (size 0.4 0.4) (layers "F.Cu" "F.Paste" "F.Mask")
      (net 1 "GND") (pinfunction "GND") (pintype "passive"))
    (pad "P21" smd circle locked (at 3.6 -2) (size 0.4 0.4) (layers "F.Cu" "F.Paste" "F.Mask")
      (net 211 "VCC1V2") (pinfunction "VCC") (pintype "passive"))
    (pad "P22" smd circle locked (at 4.4 -2) (size 0.4 0.4) (layers "F.Cu" "F.Paste" "F.Mask")
      (net 1 "GND") (pinfunction "GND") (pintype "passive"))
    (pad "P23" smd circle locked (at 5.2 -2) (size 0.4 0.4) (layers "F.Cu" "F.Paste" "F.Mask")
      (net 218 "VCC1V8") (pinfunction "VCCIO2") (pintype "passive"))
    (pad "P26" smd circle locked (at 7.6 -2) (size 0.4 0.4) (layers "F.Cu" "F.Paste" "F.Mask")
      (net 750 "unconnected-(U21D-PR44D-PadP26)") (pinfunction "PR44D") (pintype "bidirectional+no_connect"))
    (pad "P27" smd circle locked (at 8.4 -2) (size 0.4 0.4) (layers "F.Cu" "F.Paste" "F.Mask")
      (net 751 "unconnected-(U21D-PR44C-PadP27)") (pinfunction "PR44C") (pintype "bidirectional+no_connect"))
    (pad "P28" smd circle locked (at 9.2 -2) (size 0.4 0.4) (layers "F.Cu" "F.Paste" "F.Mask")
      (net 334 "ULPI1_CLKO") (pinfunction "PR47A") (pintype "bidirectional"))
    (pad "P29" smd circle locked (at 10 -2) (size 0.4 0.4) (layers "F.Cu" "F.Paste" "F.Mask")
      (net 752 "unconnected-(U21E-PR47B-PadP29)") (pinfunction "PR47B") (pintype "bidirectional+no_connect"))
    (pad "P30" smd circle locked (at 10.8 -2) (size 0.4 0.4) (layers "F.Cu" "F.Paste" "F.Mask")
      (net 330 "ULPI1_RESET") (pinfunction "PR59B") (pintype "bidirectional"))
    (pad "P31" smd circle locked (at 11.6 -2) (size 0.4 0.4) (layers "F.Cu" "F.Paste" "F.Mask")
      (net 332 "ULPI1_DIR") (pinfunction "PR59A") (pintype "bidirectional"))
    (pad "P32" smd circle locked (at 12.4 -2) (size 0.4 0.4) (layers "F.Cu" "F.Paste" "F.Mask")
      (net 333 "ULPI1_STP") (pinfunction "PR62B") (pintype "bidirectional"))
    (pad "R1" smd circle locked (at -12.4 -1.2) (size 0.4 0.4) (layers "F.Cu" "F.Paste" "F.Mask")
      (net 257 "DDR3_CS") (pinfunction "PL65A") (pintype "bidirectional"))
    (pad "R2" smd circle locked (at -11.6 -1.2) (size 0.4 0.4) (layers "F.Cu" "F.Paste" "F.Mask")
      (net 1 "GND") (pinfunction "GND") (pintype "passive"))
    (pad "R3" smd circle locked (at -10.8 -1.2) (size 0.4 0.4) (layers "F.Cu" "F.Paste" "F.Mask")
      (net 753 "unconnected-(U21G-PL59C-PadR3)") (pinfunction "PL59C") (pintype "bidirectional+no_connect"))
    (pad "R4" smd circle locked (at -10 -1.2) (size 0.4 0.4) (layers "F.Cu" "F.Paste" "F.Mask")
      (net 239 "DDR3_A9") (pinfunction "PL53A") (pintype "bidirectional"))
    (pad "R5" smd circle locked (at -9.2 -1.2) (size 0.4 0.4) (layers "F.Cu" "F.Paste" "F.Mask")
      (net 1 "GND") (pinfunction "GND") (pintype "passive"))
    (pad "R6" smd circle locked (at -8.4 -1.2) (size 0.4 0.4) (layers "F.Cu" "F.Paste" "F.Mask")
      (net 245 "DDR3_A4") (pinfunction "PL50A") (pintype "bidirectional"))
    (pad "R7" smd circle locked (at -7.6 -1.2) (size 0.4 0.4) (layers "F.Cu" "F.Paste" "F.Mask")
      (net 243 "DDR3_A8") (pinfunction "PL47C") (pintype "bidirectional"))
    (pad "R10" smd circle locked (at -5.2 -1.2) (size 0.4 0.4) (layers "F.Cu" "F.Paste" "F.Mask")
      (net 2 "VCC3V3") (pinfunction "VCCIO7") (pintype "passive"))
    (pad "R11" smd circle locked (at -4.4 -1.2) (size 0.4 0.4) (layers "F.Cu" "F.Paste" "F.Mask")
      (net 1 "GND") (pinfunction "GND") (pintype "passive"))
    (pad "R12" smd circle locked (at -3.6 -1.2) (size 0.4 0.4) (layers "F.Cu" "F.Paste" "F.Mask")
      (net 211 "VCC1V2") (pinfunction "VCC") (pintype "passive"))
    (pad "R13" smd circle locked (at -2.8 -1.2) (size 0.4 0.4) (layers "F.Cu" "F.Paste" "F.Mask")
      (net 1 "GND") (pinfunction "GND") (pintype "passive"))
    (pad "R14" smd circle locked (at -2 -1.2) (size 0.4 0.4) (layers "F.Cu" "F.Paste" "F.Mask")
      (net 1 "GND") (pinfunction "GND") (pintype "passive"))
    (pad "R15" smd circle locked (at -1.2 -1.2) (size 0.4 0.4) (layers "F.Cu" "F.Paste" "F.Mask")
      (net 1 "GND") (pinfunction "GND") (pintype "passive"))
    (pad "R16" smd circle locked (at -0.4 -1.2) (size 0.4 0.4) (layers "F.Cu" "F.Paste" "F.Mask")
      (net 1 "GND") (pinfunction "GND") (pintype "passive"))
    (pad "R17" smd circle locked (at 0.4 -1.2) (size 0.4 0.4) (layers "F.Cu" "F.Paste" "F.Mask")
      (net 1 "GND") (pinfunction "GND") (pintype "passive"))
    (pad "R18" smd circle locked (at 1.2 -1.2) (size 0.4 0.4) (layers "F.Cu" "F.Paste" "F.Mask")
      (net 1 "GND") (pinfunction "GND") (pintype "passive"))
    (pad "R19" smd circle locked (at 2 -1.2) (size 0.4 0.4) (layers "F.Cu" "F.Paste" "F.Mask")
      (net 1 "GND") (pinfunction "GND") (pintype "passive"))
    (pad "R20" smd circle locked (at 2.8 -1.2) (size 0.4 0.4) (layers "F.Cu" "F.Paste" "F.Mask")
      (net 1 "GND") (pinfunction "GND") (pintype "passive"))
    (pad "R21" smd circle locked (at 3.6 -1.2) (size 0.4 0.4) (layers "F.Cu" "F.Paste" "F.Mask")
      (net 211 "VCC1V2") (pinfunction "VCC") (pintype "passive"))
    (pad "R22" smd circle locked (at 4.4 -1.2) (size 0.4 0.4) (layers "F.Cu" "F.Paste" "F.Mask")
      (net 1 "GND") (pinfunction "GND") (pintype "passive"))
    (pad "R23" smd circle locked (at 5.2 -1.2) (size 0.4 0.4) (layers "F.Cu" "F.Paste" "F.Mask")
      (net 218 "VCC1V8") (pinfunction "VCCIO2") (pintype "passive"))
    (pad "R26" smd circle locked (at 7.6 -1.2) (size 0.4 0.4) (layers "F.Cu" "F.Paste" "F.Mask")
      (net 321 "ULPI2_CLKO") (pinfunction "PR47C") (pintype "bidirectional"))
    (pad "R27" smd circle locked (at 8.4 -1.2) (size 0.4 0.4) (layers "F.Cu" "F.Paste" "F.Mask")
      (net 123 "PRSNT1_N") (pinfunction "PR50A") (pintype "bidirectional"))
    (pad "R28" smd circle locked (at 9.2 -1.2) (size 0.4 0.4) (layers "F.Cu" "F.Paste" "F.Mask")
      (net 1 "GND") (pinfunction "GND") (pintype "passive"))
    (pad "R29" smd circle locked (at 10 -1.2) (size 0.4 0.4) (layers "F.Cu" "F.Paste" "F.Mask")
      (net 122 "IRQ_N") (pinfunction "PR53A") (pintype "bidirectional"))
    (pad "R30" smd circle locked (at 10.8 -1.2) (size 0.4 0.4) (layers "F.Cu" "F.Paste" "F.Mask")
      (net 754 "unconnected-(U21E-PR59C-PadR30)") (pinfunction "PR59C") (pintype "bidirectional+no_connect"))
    (pad "R31" smd circle locked (at 11.6 -1.2) (size 0.4 0.4) (layers "F.Cu" "F.Paste" "F.Mask")
      (net 1 "GND") (pinfunction "GND") (pintype "passive"))
    (pad "R32" smd circle locked (at 12.4 -1.2) (size 0.4 0.4) (layers "F.Cu" "F.Paste" "F.Mask")
      (net 335 "ULPI1_D7") (pinfunction "PR65A") (pintype "bidirectional"))
    (pad "T1" smd circle locked (at -12.4 -0.4) (size 0.4 0.4) (layers "F.Cu" "F.Paste" "F.Mask")
      (net 755 "unconnected-(U21G-PL68A-PadT1)") (pinfunction "PL68A") (pintype "bidirectional+no_connect"))
    (pad "T2" smd circle locked (at -11.6 -0.4) (size 0.4 0.4) (layers "F.Cu" "F.Paste" "F.Mask")
      (net 263 "DDR3_RESET") (pinfunction "PL65B") (pintype "bidirectional"))
    (pad "T3" smd circle locked (at -10.8 -0.4) (size 0.4 0.4) (layers "F.Cu" "F.Paste" "F.Mask")
      (net 756 "unconnected-(U21G-PL59D-PadT3)") (pinfunction "PL59D") (pintype "bidirectional+no_connect"))
    (pad "T4" smd circle locked (at -10 -0.4) (size 0.4 0.4) (layers "F.Cu" "F.Paste" "F.Mask")
      (net 237 "DDR3_A13") (pinfunction "PL53C") (pintype "bidirectional"))
    (pad "T5" smd circle locked (at -9.2 -0.4) (size 0.4 0.4) (layers "F.Cu" "F.Paste" "F.Mask")
      (net 248 "DDR3_A12") (pinfunction "PL53B") (pintype "bidirectional"))
    (pad "T6" smd circle locked (at -8.4 -0.4) (size 0.4 0.4) (layers "F.Cu" "F.Paste" "F.Mask")
      (net 238 "DDR3_A11") (pinfunction "PL50B") (pintype "bidirectional"))
    (pad "T7" smd circle locked (at -7.6 -0.4) (size 0.4 0.4) (layers "F.Cu" "F.Paste" "F.Mask")
      (net 244 "DDR3_A14") (pinfunction "PL47D") (pintype "bidirectional"))
    (pad "T10" smd circle locked (at -5.2 -0.4) (size 0.4 0.4) (layers "F.Cu" "F.Paste" "F.Mask")
      (net 2 "VCC3V3") (pinfunction "VCCIO7") (pintype "passive"))
    (pad "T11" smd circle locked (at -4.4 -0.4) (size 0.4 0.4) (layers "F.Cu" "F.Paste" "F.Mask")
      (net 1 "GND") (pinfunction "GND") (pintype "passive"))
    (pad "T12" smd circle locked (at -3.6 -0.4) (size 0.4 0.4) (layers "F.Cu" "F.Paste" "F.Mask")
      (net 211 "VCC1V2") (pinfunction "VCC") (pintype "passive"))
    (pad "T13" smd circle locked (at -2.8 -0.4) (size 0.4 0.4) (layers "F.Cu" "F.Paste" "F.Mask")
      (net 1 "GND") (pinfunction "GND") (pintype "passive"))
    (pad "T14" smd circle locked (at -2 -0.4) (size 0.4 0.4) (layers "F.Cu" "F.Paste" "F.Mask")
      (net 1 "GND") (pinfunction "GND") (pintype "passive"))
    (pad "T15" smd circle locked (at -1.2 -0.4) (size 0.4 0.4) (layers "F.Cu" "F.Paste" "F.Mask")
      (net 1 "GND") (pinfunction "GND") (pintype "passive"))
    (pad "T16" smd circle locked (at -0.4 -0.4) (size 0.4 0.4) (layers "F.Cu" "F.Paste" "F.Mask")
      (net 1 "GND") (pinfunction "GND") (pintype "passive"))
    (pad "T17" smd circle locked (at 0.4 -0.4) (size 0.4 0.4) (layers "F.Cu" "F.Paste" "F.Mask")
      (net 1 "GND") (pinfunction "GND") (pintype "passive"))
    (pad "T18" smd circle locked (at 1.2 -0.4) (size 0.4 0.4) (layers "F.Cu" "F.Paste" "F.Mask")
      (net 1 "GND") (pinfunction "GND") (pintype "passive"))
    (pad "T19" smd circle locked (at 2 -0.4) (size 0.4 0.4) (layers "F.Cu" "F.Paste" "F.Mask")
      (net 1 "GND") (pinfunction "GND") (pintype "passive"))
    (pad "T20" smd circle locked (at 2.8 -0.4) (size 0.4 0.4) (layers "F.Cu" "F.Paste" "F.Mask")
      (net 1 "GND") (pinfunction "GND") (pintype "passive"))
    (pad "T21" smd circle locked (at 3.6 -0.4) (size 0.4 0.4) (layers "F.Cu" "F.Paste" "F.Mask")
      (net 211 "VCC1V2") (pinfunction "VCC") (pintype "passive"))
    (pad "T22" smd circle locked (at 4.4 -0.4) (size 0.4 0.4) (layers "F.Cu" "F.Paste" "F.Mask")
      (net 1 "GND") (pinfunction "GND") (pintype "passive"))
    (pad "T23" smd circle locked (at 5.2 -0.4) (size 0.4 0.4) (layers "F.Cu" "F.Paste" "F.Mask")
      (net 218 "VCC1V8") (pinfunction "VCCIO2") (pintype "passive"))
    (pad "T26" smd circle locked (at 7.6 -0.4) (size 0.4 0.4) (layers "F.Cu" "F.Paste" "F.Mask")
      (net 757 "unconnected-(U21E-PR47D-PadT26)") (pinfunction "PR47D") (pintype "bidirectional+no_connect"))
    (pad "T27" smd circle locked (at 8.4 -0.4) (size 0.4 0.4) (layers "F.Cu" "F.Paste" "F.Mask")
      (net 115 "DBP_PREQ_N") (pinfunction "PR50B") (pintype "bidirectional"))
    (pad "T28" smd circle locked (at 9.2 -0.4) (size 0.4 0.4) (layers "F.Cu" "F.Paste" "F.Mask")
      (net 121 "SPARE0") (pinfunction "PR53B") (pintype "bidirectional"))
    (pad "T29" smd circle locked (at 10 -0.4) (size 0.4 0.4) (layers "F.Cu" "F.Paste" "F.Mask")
      (net 120 "CHASI#") (pinfunction "PR53C") (pintype "bidirectional"))
    (pad "T30" smd circle locked (at 10.8 -0.4) (size 0.4 0.4) (layers "F.Cu" "F.Paste" "F.Mask")
      (net 758 "unconnected-(U21E-PR59D-PadT30)") (pinfunction "PR59D") (pintype "bidirectional+no_connect"))
    (pad "T31" smd circle locked (at 11.6 -0.4) (size 0.4 0.4) (layers "F.Cu" "F.Paste" "F.Mask")
      (net 337 "ULPI1_D5") (pinfunction "PR65B") (pintype "bidirectional"))
    (pad "T32" smd circle locked (at 12.4 -0.4) (size 0.4 0.4) (layers "F.Cu" "F.Paste" "F.Mask")
      (net 336 "ULPI1_D6") (pinfunction "PR68A") (pintype "bidirectional"))
    (pad "U1" smd circle locked (at -12.4 0.4) (size 0.4 0.4) (layers "F.Cu" "F.Paste" "F.Mask")
      (net 759 "unconnected-(U21G-PL68B-PadU1)") (pinfunction "PL68B") (pintype "bidirectional+no_connect"))
    (pad "U2" smd circle locked (at -11.6 0.4) (size 0.4 0.4) (layers "F.Cu" "F.Paste" "F.Mask")
      (net 760 "unconnected-(U21G-PL62C-PadU2)") (pinfunction "PL62C") (pintype "bidirectional+no_connect"))
    (pad "U3" smd circle locked (at -10.8 0.4) (size 0.4 0.4) (layers "F.Cu" "F.Paste" "F.Mask")
      (net 761 "unconnected-(U21G-PL62D-PadU3)") (pinfunction "PL62D") (pintype "bidirectional+no_connect"))
    (pad "U4" smd circle locked (at -10 0.4) (size 0.4 0.4) (layers "F.Cu" "F.Paste" "F.Mask")
      (net 250 "DDR3_A10") (pinfunction "PL56A") (pintype "bidirectional"))
    (pad "U5" smd circle locked (at -9.2 0.4) (size 0.4 0.4) (layers "F.Cu" "F.Paste" "F.Mask")
      (net 240 "DDR3_A7") (pinfunction "PL53D") (pintype "bidirectional"))
    (pad "U6" smd circle locked (at -8.4 0.4) (size 0.4 0.4) (layers "F.Cu" "F.Paste" "F.Mask")
      (net 242 "DDR3_A6") (pinfunction "PL50C") (pintype "bidirectional"))
    (pad "U7" smd circle locked (at -7.6 0.4) (size 0.4 0.4) (layers "F.Cu" "F.Paste" "F.Mask")
      (net 241 "DDR3_A2") (pinfunction "PL50D") (pintype "bidirectional"))
    (pad "U10" smd circle locked (at -5.2 0.4) (size 0.4 0.4) (layers "F.Cu" "F.Paste" "F.Mask")
      (net 3 "VCC1V35") (pinfunction "VCCIO6") (pintype "passive"))
    (pad "U11" smd circle locked (at -4.4 0.4) (size 0.4 0.4) (layers "F.Cu" "F.Paste" "F.Mask")
      (net 1 "GND") (pinfunction "GND") (pintype "passive"))
    (pad "U12" smd circle locked (at -3.6 0.4) (size 0.4 0.4) (layers "F.Cu" "F.Paste" "F.Mask")
      (net 211 "VCC1V2") (pinfunction "VCC") (pintype "passive"))
    (pad "U13" smd circle locked (at -2.8 0.4) (size 0.4 0.4) (layers "F.Cu" "F.Paste" "F.Mask")
      (net 1 "GND") (pinfunction "GND") (pintype "passive"))
    (pad "U14" smd circle locked (at -2 0.4) (size 0.4 0.4) (layers "F.Cu" "F.Paste" "F.Mask")
      (net 1 "GND") (pinfunction "GND") (pintype "passive"))
    (pad "U15" smd circle locked (at -1.2 0.4) (size 0.4 0.4) (layers "F.Cu" "F.Paste" "F.Mask")
      (net 1 "GND") (pinfunction "GND") (pintype "passive"))
    (pad "U16" smd circle locked (at -0.4 0.4) (size 0.4 0.4) (layers "F.Cu" "F.Paste" "F.Mask")
      (net 1 "GND") (pinfunction "GND") (pintype "passive"))
    (pad "U17" smd circle locked (at 0.4 0.4) (size 0.4 0.4) (layers "F.Cu" "F.Paste" "F.Mask")
      (net 1 "GND") (pinfunction "GND") (pintype "passive"))
    (pad "U18" smd circle locked (at 1.2 0.4) (size 0.4 0.4) (layers "F.Cu" "F.Paste" "F.Mask")
      (net 1 "GND") (pinfunction "GND") (pintype "passive"))
    (pad "U19" smd circle locked (at 2 0.4) (size 0.4 0.4) (layers "F.Cu" "F.Paste" "F.Mask")
      (net 1 "GND") (pinfunction "GND") (pintype "passive"))
    (pad "U20" smd circle locked (at 2.8 0.4) (size 0.4 0.4) (layers "F.Cu" "F.Paste" "F.Mask")
      (net 1 "GND") (pinfunction "GND") (pintype "passive"))
    (pad "U21" smd circle locked (at 3.6 0.4) (size 0.4 0.4) (layers "F.Cu" "F.Paste" "F.Mask")
      (net 211 "VCC1V2") (pinfunction "VCC") (pintype "passive"))
    (pad "U22" smd circle locked (at 4.4 0.4) (size 0.4 0.4) (layers "F.Cu" "F.Paste" "F.Mask")
      (net 1 "GND") (pinfunction "GND") (pintype "passive"))
    (pad "U23" smd circle locked (at 5.2 0.4) (size 0.4 0.4) (layers "F.Cu" "F.Paste" "F.Mask")
      (net 2 "VCC3V3") (pinfunction "VCCIO3") (pintype "passive"))
    (pad "U26" smd circle locked (at 7.6 0.4) (size 0.4 0.4) (layers "F.Cu" "F.Paste" "F.Mask")
      (net 113 "SYS_PWRBTN_N") (pinfunction "PR50D") (pintype "bidirectional"))
    (pad "U27" smd circle locked (at 8.4 0.4) (size 0.4 0.4) (layers "F.Cu" "F.Paste" "F.Mask")
      (net 114 "SYS_PWROK") (pinfunction "PR50C") (pintype "bidirectional"))
    (pad "U28" smd circle locked (at 9.2 0.4) (size 0.4 0.4) (layers "F.Cu" "F.Paste" "F.Mask")
      (net 119 "RoT_CPU_RST_N") (pinfunction "PR53D") (pintype "bidirectional"))
    (pad "U29" smd circle locked (at 10 0.4) (size 0.4 0.4) (layers "F.Cu" "F.Paste" "F.Mask")
      (net 118 "SPARE1") (pinfunction "PR56A") (pintype "bidirectional"))
    (pad "U30" smd circle locked (at 10.8 0.4) (size 0.4 0.4) (layers "F.Cu" "F.Paste" "F.Mask")
      (net 762 "unconnected-(U21E-PR62D-PadU30)") (pinfunction "PR62D") (pintype "bidirectional+no_connect"))
    (pad "U31" smd circle locked (at 11.6 0.4) (size 0.4 0.4) (layers "F.Cu" "F.Paste" "F.Mask")
      (net 339 "ULPI1_D3") (pinfunction "PR62C") (pintype "bidirectional"))
    (pad "U32" smd circle locked (at 12.4 0.4) (size 0.4 0.4) (layers "F.Cu" "F.Paste" "F.Mask")
      (net 338 "ULPI1_D4") (pinfunction "PR68B") (pintype "bidirectional"))
    (pad "V1" smd circle locked (at -12.4 1.2) (size 0.4 0.4) (layers "F.Cu" "F.Paste" "F.Mask")
      (net 763 "unconnected-(U21G-PL68C-PadV1)") (pinfunction "PL68C") (pintype "bidirectional+no_connect"))
    (pad "V2" smd circle locked (at -11.6 1.2) (size 0.4 0.4) (layers "F.Cu" "F.Paste" "F.Mask")
      (net 1 "GND") (pinfunction "GND") (pintype "passive"))
    (pad "V3" smd circle locked (at -10.8 1.2) (size 0.4 0.4) (layers "F.Cu" "F.Paste" "F.Mask")
      (net 764 "unconnected-(U21A-NC-PadV3)") (pinfunction "NC") (pintype "no_connect"))
    (pad "V4" smd circle locked (at -10 1.2) (size 0.4 0.4) (layers "F.Cu" "F.Paste" "F.Mask")
      (net 217 "DDR3_VREF") (pinfunction "PL56B") (pintype "bidirectional"))
    (pad "V5" smd circle locked (at -9.2 1.2) (size 0.4 0.4) (layers "F.Cu" "F.Paste" "F.Mask")
      (net 1 "GND") (pinfunction "GND") (pintype "passive"))
    (pad "V6" smd circle locked (at -8.4 1.2) (size 0.4 0.4) (layers "F.Cu" "F.Paste" "F.Mask")
      (net 249 "DDR3_BA1") (pinfunction "PL56C") (pintype "bidirectional"))
    (pad "V7" smd circle locked (at -7.6 1.2) (size 0.4 0.4) (layers "F.Cu" "F.Paste" "F.Mask")
      (net 247 "DDR3_A1") (pinfunction "PL56D") (pintype "bidirectional"))
    (pad "V10" smd circle locked (at -5.2 1.2) (size 0.4 0.4) (layers "F.Cu" "F.Paste" "F.Mask")
      (net 3 "VCC1V35") (pinfunction "VCCIO6") (pintype "passive"))
    (pad "V11" smd circle locked (at -4.4 1.2) (size 0.4 0.4) (layers "F.Cu" "F.Paste" "F.Mask")
      (net 1 "GND") (pinfunction "GND") (pintype "passive"))
    (pad "V12" smd circle locked (at -3.6 1.2) (size 0.4 0.4) (layers "F.Cu" "F.Paste" "F.Mask")
      (net 211 "VCC1V2") (pinfunction "VCC") (pintype "passive"))
    (pad "V13" smd circle locked (at -2.8 1.2) (size 0.4 0.4) (layers "F.Cu" "F.Paste" "F.Mask")
      (net 1 "GND") (pinfunction "GND") (pintype "passive"))
    (pad "V14" smd circle locked (at -2 1.2) (size 0.4 0.4) (layers "F.Cu" "F.Paste" "F.Mask")
      (net 1 "GND") (pinfunction "GND") (pintype "passive"))
    (pad "V15" smd circle locked (at -1.2 1.2) (size 0.4 0.4) (layers "F.Cu" "F.Paste" "F.Mask")
      (net 1 "GND") (pinfunction "GND") (pintype "passive"))
    (pad "V16" smd circle locked (at -0.4 1.2) (size 0.4 0.4) (layers "F.Cu" "F.Paste" "F.Mask")
      (net 1 "GND") (pinfunction "GND") (pintype "passive"))
    (pad "V17" smd circle locked (at 0.4 1.2) (size 0.4 0.4) (layers "F.Cu" "F.Paste" "F.Mask")
      (net 1 "GND") (pinfunction "GND") (pintype "passive"))
    (pad "V18" smd circle locked (at 1.2 1.2) (size 0.4 0.4) (layers "F.Cu" "F.Paste" "F.Mask")
      (net 1 "GND") (pinfunction "GND") (pintype "passive"))
    (pad "V19" smd circle locked (at 2 1.2) (size 0.4 0.4) (layers "F.Cu" "F.Paste" "F.Mask")
      (net 1 "GND") (pinfunction "GND") (pintype "passive"))
    (pad "V20" smd circle locked (at 2.8 1.2) (size 0.4 0.4) (layers "F.Cu" "F.Paste" "F.Mask")
      (net 1 "GND") (pinfunction "GND") (pintype "passive"))
    (pad "V21" smd circle locked (at 3.6 1.2) (size 0.4 0.4) (layers "F.Cu" "F.Paste" "F.Mask")
      (net 211 "VCC1V2") (pinfunction "VCC") (pintype "passive"))
    (pad "V22" smd circle locked (at 4.4 1.2) (size 0.4 0.4) (layers "F.Cu" "F.Paste" "F.Mask")
      (net 1 "GND") (pinfunction "GND") (pintype "passive"))
    (pad "V23" smd circle locked (at 5.2 1.2) (size 0.4 0.4) (layers "F.Cu" "F.Paste" "F.Mask")
      (net 2 "VCC3V3") (pinfunction "VCCIO3") (pintype "passive"))
    (pad "V26" smd circle locked (at 7.6 1.2) (size 0.4 0.4) (layers "F.Cu" "F.Paste" "F.Mask")
      (net 765 "unconnected-(U21E-PR56D-PadV26)") (pinfunction "PR56D") (pintype "bidirectional+no_connect"))
    (pad "V27" smd circle locked (at 8.4 1.2) (size 0.4 0.4) (layers "F.Cu" "F.Paste" "F.Mask")
      (net 766 "unconnected-(U21E-PR56C-PadV27)") (pinfunction "PR56C") (pintype "bidirectional+no_connect"))
    (pad "V28" smd circle locked (at 9.2 1.2) (size 0.4 0.4) (layers "F.Cu" "F.Paste" "F.Mask")
      (net 1 "GND") (pinfunction "GND") (pintype "passive"))
    (pad "V29" smd circle locked (at 10 1.2) (size 0.4 0.4) (layers "F.Cu" "F.Paste" "F.Mask")
      (net 117 "RST_PLTRST_BUF_N") (pinfunction "PR56B") (pintype "bidirectional"))
    (pad "V30" smd circle locked (at 10.8 1.2) (size 0.4 0.4) (layers "F.Cu" "F.Paste" "F.Mask")
      (net 767 "unconnected-(U21A-NC-PadV30)") (pinfunction "NC") (pintype "no_connect"))
    (pad "V31" smd circle locked (at 11.6 1.2) (size 0.4 0.4) (layers "F.Cu" "F.Paste" "F.Mask")
      (net 1 "GND") (pinfunction "GND") (pintype "passive"))
    (pad "V32" smd circle locked (at 12.4 1.2) (size 0.4 0.4) (layers "F.Cu" "F.Paste" "F.Mask")
      (net 340 "ULPI1_D2") (pinfunction "PR68C") (pintype "bidirectional"))
    (pad "W1" smd circle locked (at -12.4 2) (size 0.4 0.4) (layers "F.Cu" "F.Paste" "F.Mask")
      (net 768 "unconnected-(U21G-PL68D-PadW1)") (pinfunction "PL68D") (pintype "bidirectional+no_connect"))
    (pad "W2" smd circle locked (at -11.6 2) (size 0.4 0.4) (layers "F.Cu" "F.Paste" "F.Mask")
      (net 254 "DDR3_CAS") (pinfunction "PL86A") (pintype "bidirectional"))
    (pad "W3" smd circle locked (at -10.8 2) (size 0.4 0.4) (layers "F.Cu" "F.Paste" "F.Mask")
      (net 769 "unconnected-(U21G-PL65C-PadW3)") (pinfunction "PL65C") (pintype "bidirectional+no_connect"))
    (pad "W4" smd circle locked (at -10 2) (size 0.4 0.4) (layers "F.Cu" "F.Paste" "F.Mask")
      (net 246 "DDR3_A0") (pinfunction "PL74B") (pintype "bidirectional"))
    (pad "W5" smd circle locked (at -9.2 2) (size 0.4 0.4) (layers "F.Cu" "F.Paste" "F.Mask")
      (net 252 "DDR3_BA2") (pinfunction "PL71D") (pintype "bidirectional"))
    (pad "W6" smd circle locked (at -8.4 2) (size 0.4 0.4) (layers "F.Cu" "F.Paste" "F.Mask")
      (net 770 "unconnected-(U21A-NC-PadW6)") (pinfunction "NC") (pintype "no_connect"))
    (pad "W10" smd circle locked (at -5.2 2) (size 0.4 0.4) (layers "F.Cu" "F.Paste" "F.Mask")
      (net 3 "VCC1V35") (pinfunction "VCCIO6") (pintype "passive"))
    (pad "W11" smd circle locked (at -4.4 2) (size 0.4 0.4) (layers "F.Cu" "F.Paste" "F.Mask")
      (net 1 "GND") (pinfunction "GND") (pintype "passive"))
    (pad "W12" smd circle locked (at -3.6 2) (size 0.4 0.4) (layers "F.Cu" "F.Paste" "F.Mask")
      (net 211 "VCC1V2") (pinfunction "VCC") (pintype "passive"))
    (pad "W13" smd circle locked (at -2.8 2) (size 0.4 0.4) (layers "F.Cu" "F.Paste" "F.Mask")
      (net 1 "GND") (pinfunction "GND") (pintype "passive"))
    (pad "W14" smd circle locked (at -2 2) (size 0.4 0.4) (layers "F.Cu" "F.Paste" "F.Mask")
      (net 1 "GND") (pinfunction "GND") (pintype "passive"))
    (pad "W15" smd circle locked (at -1.2 2) (size 0.4 0.4) (layers "F.Cu" "F.Paste" "F.Mask")
      (net 1 "GND") (pinfunction "GND") (pintype "passive"))
    (pad "W16" smd circle locked (at -0.4 2) (size 0.4 0.4) (layers "F.Cu" "F.Paste" "F.Mask")
      (net 1 "GND") (pinfunction "GND") (pintype "passive"))
    (pad "W17" smd circle locked (at 0.4 2) (size 0.4 0.4) (layers "F.Cu" "F.Paste" "F.Mask")
      (net 1 "GND") (pinfunction "GND") (pintype "passive"))
    (pad "W18" smd circle locked (at 1.2 2) (size 0.4 0.4) (layers "F.Cu" "F.Paste" "F.Mask")
      (net 1 "GND") (pinfunction "GND") (pintype "passive"))
    (pad "W19" smd circle locked (at 2 2) (size 0.4 0.4) (layers "F.Cu" "F.Paste" "F.Mask")
      (net 1 "GND") (pinfunction "GND") (pintype "passive"))
    (pad "W20" smd circle locked (at 2.8 2) (size 0.4 0.4) (layers "F.Cu" "F.Paste" "F.Mask")
      (net 1 "GND") (pinfunction "GND") (pintype "passive"))
    (pad "W21" smd circle locked (at 3.6 2) (size 0.4 0.4) (layers "F.Cu" "F.Paste" "F.Mask")
      (net 211 "VCC1V2") (pinfunction "VCC") (pintype "passive"))
    (pad "W22" smd circle locked (at 4.4 2) (size 0.4 0.4) (layers "F.Cu" "F.Paste" "F.Mask")
      (net 1 "GND") (pinfunction "GND") (pintype "passive"))
    (pad "W23" smd circle locked (at 5.2 2) (size 0.4 0.4) (layers "F.Cu" "F.Paste" "F.Mask")
      (net 2 "VCC3V3") (pinfunction "VCCIO3") (pintype "passive"))
    (pad "W27" smd circle locked (at 8.4 2) (size 0.4 0.4) (layers "F.Cu" "F.Paste" "F.Mask")
      (net 771 "unconnected-(U21A-NC-PadW27)") (pinfunction "NC") (pintype "no_connect"))
    (pad "W28" smd circle locked (at 9.2 2) (size 0.4 0.4) (layers "F.Cu" "F.Paste" "F.Mask")
      (net 772 "unconnected-(U21E-PR71D-PadW28)") (pinfunction "PR71D") (pintype "bidirectional+no_connect"))
    (pad "W29" smd circle locked (at 10 2) (size 0.4 0.4) (layers "F.Cu" "F.Paste" "F.Mask")
      (net 773 "unconnected-(U21E-PR74B-PadW29)") (pinfunction "PR74B") (pintype "bidirectional+no_connect"))
    (pad "W30" smd circle locked (at 10.8 2) (size 0.4 0.4) (layers "F.Cu" "F.Paste" "F.Mask")
      (net 116 "DBP_PRDY_N") (pinfunction "PR65C") (pintype "bidirectional"))
    (pad "W31" smd circle locked (at 11.6 2) (size 0.4 0.4) (layers "F.Cu" "F.Paste" "F.Mask")
      (net 342 "ULPI1_D0") (pinfunction "PR86A") (pintype "bidirectional"))
    (pad "W32" smd circle locked (at 12.4 2) (size 0.4 0.4) (layers "F.Cu" "F.Paste" "F.Mask")
      (net 341 "ULPI1_D1") (pinfunction "PR68D") (pintype "bidirectional"))
    (pad "Y1" smd circle locked (at -12.4 2.8) (size 0.4 0.4) (layers "F.Cu" "F.Paste" "F.Mask")
      (net 260 "DDR3_CKE") (pinfunction "PL86B") (pintype "bidirectional"))
    (pad "Y2" smd circle locked (at -11.6 2.8) (size 0.4 0.4) (layers "F.Cu" "F.Paste" "F.Mask")
      (net 1 "GND") (pinfunction "GND") (pintype "passive"))
    (pad "Y3" smd circle locked (at -10.8 2.8) (size 0.4 0.4) (layers "F.Cu" "F.Paste" "F.Mask")
      (net 774 "unconnected-(U21G-PL65D-PadY3)") (pinfunction "PL65D") (pintype "bidirectional+no_connect"))
    (pad "Y4" smd circle locked (at -10 2.8) (size 0.4 0.4) (layers "F.Cu" "F.Paste" "F.Mask")
      (net 190 "DDR3_DQ2") (pinfunction "PL74A") (pintype "bidirectional"))
    (pad "Y5" smd circle locked (at -9.2 2.8) (size 0.4 0.4) (layers "F.Cu" "F.Paste" "F.Mask")
      (net 189 "DDR3_DQ5") (pinfunction "PL71C") (pintype "bidirectional"))
    (pad "Y6" smd circle locked (at -8.4 2.8) (size 0.4 0.4) (layers "F.Cu" "F.Paste" "F.Mask")
      (net 194 "DDR3_DQ6") (pinfunction "PL71B") (pintype "bidirectional"))
    (pad "Y7" smd circle locked (at -7.6 2.8) (size 0.4 0.4) (layers "F.Cu" "F.Paste" "F.Mask")
      (net 188 "DDR3_DQ7") (pinfunction "PL71A") (pintype "bidirectional"))
    (pad "Y10" smd circle locked (at -5.2 2.8) (size 0.4 0.4) (layers "F.Cu" "F.Paste" "F.Mask")
      (net 304 "/FPGA power supply/VCCAUX") (pinfunction "VCCAUX") (pintype "passive"))
    (pad "Y11" smd circle locked (at -4.4 2.8) (size 0.4 0.4) (layers "F.Cu" "F.Paste" "F.Mask")
      (net 1 "GND") (pinfunction "GND") (pintype "passive"))
    (pad "Y12" smd circle locked (at -3.6 2.8) (size 0.4 0.4) (layers "F.Cu" "F.Paste" "F.Mask")
      (net 211 "VCC1V2") (pinfunction "VCC") (pintype "passive"))
    (pad "Y13" smd circle locked (at -2.8 2.8) (size 0.4 0.4) (layers "F.Cu" "F.Paste" "F.Mask")
      (net 1 "GND") (pinfunction "GND") (pintype "passive"))
    (pad "Y14" smd circle locked (at -2 2.8) (size 0.4 0.4) (layers "F.Cu" "F.Paste" "F.Mask")
      (net 1 "GND") (pinfunction "GND") (pintype "passive"))
    (pad "Y15" smd circle locked (at -1.2 2.8) (size 0.4 0.4) (layers "F.Cu" "F.Paste" "F.Mask")
      (net 1 "GND") (pinfunction "GND") (pintype "passive"))
    (pad "Y16" smd circle locked (at -0.4 2.8) (size 0.4 0.4) (layers "F.Cu" "F.Paste" "F.Mask")
      (net 1 "GND") (pinfunction "GND") (pintype "passive"))
    (pad "Y17" smd circle locked (at 0.4 2.8) (size 0.4 0.4) (layers "F.Cu" "F.Paste" "F.Mask")
      (net 1 "GND") (pinfunction "GND") (pintype "passive"))
    (pad "Y18" smd circle locked (at 1.2 2.8) (size 0.4 0.4) (layers "F.Cu" "F.Paste" "F.Mask")
      (net 1 "GND") (pinfunction "GND") (pintype "passive"))
    (pad "Y19" smd circle locked (at 2 2.8) (size 0.4 0.4) (layers "F.Cu" "F.Paste" "F.Mask")
      (net 1 "GND") (pinfunction "GND") (pintype "passive"))
    (pad "Y20" smd circle locked (at 2.8 2.8) (size 0.4 0.4) (layers "F.Cu" "F.Paste" "F.Mask")
      (net 1 "GND") (pinfunction "GND") (pintype "passive"))
    (pad "Y21" smd circle locked (at 3.6 2.8) (size 0.4 0.4) (layers "F.Cu" "F.Paste" "F.Mask")
      (net 211 "VCC1V2") (pinfunction "VCC") (pintype "passive"))
    (pad "Y22" smd circle locked (at 4.4 2.8) (size 0.4 0.4) (layers "F.Cu" "F.Paste" "F.Mask")
      (net 1 "GND") (pinfunction "GND") (pintype "passive"))
    (pad "Y23" smd circle locked (at 5.2 2.8) (size 0.4 0.4) (layers "F.Cu" "F.Paste" "F.Mask")
      (net 304 "/FPGA power supply/VCCAUX") (pinfunction "VCCAUX") (pintype "passive"))
    (pad "Y26" smd circle locked (at 7.6 2.8) (size 0.4 0.4) (layers "F.Cu" "F.Paste" "F.Mask")
      (net 775 "unconnected-(U21E-PR71A-PadY26)") (pinfunction "PR71A") (pintype "bidirectional+no_connect"))
    (pad "Y27" smd circle locked (at 8.4 2.8) (size 0.4 0.4) (layers "F.Cu" "F.Paste" "F.Mask")
      (net 112 "HPM_STBY_RST_N") (pinfunction "PR71B") (pintype "bidirectional"))
    (pad "Y28" smd circle locked (at 9.2 2.8) (size 0.4 0.4) (layers "F.Cu" "F.Paste" "F.Mask")
      (net 320 "ULPI2_STP") (pinfunction "PR71C") (pintype "bidirectional"))
    (pad "Y29" smd circle locked (at 10 2.8) (size 0.4 0.4) (layers "F.Cu" "F.Paste" "F.Mask")
      (net 319 "ULPI_DIR") (pinfunction "PR74A") (pintype "bidirectional"))
    (pad "Y30" smd circle locked (at 10.8 2.8) (size 0.4 0.4) (layers "F.Cu" "F.Paste" "F.Mask")
      (net 318 "ULPI2_NXT") (pinfunction "PR65D") (pintype "bidirectional"))
    (pad "Y31" smd circle locked (at 11.6 2.8) (size 0.4 0.4) (layers "F.Cu" "F.Paste" "F.Mask")
      (net 1 "GND") (pinfunction "GND") (pintype "passive"))
    (pad "Y32" smd circle locked (at 12.4 2.8) (size 0.4 0.4) (layers "F.Cu" "F.Paste" "F.Mask")
      (net 317 "ULPI2_RESET") (pinfunction "PR86B") (pintype "bidirectional"))
  )

  (footprint "antmicro-footprints:R_0402_1005Metric" (layer "F.Cu")
    (at 108.95 99.45)
    (descr "Resistor SMD 0402")
    (tags "resistor SMD 0402")
    (property "Author" "Antmicro")
    (property "License" "Apache-2.0")
    (property "MPN" "CR0402-FX-1022GLF")
    (property "Manufacturer" "Bourns")
    (property "Public" "False")
    (property "Sheetfile" "ethernet.kicad_sch")
    (property "Sheetname" "Ethernet")
    (property "Tolerance" "1%")
    (property "Val" "10k2")
    (property "ki_description" "SMD Chip Resistor")
    (property "ki_keywords" "0402, SMT, RESISTOR, PASSIVE")
    (attr smd)
    (fp_text reference "R10" (at 0.07 1.16) (layer "F.SilkS")
        (effects (font (size 0.7 0.7) (thickness 0.127)))
    )
    (fp_text value "R_10k2_0402" (at 0 1.17) (layer "F.Fab")
        (effects (font (size 1 1) (thickness 0.15)))
    )
    (fp_text user "Author: Antmicro" (at -0.95 4.169) (layer "F.Fab") hide
        (effects (font (size 0.7 0.7) (thickness 0.15)) (justify left bottom))
    )
    (fp_text user "${REFERENCE}" (at 0 0) (layer "F.Fab")
        (effects (font (size 0.25 0.25) (thickness 0.04)))
    )
    (fp_text user "License: Apache-2.0" (at -0.95 5.169) (layer "F.Fab") hide
        (effects (font (size 0.7 0.7) (thickness 0.15)) (justify left bottom))
    )
    (fp_rect (start -0.925 -0.47) (end 0.925 0.47)
      (stroke (width 0.05) (type default)) (fill none) (layer "F.CrtYd"))
    (fp_rect (start -0.5 -0.25) (end 0.5 0.25)
      (stroke (width 0.15) (type solid)) (fill none) (layer "F.Fab"))
    (pad "1" smd roundrect (at -0.48 0) (size 0.59 0.64) (layers "F.Cu" "F.Paste" "F.Mask") (roundrect_rratio 0.25)
      (net 197 "ETH_INT_N") (pintype "passive"))
    (pad "2" smd roundrect (at 0.48 0) (size 0.59 0.64) (layers "F.Cu" "F.Paste" "F.Mask") (roundrect_rratio 0.25)
      (net 2 "VCC3V3") (pintype "passive"))
  )

  (footprint "antmicro-footprints:R_0402_1005Metric" (layer "F.Cu")
    (at 108.95 97.15)
    (descr "Resistor SMD 0402")
    (tags "resistor SMD 0402")
    (property "Author" "Antmicro")
    (property "License" "Apache-2.0")
    (property "MPN" "CR0402-FX-1022GLF")
    (property "Manufacturer" "Bourns")
    (property "Public" "False")
    (property "Sheetfile" "ethernet.kicad_sch")
    (property "Sheetname" "Ethernet")
    (property "Tolerance" "1%")
    (property "Val" "10k2")
    (property "ki_description" "SMD Chip Resistor")
    (property "ki_keywords" "0402, SMT, RESISTOR, PASSIVE")
    (attr smd)
    (fp_text reference "R7" (at 0.04 1.04) (layer "F.SilkS")
        (effects (font (size 0.7 0.7) (thickness 0.127)))
    )
    (fp_text value "R_10k2_0402" (at 0 1.17) (layer "F.Fab")
        (effects (font (size 1 1) (thickness 0.15)))
    )
    (fp_text user "Author: Antmicro" (at -0.95 4.169) (layer "F.Fab") hide
        (effects (font (size 0.7 0.7) (thickness 0.15)) (justify left bottom))
    )
    (fp_text user "${REFERENCE}" (at 0 0) (layer "F.Fab")
        (effects (font (size 0.25 0.25) (thickness 0.04)))
    )
    (fp_text user "License: Apache-2.0" (at -0.95 5.169) (layer "F.Fab") hide
        (effects (font (size 0.7 0.7) (thickness 0.15)) (justify left bottom))
    )
    (fp_rect (start -0.925 -0.47) (end 0.925 0.47)
      (stroke (width 0.05) (type default)) (fill none) (layer "F.CrtYd"))
    (fp_rect (start -0.5 -0.25) (end 0.5 0.25)
      (stroke (width 0.15) (type solid)) (fill none) (layer "F.Fab"))
    (pad "1" smd roundrect (at -0.48 0) (size 0.59 0.64) (layers "F.Cu" "F.Paste" "F.Mask") (roundrect_rratio 0.25)
      (net 160 "RGMII_REF_CLK") (pintype "passive"))
    (pad "2" smd roundrect (at 0.48 0) (size 0.59 0.64) (layers "F.Cu" "F.Paste" "F.Mask") (roundrect_rratio 0.25)
      (net 2 "VCC3V3") (pintype "passive"))
  )

  (footprint "antmicro-footprints:R_0402_1005Metric" (layer "F.Cu")
    (at 106 104 -90)
    (descr "Resistor SMD 0402")
    (tags "resistor SMD 0402")
    (property "Author" "Antmicro")
    (property "License" "Apache-2.0")
    (property "MPN" "CR0402-FX-1022GLF")
    (property "Manufacturer" "Bourns")
    (property "Public" "False")
    (property "Sheetfile" "ethernet.kicad_sch")
    (property "Sheetname" "Ethernet")
    (property "Tolerance" "1%")
    (property "Val" "10k2")
    (property "ki_description" "SMD Chip Resistor")
    (property "ki_keywords" "0402, SMT, RESISTOR, PASSIVE")
    (attr smd)
    (fp_text reference "R6" (at 0.04 -8.93738 90) (layer "F.SilkS")
        (effects (font (size 0.7 0.7) (thickness 0.127)))
    )
    (fp_text value "R_10k2_0402" (at 0 1.17 90) (layer "F.Fab")
        (effects (font (size 1 1) (thickness 0.15)))
    )
    (fp_text user "${REFERENCE}" (at 0 0 90) (layer "F.Fab")
        (effects (font (size 0.25 0.25) (thickness 0.04)))
    )
    (fp_text user "License: Apache-2.0" (at -0.95 5.169 -90) (layer "F.Fab") hide
        (effects (font (size 0.7 0.7) (thickness 0.15)) (justify left bottom))
    )
    (fp_text user "Author: Antmicro" (at -0.95 4.169 -90) (layer "F.Fab") hide
        (effects (font (size 0.7 0.7) (thickness 0.15)) (justify left bottom))
    )
    (fp_rect (start -0.925 -0.47) (end 0.925 0.47)
      (stroke (width 0.05) (type default)) (fill none) (layer "F.CrtYd"))
    (fp_rect (start -0.5 -0.25) (end 0.5 0.25)
      (stroke (width 0.15) (type solid)) (fill none) (layer "F.Fab"))
    (pad "1" smd roundrect (at -0.48 0 270) (size 0.59 0.64) (layers "F.Cu" "F.Paste" "F.Mask") (roundrect_rratio 0.25)
      (net 159 "RGMII_RX_CLK") (pintype "passive"))
    (pad "2" smd roundrect (at 0.48 0 270) (size 0.59 0.64) (layers "F.Cu" "F.Paste" "F.Mask") (roundrect_rratio 0.25)
      (net 2 "VCC3V3") (pintype "passive"))
  )

  (footprint "antmicro-footprints:R_0402_1005Metric" (layer "F.Cu")
    (at 105 104 -90)
    (descr "Resistor SMD 0402")
    (tags "resistor SMD 0402")
    (property "Author" "Antmicro")
    (property "License" "Apache-2.0")
    (property "MPN" "CR0402-FX-1022GLF")
    (property "Manufacturer" "Bourns")
    (property "Public" "False")
    (property "Sheetfile" "ethernet.kicad_sch")
    (property "Sheetname" "Ethernet")
    (property "Tolerance" "1%")
    (property "Val" "10k2")
    (property "ki_description" "SMD Chip Resistor")
    (property "ki_keywords" "0402, SMT, RESISTOR, PASSIVE")
    (attr smd)
    (fp_text reference "R5" (at 0.04 -8.941904 90) (layer "F.SilkS")
        (effects (font (size 0.7 0.7) (thickness 0.127)))
    )
    (fp_text value "R_10k2_0402" (at 0 1.17 90) (layer "F.Fab")
        (effects (font (size 1 1) (thickness 0.15)))
    )
    (fp_text user "Author: Antmicro" (at -0.95 4.169 -90) (layer "F.Fab") hide
        (effects (font (size 0.7 0.7) (thickness 0.15)) (justify left bottom))
    )
    (fp_text user "${REFERENCE}" (at 0 0 90) (layer "F.Fab")
        (effects (font (size 0.25 0.25) (thickness 0.04)))
    )
    (fp_text user "License: Apache-2.0" (at -0.95 5.169 -90) (layer "F.Fab") hide
        (effects (font (size 0.7 0.7) (thickness 0.15)) (justify left bottom))
    )
    (fp_rect (start -0.925 -0.47) (end 0.925 0.47)
      (stroke (width 0.05) (type default)) (fill none) (layer "F.CrtYd"))
    (fp_rect (start -0.5 -0.25) (end 0.5 0.25)
      (stroke (width 0.15) (type solid)) (fill none) (layer "F.Fab"))
    (pad "1" smd roundrect (at -0.48 0 270) (size 0.59 0.64) (layers "F.Cu" "F.Paste" "F.Mask") (roundrect_rratio 0.25)
      (net 158 "RGMII_RX_DV") (pintype "passive"))
    (pad "2" smd roundrect (at 0.48 0 270) (size 0.59 0.64) (layers "F.Cu" "F.Paste" "F.Mask") (roundrect_rratio 0.25)
      (net 2 "VCC3V3") (pintype "passive"))
  )

  (footprint "antmicro-footprints:QFN-48-1EP_7x7x0.9mm_P0.5mm_EP3.5x3.5mm" (layer "F.Cu")
    (at 103.2 96.45 -90)
    (property "Author" "Antmicro")
    (property "License" "Apache-2.0")
    (property "MPN" "KSZ9031RNXCA")
    (property "Manufacturer" "Microchip Technology")
    (property "Sheetfile" "ethernet.kicad_sch")
    (property "Sheetname" "Ethernet")
    (property "ki_description" "Ethernet Controller, 1000 Mbps, IEEE 802.3, 1.14 V, 3.465 V, QFN, 48 Pins")
    (property "ki_keywords" "SMT, TRANSCEIVER, IC, ETHERNET, PHY")
    (attr smd)
    (fp_text reference "U1" (at -4.66 4.66) (layer "F.SilkS")
        (effects (font (size 0.7 0.7) (thickness 0.127)) (justify left))
    )
    (fp_text value "KSZ9031RNXCA" (at 0.0254 5.7404 90) (layer "F.Fab")
        (effects (font (size 1.27 1.27) (thickness 0.15)))
    )
    (fp_text user "Author: Antmicro" (at -4.202 8.4 -90) (layer "F.Fab") hide
        (effects (font (size 0.7 0.7) (thickness 0.15)) (justify left bottom))
    )
    (fp_text user "License: Apache-2.0" (at -4.202 9.598 -90) (layer "F.Fab") hide
        (effects (font (size 0.7 0.7) (thickness 0.15)) (justify left bottom))
    )
    (fp_text user "${REFERENCE}" (at -4.202 7.2 -90) (layer "F.Fab") hide
        (effects (font (size 0.7 0.7) (thickness 0.15)) (justify left bottom))
    )
    (fp_line (start -3.65 -3.3) (end -3.65 -3.65)
      (stroke (width 0.15) (type solid)) (layer "F.SilkS"))
    (fp_line (start -3.65 3.648) (end -3.65 3.249)
      (stroke (width 0.15) (type solid)) (layer "F.SilkS"))
    (fp_line (start -3.3 -3.65) (end -3.65 -3.65)
      (stroke (width 0.15) (type solid)) (layer "F.SilkS"))
    (fp_line (start -3.25 3.648) (end -3.65 3.648)
      (stroke (width 0.15) (type solid)) (layer "F.SilkS"))
    (fp_line (start 3.249 -3.65) (end 3.648 -3.65)
      (stroke (width 0.15) (type solid)) (layer "F.SilkS"))
    (fp_line (start 3.249 3.648) (end 3.648 3.648)
      (stroke (width 0.15) (type solid)) (layer "F.SilkS"))
    (fp_line (start 3.648 -3.65) (end 3.648 -3.25)
      (stroke (width 0.15) (type solid)) (layer "F.SilkS"))
    (fp_line (start 3.648 3.648) (end 3.648 3.249)
      (stroke (width 0.15) (type solid)) (layer "F.SilkS"))
    (fp_circle (center -3.7 -3.05) (end -3.65 -3.05)
      (stroke (width 0.15) (type solid)) (fill solid) (layer "F.SilkS"))
    (fp_rect (start -4.15 -4.15) (end 4.15 4.15)
      (stroke (width 0.05) (type solid)) (fill none) (layer "F.CrtYd"))
    (fp_line (start -3.5 -2.5) (end -3.5 3.499)
      (stroke (width 0.15) (type solid)) (layer "F.Fab"))
    (fp_line (start -3.5 3.499) (end 3.499 3.499)
      (stroke (width 0.15) (type solid)) (layer "F.Fab"))
    (fp_line (start -2.5 -3.5) (end -3.5 -2.5)
      (stroke (width 0.15) (type solid)) (layer "F.Fab"))
    (fp_line (start 3.499 -3.5) (end -2.5 -3.5)
      (stroke (width 0.15) (type solid)) (layer "F.Fab"))
    (fp_line (start 3.499 3.499) (end 3.499 -3.5)
      (stroke (width 0.15) (type solid)) (layer "F.Fab"))
    (pad "1" smd oval (at -3.5 -2.75) (size 0.3 0.9) (layers "F.Cu" "F.Paste" "F.Mask")
      (net 4 "/Ethernet/AVDDH") (pinfunction "AVDDH") (pintype "power_in"))
    (pad "2" smd oval (at -3.5 -2.25) (size 0.3 0.9) (layers "F.Cu" "F.Paste" "F.Mask")
      (net 148 "/Ethernet/ETH1_P") (pinfunction "TXRXP_A") (pintype "bidirectional"))
    (pad "3" smd oval (at -3.5 -1.75) (size 0.3 0.9) (layers "F.Cu" "F.Paste" "F.Mask")
      (net 151 "/Ethernet/ETH1_N") (pinfunction "TXRXM_A") (pintype "bidirectional"))
    (pad "4" smd oval (at -3.5 -1.25) (size 0.3 0.9) (layers "F.Cu" "F.Paste" "F.Mask")
      (net 9 "/Ethernet/AVDDL") (pinfunction "AVDDL") (pintype "power_in"))
    (pad "5" smd oval (at -3.5 -0.75) (size 0.3 0.9) (layers "F.Cu" "F.Paste" "F.Mask")
      (net 147 "/Ethernet/ETH2_P") (pinfunction "TXRXP_B") (pintype "bidirectional"))
    (pad "6" smd oval (at -3.5 -0.25) (size 0.3 0.9) (layers "F.Cu" "F.Paste" "F.Mask")
      (net 150 "/Ethernet/ETH2_N") (pinfunction "TXRXM_B") (pintype "bidirectional"))
    (pad "7" smd oval (at -3.5 0.248) (size 0.3 0.9) (layers "F.Cu" "F.Paste" "F.Mask")
      (net 146 "/Ethernet/ETH3_P") (pinfunction "TXRXP_C") (pintype "bidirectional"))
    (pad "8" smd oval (at -3.5 0.748) (size 0.3 0.9) (layers "F.Cu" "F.Paste" "F.Mask")
      (net 152 "/Ethernet/ETH3_N") (pinfunction "TXRXM_C") (pintype "bidirectional"))
    (pad "9" smd oval (at -3.5 1.249) (size 0.3 0.9) (layers "F.Cu" "F.Paste" "F.Mask")
      (net 9 "/Ethernet/AVDDL") (pinfunction "AVDDL") (pintype "passive"))
    (pad "10" smd oval (at -3.5 1.749) (size 0.3 0.9) (layers "F.Cu" "F.Paste" "F.Mask")
      (net 149 "/Ethernet/ETH4_P") (pinfunction "TXRXP_D") (pintype "bidirectional"))
    (pad "11" smd oval (at -3.5 2.249) (size 0.3 0.9) (layers "F.Cu" "F.Paste" "F.Mask")
      (net 153 "/Ethernet/ETH4_N") (pinfunction "TXRXM_D") (pintype "bidirectional"))
    (pad "12" smd oval (at -3.5 2.749) (size 0.3 0.9) (layers "F.Cu" "F.Paste" "F.Mask")
      (net 4 "/Ethernet/AVDDH") (pinfunction "AVDDH") (pintype "passive"))
    (pad "13" smd oval (at -2.75 3.499 270) (size 0.3 0.9) (layers "F.Cu" "F.Paste" "F.Mask")
      (net 438 "unconnected-(U1-NC-Pad13)") (pinfunction "NC") (pintype "no_connect"))
    (pad "14" smd oval (at -2.25 3.499 270) (size 0.3 0.9) (layers "F.Cu" "F.Paste" "F.Mask")
      (net 211 "VCC1V2") (pinfunction "DVDDL") (pintype "power_in"))
    (pad "15" smd oval (at -1.75 3.499 270) (size 0.3 0.9) (layers "F.Cu" "F.Paste" "F.Mask")
      (net 165 "/Ethernet/ETH_LED2") (pinfunction "LED2/PHYAD1") (pintype "bidirectional"))
    (pad "16" smd oval (at -1.25 3.499 270) (size 0.3 0.9) (layers "F.Cu" "F.Paste" "F.Mask")
      (net 2 "VCC3V3") (pinfunction "DVDDH") (pintype "power_in"))
    (pad "17" smd oval (at -0.75 3.499 270) (size 0.3 0.9) (layers "F.Cu" "F.Paste" "F.Mask")
      (net 164 "/Ethernet/ETH_LED1") (pinfunction "LED1/PHAD0/PME_N1") (pintype "bidirectional"))
    (pad "18" smd oval (at -0.25 3.499 270) (size 0.3 0.9) (layers "F.Cu" "F.Paste" "F.Mask")
      (net 211 "VCC1V2") (pinfunction "DVDDL") (pintype "passive"))
    (pad "19" smd oval (at 0.248 3.499 270) (size 0.3 0.9) (layers "F.Cu" "F.Paste" "F.Mask")
      (net 202 "RGMII_TXD0") (pinfunction "TXD0") (pintype "input"))
    (pad "20" smd oval (at 0.748 3.499 270) (size 0.3 0.9) (layers "F.Cu" "F.Paste" "F.Mask")
      (net 198 "RGMII_TXD1") (pinfunction "TXD1") (pintype "input"))
    (pad "21" smd oval (at 1.249 3.499 270) (size 0.3 0.9) (layers "F.Cu" "F.Paste" "F.Mask")
      (net 199 "RGMII_TXD2") (pinfunction "TXD2") (pintype "input"))
    (pad "22" smd oval (at 1.749 3.499 270) (size 0.3 0.9) (layers "F.Cu" "F.Paste" "F.Mask")
      (net 201 "RGMII_TXD3") (pinfunction "TXD3") (pintype "input"))
    (pad "23" smd oval (at 2.249 3.499 270) (size 0.3 0.9) (layers "F.Cu" "F.Paste" "F.Mask")
      (net 211 "VCC1V2") (pinfunction "DVDDL") (pintype "passive"))
    (pad "24" smd oval (at 2.749 3.499 270) (size 0.3 0.9) (layers "F.Cu" "F.Paste" "F.Mask")
      (net 200 "RGMII_TX_CLK") (pinfunction "GTX_CLK") (pintype "input"))
    (pad "25" smd oval (at 3.499 2.749) (size 0.3 0.9) (layers "F.Cu" "F.Paste" "F.Mask")
      (net 296 "RGMII_TX_EN") (pinfunction "TX_EN") (pintype "input"))
    (pad "26" smd oval (at 3.499 2.249) (size 0.3 0.9) (layers "F.Cu" "F.Paste" "F.Mask")
      (net 211 "VCC1V2") (pinfunction "DVDDL") (pintype "passive"))
    (pad "27" smd oval (at 3.499 1.749) (size 0.3 0.9) (layers "F.Cu" "F.Paste" "F.Mask")
      (net 157 "RGMII_RXD3") (pinfunction "RXD3/MODE3") (pintype "input"))
    (pad "28" smd oval (at 3.499 1.249) (size 0.3 0.9) (layers "F.Cu" "F.Paste" "F.Mask")
      (net 156 "RGMII_RXD2") (pinfunction "RXD2/MODE2") (pintype "input"))
    (pad "29" smd oval (at 3.499 0.748) (size 0.3 0.9) (layers "F.Cu" "F.Paste" "F.Mask")
      (net 1 "GND") (pinfunction "VSS") (pintype "power_in"))
    (pad "30" smd oval (at 3.499 0.248) (size 0.3 0.9) (layers "F.Cu" "F.Paste" "F.Mask")
      (net 211 "VCC1V2") (pinfunction "DVDDL") (pintype "passive"))
    (pad "31" smd oval (at 3.499 -0.25) (size 0.3 0.9) (layers "F.Cu" "F.Paste" "F.Mask")
      (net 155 "RGMII_RXD1") (pinfunction "RXD1/MODE1") (pintype "input"))
    (pad "32" smd oval (at 3.499 -0.75) (size 0.3 0.9) (layers "F.Cu" "F.Paste" "F.Mask")
      (net 154 "RGMII_RXD0") (pinfunction "RXD0/MODE0") (pintype "input"))
    (pad "33" smd oval (at 3.499 -1.25) (size 0.3 0.9) (layers "F.Cu" "F.Paste" "F.Mask")
      (net 158 "RGMII_RX_DV") (pinfunction "RX_DV/CLK125_EN") (pintype "input"))
    (pad "34" smd oval (at 3.499 -1.75) (size 0.3 0.9) (layers "F.Cu" "F.Paste" "F.Mask")
      (net 2 "VCC3V3") (pinfunction "DVDDH") (pintype "passive"))
    (pad "35" smd oval (at 3.499 -2.25) (size 0.3 0.9) (layers "F.Cu" "F.Paste" "F.Mask")
      (net 159 "RGMII_RX_CLK") (pinfunction "RX_CLK/PHYAD2") (pintype "input"))
    (pad "36" smd oval (at 3.499 -2.75) (size 0.3 0.9) (layers "F.Cu" "F.Paste" "F.Mask")
      (net 161 "ETH_MDC") (pinfunction "MDC") (pintype "input"))
    (pad "37" smd oval (at 2.749 -3.5 270) (size 0.3 0.9) (layers "F.Cu" "F.Paste" "F.Mask")
      (net 162 "ETH_MDIO") (pinfunction "MDIO") (pintype "input"))
    (pad "38" smd oval (at 2.249 -3.5 270) (size 0.3 0.9) (layers "F.Cu" "F.Paste" "F.Mask")
      (net 197 "ETH_INT_N") (pinfunction "~{INT/PME}") (pintype "input"))
    (pad "39" smd oval (at 1.749 -3.5 270) (size 0.3 0.9) (layers "F.Cu" "F.Paste" "F.Mask")
      (net 211 "VCC1V2") (pinfunction "DVDDL") (pintype "passive"))
    (pad "40" smd oval (at 1.249 -3.5 270) (size 0.3 0.9) (layers "F.Cu" "F.Paste" "F.Mask")
      (net 2 "VCC3V3") (pinfunction "DVDDH") (pintype "passive"))
    (pad "41" smd oval (at 0.748 -3.5 270) (size 0.3 0.9) (layers "F.Cu" "F.Paste" "F.Mask")
      (net 160 "RGMII_REF_CLK") (pinfunction "CLK125_NDO/LED_MODE") (pintype "input"))
    (pad "42" smd oval (at 0.248 -3.5 270) (size 0.3 0.9) (layers "F.Cu" "F.Paste" "F.Mask")
      (net 163 "ETH_~{RESET}") (pinfunction "~{RESET}") (pintype "input"))
    (pad "43" smd oval (at -0.25 -3.5 270) (size 0.3 0.9) (layers "F.Cu" "F.Paste" "F.Mask")
      (net 439 "unconnected-(U1-LDO_O-Pad43)") (pinfunction "LDO_O") (pintype "input+no_connect"))
    (pad "44" smd oval (at -0.75 -3.5 270) (size 0.3 0.9) (layers "F.Cu" "F.Paste" "F.Mask")
      (net 10 "/Ethernet/AVDDL_PLL") (pinfunction "AVDDL_PLL") (pintype "power_in"))
    (pad "45" smd oval (at -1.25 -3.5 270) (size 0.3 0.9) (layers "F.Cu" "F.Paste" "F.Mask")
      (net 440 "unconnected-(U1-XO-Pad45)") (pinfunction "XO") (pintype "input+no_connect"))
    (pad "46" smd oval (at -1.75 -3.5 270) (size 0.3 0.9) (layers "F.Cu" "F.Paste" "F.Mask")
      (net 676 "/Ethernet/PHY_CLK") (pinfunction "XI") (pintype "input"))
    (pad "47" smd oval (at -2.25 -3.5 270) (size 0.3 0.9) (layers "F.Cu" "F.Paste" "F.Mask")
      (net 441 "unconnected-(U1-NC-Pad47)") (pinfunction "NC") (pintype "no_connect"))
    (pad "48" smd oval (at -2.75 -3.5 270) (size 0.3 0.9) (layers "F.Cu" "F.Paste" "F.Mask")
      (net 402 "Net-(U1-ISET)") (pinfunction "ISET") (pintype "output"))
    (pad "49" smd rect (at 0 0 270) (size 3.5 3.5) (layers "F.Cu" "F.Paste" "F.Mask")
      (net 1 "GND") (pinfunction "PAD_GND") (pintype "power_in"))
  )

  (footprint "antmicro-footprints:C_0402_1005Metric" (layer "F.Cu")
    (at 111.25 97.63 90)
    (descr "Capacitor SMD 0402")
    (tags "capacitor SMD 0402")
    (property "Author" "Antmicro")
    (property "Dielectric" "X7R")
    (property "License" "Apache-2.0")
    (property "MPN" "GRM155R71H103KA88D")
    (property "Manufacturer" "Murata")
    (property "Public" "False")
    (property "Sheetfile" "ethernet.kicad_sch")
    (property "Sheetname" "Ethernet")
    (property "Val" "10n")
    (property "Voltage" "50V")
    (property "ki_description" "SMD Multilayer Ceramic Capacitor, 10000 pF, 50 V, 0402 [1005 Metric], ± 10%, X7R, GRM Series")
    (property "ki_keywords" "0402, SMT, CAPACITOR, PASSIVE")
    (attr smd)
    (fp_text reference "C20" (at 0.02 0.995 90) (layer "F.SilkS")
        (effects (font (size 0.7 0.7) (thickness 0.127)))
    )
    (fp_text value "C_10n_0402" (at 0 1.17 90) (layer "F.Fab")
        (effects (font (size 1 1) (thickness 0.15)))
    )
    (fp_text user "Author: Antmicro" (at -0.939 3.399 90) (layer "F.Fab") hide
        (effects (font (size 0.7 0.7) (thickness 0.15)) (justify left bottom))
    )
    (fp_text user "${REFERENCE}" (at 0 0 90) (layer "F.Fab")
        (effects (font (size 0.25 0.25) (thickness 0.04)))
    )
    (fp_text user "License: Apache-2.0" (at -0.939 5.799 90) (layer "F.Fab") hide
        (effects (font (size 0.7 0.7) (thickness 0.15)) (justify left bottom))
    )
    (fp_rect (start -0.925 -0.47) (end 0.925 0.47)
      (stroke (width 0.05) (type default)) (fill none) (layer "F.CrtYd"))
    (fp_line (start -0.494 -0.25) (end 0.504 -0.25)
      (stroke (width 0.15) (type solid)) (layer "F.Fab"))
    (fp_line (start -0.494 0.248) (end -0.494 -0.25)
      (stroke (width 0.15) (type solid)) (layer "F.Fab"))
    (fp_line (start 0.504 -0.25) (end 0.504 0.248)
      (stroke (width 0.15) (type solid)) (layer "F.Fab"))
    (fp_line (start 0.504 0.248) (end -0.494 0.248)
      (stroke (width 0.15) (type solid)) (layer "F.Fab"))
    (pad "1" smd roundrect (at -0.48 0 90) (size 0.59 0.64) (layers "F.Cu" "F.Paste" "F.Mask") (roundrect_rratio 0.25)
      (net 1 "GND") (pintype "passive"))
    (pad "2" smd roundrect (at 0.48 0 90) (size 0.59 0.64) (layers "F.Cu" "F.Paste" "F.Mask") (roundrect_rratio 0.25)
      (net 2 "VCC3V3") (pintype "passive"))
  )

  (footprint "antmicro-footprints:C_0402_1005Metric" (layer "F.Cu")
    (at 131 119.685)
    (descr "Capacitor SMD 0402")
    (tags "capacitor SMD 0402")
    (property "Author" "Antmicro")
    (property "Dielectric" "X7R")
    (property "License" "Apache-2.0")
    (property "MPN" "GRM155R71H103KA88D")
    (property "Manufacturer" "Murata")
    (property "Public" "False")
    (property "Sheetfile" "interfaces.kicad_sch")
    (property "Sheetname" "Interfaces")
    (property "Val" "10n")
    (property "Voltage" "50V")
    (property "ki_description" "SMD Multilayer Ceramic Capacitor, 10000 pF, 50 V, 0402 [1005 Metric], ± 10%, X7R, GRM Series")
    (property "ki_keywords" "0402, SMT, CAPACITOR, PASSIVE")
    (attr smd)
    (fp_text reference "C26" (at -0.035 1.025) (layer "F.SilkS")
        (effects (font (size 0.7 0.7) (thickness 0.127)))
    )
    (fp_text value "C_10n_0402" (at 0 1.17) (layer "F.Fab")
        (effects (font (size 1 1) (thickness 0.15)))
    )
    (fp_text user "License: Apache-2.0" (at -0.939 5.799) (layer "F.Fab") hide
        (effects (font (size 0.7 0.7) (thickness 0.15)) (justify left bottom))
    )
    (fp_text user "${REFERENCE}" (at 0 0) (layer "F.Fab")
        (effects (font (size 0.25 0.25) (thickness 0.04)))
    )
    (fp_text user "Author: Antmicro" (at -0.939 3.399) (layer "F.Fab") hide
        (effects (font (size 0.7 0.7) (thickness 0.15)) (justify left bottom))
    )
    (fp_rect (start -0.925 -0.47) (end 0.925 0.47)
      (stroke (width 0.05) (type default)) (fill none) (layer "F.CrtYd"))
    (fp_line (start -0.494 -0.25) (end 0.504 -0.25)
      (stroke (width 0.15) (type solid)) (layer "F.Fab"))
    (fp_line (start -0.494 0.248) (end -0.494 -0.25)
      (stroke (width 0.15) (type solid)) (layer "F.Fab"))
    (fp_line (start 0.504 -0.25) (end 0.504 0.248)
      (stroke (width 0.15) (type solid)) (layer "F.Fab"))
    (fp_line (start 0.504 0.248) (end -0.494 0.248)
      (stroke (width 0.15) (type solid)) (layer "F.Fab"))
    (pad "1" smd roundrect (at -0.48 0) (size 0.59 0.64) (layers "F.Cu" "F.Paste" "F.Mask") (roundrect_rratio 0.25)
      (net 1 "GND") (pintype "passive"))
    (pad "2" smd roundrect (at 0.48 0) (size 0.59 0.64) (layers "F.Cu" "F.Paste" "F.Mask") (roundrect_rratio 0.25)
      (net 2 "VCC3V3") (pintype "passive"))
  )

  (footprint "antmicro-footprints:R_0402_1005Metric" (layer "F.Cu")
    (at 101 104 -90)
    (descr "Resistor SMD 0402")
    (tags "resistor SMD 0402")
    (property "Author" "Antmicro")
    (property "License" "Apache-2.0")
    (property "MPN" "CR0402-FX-1022GLF")
    (property "Manufacturer" "Bourns")
    (property "Public" "False")
    (property "Sheetfile" "ethernet.kicad_sch")
    (property "Sheetname" "Ethernet")
    (property "Tolerance" "1%")
    (property "Val" "10k2")
    (property "ki_description" "SMD Chip Resistor")
    (property "ki_keywords" "0402, SMT, RESISTOR, PASSIVE")
    (attr smd)
    (fp_text reference "R4" (at 0.04 -8.96 90) (layer "F.SilkS")
        (effects (font (size 0.7 0.7) (thickness 0.127)))
    )
    (fp_text value "R_10k2_0402" (at 0 1.17 90) (layer "F.Fab")
        (effects (font (size 1 1) (thickness 0.15)))
    )
    (fp_text user "License: Apache-2.0" (at -0.95 5.169 -90) (layer "F.Fab") hide
        (effects (font (size 0.7 0.7) (thickness 0.15)) (justify left bottom))
    )
    (fp_text user "${REFERENCE}" (at 0 0 90) (layer "F.Fab")
        (effects (font (size 0.25 0.25) (thickness 0.04)))
    )
    (fp_text user "Author: Antmicro" (at -0.95 4.169 -90) (layer "F.Fab") hide
        (effects (font (size 0.7 0.7) (thickness 0.15)) (justify left bottom))
    )
    (fp_rect (start -0.925 -0.47) (end 0.925 0.47)
      (stroke (width 0.05) (type default)) (fill none) (layer "F.CrtYd"))
    (fp_rect (start -0.5 -0.25) (end 0.5 0.25)
      (stroke (width 0.15) (type solid)) (fill none) (layer "F.Fab"))
    (pad "1" smd roundrect (at -0.48 0 270) (size 0.59 0.64) (layers "F.Cu" "F.Paste" "F.Mask") (roundrect_rratio 0.25)
      (net 157 "RGMII_RXD3") (pintype "passive"))
    (pad "2" smd roundrect (at 0.48 0 270) (size 0.59 0.64) (layers "F.Cu" "F.Paste" "F.Mask") (roundrect_rratio 0.25)
      (net 2 "VCC3V3") (pintype "passive"))
  )

  (footprint "antmicro-footprints:R_0402_1005Metric" (layer "F.Cu")
    (at 102 104 -90)
    (descr "Resistor SMD 0402")
    (tags "resistor SMD 0402")
    (property "Author" "Antmicro")
    (property "License" "Apache-2.0")
    (property "MPN" "CR0402-FX-1022GLF")
    (property "Manufacturer" "Bourns")
    (property "Public" "False")
    (property "Sheetfile" "ethernet.kicad_sch")
    (property "Sheetname" "Ethernet")
    (property "Tolerance" "1%")
    (property "Val" "10k2")
    (property "ki_description" "SMD Chip Resistor")
    (property "ki_keywords" "0402, SMT, RESISTOR, PASSIVE")
    (attr smd)
    (fp_text reference "R3" (at 0.04 -8.955476 90) (layer "F.SilkS")
        (effects (font (size 0.7 0.7) (thickness 0.127)))
    )
    (fp_text value "R_10k2_0402" (at 0 1.17 90) (layer "F.Fab")
        (effects (font (size 1 1) (thickness 0.15)))
    )
    (fp_text user "License: Apache-2.0" (at -0.95 5.169 -90) (layer "F.Fab") hide
        (effects (font (size 0.7 0.7) (thickness 0.15)) (justify left bottom))
    )
    (fp_text user "${REFERENCE}" (at 0 0 90) (layer "F.Fab")
        (effects (font (size 0.25 0.25) (thickness 0.04)))
    )
    (fp_text user "Author: Antmicro" (at -0.95 4.169 -90) (layer "F.Fab") hide
        (effects (font (size 0.7 0.7) (thickness 0.15)) (justify left bottom))
    )
    (fp_rect (start -0.925 -0.47) (end 0.925 0.47)
      (stroke (width 0.05) (type default)) (fill none) (layer "F.CrtYd"))
    (fp_rect (start -0.5 -0.25) (end 0.5 0.25)
      (stroke (width 0.15) (type solid)) (fill none) (layer "F.Fab"))
    (pad "1" smd roundrect (at -0.48 0 270) (size 0.59 0.64) (layers "F.Cu" "F.Paste" "F.Mask") (roundrect_rratio 0.25)
      (net 156 "RGMII_RXD2") (pintype "passive"))
    (pad "2" smd roundrect (at 0.48 0 270) (size 0.59 0.64) (layers "F.Cu" "F.Paste" "F.Mask") (roundrect_rratio 0.25)
      (net 2 "VCC3V3") (pintype "passive"))
  )

  (footprint "antmicro-footprints:R_0402_1005Metric" (layer "F.Cu")
    (at 103 104 -90)
    (descr "Resistor SMD 0402")
    (tags "resistor SMD 0402")
    (property "Author" "Antmicro")
    (property "License" "Apache-2.0")
    (property "MPN" "CR0402-FX-1022GLF")
    (property "Manufacturer" "Bourns")
    (property "Public" "False")
    (property "Sheetfile" "ethernet.kicad_sch")
    (property "Sheetname" "Ethernet")
    (property "Tolerance" "1%")
    (property "Val" "10k2")
    (property "ki_description" "SMD Chip Resistor")
    (property "ki_keywords" "0402, SMT, RESISTOR, PASSIVE")
    (attr smd)
    (fp_text reference "R2" (at 0.04 -8.950952 90) (layer "F.SilkS")
        (effects (font (size 0.7 0.7) (thickness 0.127)))
    )
    (fp_text value "R_10k2_0402" (at 0 1.17 90) (layer "F.Fab")
        (effects (font (size 1 1) (thickness 0.15)))
    )
    (fp_text user "License: Apache-2.0" (at -0.95 5.169 -90) (layer "F.Fab") hide
        (effects (font (size 0.7 0.7) (thickness 0.15)) (justify left bottom))
    )
    (fp_text user "${REFERENCE}" (at 0 0 90) (layer "F.Fab")
        (effects (font (size 0.25 0.25) (thickness 0.04)))
    )
    (fp_text user "Author: Antmicro" (at -0.95 4.169 -90) (layer "F.Fab") hide
        (effects (font (size 0.7 0.7) (thickness 0.15)) (justify left bottom))
    )
    (fp_rect (start -0.925 -0.47) (end 0.925 0.47)
      (stroke (width 0.05) (type default)) (fill none) (layer "F.CrtYd"))
    (fp_rect (start -0.5 -0.25) (end 0.5 0.25)
      (stroke (width 0.15) (type solid)) (fill none) (layer "F.Fab"))
    (pad "1" smd roundrect (at -0.48 0 270) (size 0.59 0.64) (layers "F.Cu" "F.Paste" "F.Mask") (roundrect_rratio 0.25)
      (net 155 "RGMII_RXD1") (pintype "passive"))
    (pad "2" smd roundrect (at 0.48 0 270) (size 0.59 0.64) (layers "F.Cu" "F.Paste" "F.Mask") (roundrect_rratio 0.25)
      (net 2 "VCC3V3") (pintype "passive"))
  )

  (footprint "antmicro-footprints:R_0402_1005Metric" (layer "F.Cu")
    (at 104 104 -90)
    (descr "Resistor SMD 0402")
    (tags "resistor SMD 0402")
    (property "Author" "Antmicro")
    (property "License" "Apache-2.0")
    (property "MPN" "CR0402-FX-1022GLF")
    (property "Manufacturer" "Bourns")
    (property "Public" "False")
    (property "Sheetfile" "ethernet.kicad_sch")
    (property "Sheetname" "Ethernet")
    (property "Tolerance" "1%")
    (property "Val" "10k2")
    (property "ki_description" "SMD Chip Resistor")
    (property "ki_keywords" "0402, SMT, RESISTOR, PASSIVE")
    (attr smd)
    (fp_text reference "R1" (at 0.04 -8.946428 90) (layer "F.SilkS")
        (effects (font (size 0.7 0.7) (thickness 0.127)))
    )
    (fp_text value "R_10k2_0402" (at 0 1.17 90) (layer "F.Fab")
        (effects (font (size 1 1) (thickness 0.15)))
    )
    (fp_text user "Author: Antmicro" (at -0.95 4.169 -90) (layer "F.Fab") hide
        (effects (font (size 0.7 0.7) (thickness 0.15)) (justify left bottom))
    )
    (fp_text user "License: Apache-2.0" (at -0.95 5.169 -90) (layer "F.Fab") hide
        (effects (font (size 0.7 0.7) (thickness 0.15)) (justify left bottom))
    )
    (fp_text user "${REFERENCE}" (at 0 0 90) (layer "F.Fab")
        (effects (font (size 0.25 0.25) (thickness 0.04)))
    )
    (fp_rect (start -0.925 -0.47) (end 0.925 0.47)
      (stroke (width 0.05) (type default)) (fill none) (layer "F.CrtYd"))
    (fp_rect (start -0.5 -0.25) (end 0.5 0.25)
      (stroke (width 0.15) (type solid)) (fill none) (layer "F.Fab"))
    (pad "1" smd roundrect (at -0.48 0 270) (size 0.59 0.64) (layers "F.Cu" "F.Paste" "F.Mask") (roundrect_rratio 0.25)
      (net 154 "RGMII_RXD0") (pintype "passive"))
    (pad "2" smd roundrect (at 0.48 0 270) (size 0.59 0.64) (layers "F.Cu" "F.Paste" "F.Mask") (roundrect_rratio 0.25)
      (net 2 "VCC3V3") (pintype "passive"))
  )

  (footprint "antmicro-footprints:R_0402_1005Metric" (layer "F.Cu")
    (at 108.95 93.75 180)
    (descr "Resistor SMD 0402")
    (tags "resistor SMD 0402")
    (property "Author" "Antmicro")
    (property "License" "Apache-2.0")
    (property "MPN" "CR0402-FX-1212GLF")
    (property "Manufacturer" "Bourns")
    (property "Public" "False")
    (property "Sheetfile" "ethernet.kicad_sch")
    (property "Sheetname" "Ethernet")
    (property "Tolerance" "1%")
    (property "Val" "12k1")
    (property "ki_description" "SMD Chip Resistor, 12.1 kohm, ± 1%, 62.5 mW, 0402 [1005 Metric], Thick Film, General Purpose")
    (property "ki_keywords" "0402, SMT, RESISTOR, PASSIVE")
    (attr smd)
    (fp_text reference "R13" (at -0.01 1.1) (layer "F.SilkS")
        (effects (font (size 0.7 0.7) (thickness 0.127)))
    )
    (fp_text value "R_12k1_0402" (at 0 1.17) (layer "F.Fab")
        (effects (font (size 1 1) (thickness 0.15)))
    )
    (fp_text user "License: Apache-2.0" (at -0.95 5.169 180) (layer "F.Fab") hide
        (effects (font (size 0.7 0.7) (thickness 0.15)) (justify left bottom))
    )
    (fp_text user "${REFERENCE}" (at 0 0) (layer "F.Fab")
        (effects (font (size 0.25 0.25) (thickness 0.04)))
    )
    (fp_text user "Author: Antmicro" (at -0.95 4.169 180) (layer "F.Fab") hide
        (effects (font (size 0.7 0.7) (thickness 0.15)) (justify left bottom))
    )
    (fp_rect (start -0.925 -0.47) (end 0.925 0.47)
      (stroke (width 0.05) (type default)) (fill none) (layer "F.CrtYd"))
    (fp_rect (start -0.5 -0.25) (end 0.5 0.25)
      (stroke (width 0.15) (type solid)) (fill none) (layer "F.Fab"))
    (pad "1" smd roundrect (at -0.48 0 180) (size 0.59 0.64) (layers "F.Cu" "F.Paste" "F.Mask") (roundrect_rratio 0.25)
      (net 1 "GND") (pintype "passive"))
    (pad "2" smd roundrect (at 0.48 0 180) (size 0.59 0.64) (layers "F.Cu" "F.Paste" "F.Mask") (roundrect_rratio 0.25)
      (net 402 "Net-(U1-ISET)") (pintype "passive"))
  )

  (footprint "antmicro-footprints:R_0402_1005Metric" (layer "F.Cu")
    (at 108.95 96.15 180)
    (descr "Resistor SMD 0402")
    (tags "resistor SMD 0402")
    (property "Author" "Antmicro")
    (property "License" "Apache-2.0")
    (property "MPN" "CR0402-FX-4701GLF")
    (property "Manufacturer" "Bourns")
    (property "Public" "False")
    (property "Sheetfile" "ethernet.kicad_sch")
    (property "Sheetname" "Ethernet")
    (property "Tolerance" "1%")
    (property "Val" "4k7")
    (property "ki_description" "SMD Chip Resistor, 4.7 kohm, ± 1%, 62.5 mW, 0402 [1005 Metric], Thick Film, General Purpose")
    (property "ki_keywords" "0402, SMT, RESISTOR, PASSIVE")
    (attr smd)
    (fp_text reference "R48" (at -0.075 1.075) (layer "F.SilkS")
        (effects (font (size 0.7 0.7) (thickness 0.127)))
    )
    (fp_text value "R_4k7_0402" (at 0 1.17) (layer "F.Fab")
        (effects (font (size 1 1) (thickness 0.15)))
    )
    (fp_text user "${REFERENCE}" (at 0 0) (layer "F.Fab")
        (effects (font (size 0.25 0.25) (thickness 0.04)))
    )
    (fp_text user "Author: Antmicro" (at -0.95 4.169 180) (layer "F.Fab") hide
        (effects (font (size 0.7 0.7) (thickness 0.15)) (justify left bottom))
    )
    (fp_text user "License: Apache-2.0" (at -0.95 5.169 180) (layer "F.Fab") hide
        (effects (font (size 0.7 0.7) (thickness 0.15)) (justify left bottom))
    )
    (fp_rect (start -0.925 -0.47) (end 0.925 0.47)
      (stroke (width 0.05) (type default)) (fill none) (layer "F.CrtYd"))
    (fp_rect (start -0.5 -0.25) (end 0.5 0.25)
      (stroke (width 0.15) (type solid)) (fill none) (layer "F.Fab"))
    (pad "1" smd roundrect (at -0.48 0 180) (size 0.59 0.64) (layers "F.Cu" "F.Paste" "F.Mask") (roundrect_rratio 0.25)
      (net 2 "VCC3V3") (pintype "passive"))
    (pad "2" smd roundrect (at 0.48 0 180) (size 0.59 0.64) (layers "F.Cu" "F.Paste" "F.Mask") (roundrect_rratio 0.25)
      (net 163 "ETH_~{RESET}") (pintype "passive"))
  )

  (footprint "antmicro-footprints:QFN-32-1EP_5x5mm" locked (layer "F.Cu")
    (at 125.034 115.794 -90)
    (property "Author" "Antmicro")
    (property "License" "Apache-2.0")
    (property "MPN" "USB3300-EZK-TR")
    (property "Manufacturer" "Microchip Technology")
    (property "Sheetfile" "interfaces.kicad_sch")
    (property "Sheetname" "Interfaces")
    (property "ki_description" "USB Interface, USB Host Controller, USB 2.0 OTG, 3 V, 3.6 V, VQFN, 32 Pins")
    (property "ki_keywords" "SMT, INTERFACE, CONTROLLER, IC, USB")
    (attr smd)
    (fp_text reference "U9" (at -3.469 -3.036 90) (layer "F.SilkS")
        (effects (font (size 0.7 0.7) (thickness 0.12051)))
    )
    (fp_text value "USB3300-EZK-TR" (at 3.23987 3.520501 90) (layer "F.Fab")
        (effects (font (size 0.482094 0.482094) (thickness 0.015)))
    )
    (fp_text user "License: Apache-2.0" (at -4.939 5.91 -90) (layer "F.Fab") hide
        (effects (font (size 0.7 0.7) (thickness 0.15)) (justify left bottom))
    )
    (fp_text user "Author: Antmicro" (at -4.939 8.31 -90) (layer "F.Fab") hide
        (effects (font (size 0.7 0.7) (thickness 0.15)) (justify left bottom))
    )
    (fp_text user "${REFERENCE}" (at -4.939 7.11 -90) (layer "F.Fab") hide
        (effects (font (size 0.7 0.7) (thickness 0.15)) (justify left bottom))
    )
    (fp_rect (start -1.446 -0.175) (end -0.246 -1.375)
      (stroke (width 0.2) (type solid)) (fill solid) (layer "F.Paste"))
    (fp_rect (start -1.446 1.474) (end -0.246 0.274)
      (stroke (width 0.2) (type solid)) (fill solid) (layer "F.Paste"))
    (fp_rect (start 0.203 -0.175) (end 1.403 -1.375)
      (stroke (width 0.2) (type solid)) (fill solid) (layer "F.Paste"))
    (fp_rect (start 0.203 1.474) (end 1.403 0.274)
      (stroke (width 0.2) (type solid)) (fill solid) (layer "F.Paste"))
    (fp_line (start -2.62 2.648) (end -2.62 2.249)
      (stroke (width 0.15) (type solid)) (layer "F.SilkS"))
    (fp_line (start -2.221 -2.551) (end -2.62 -2.149)
      (stroke (width 0.15) (type solid)) (layer "F.SilkS"))
    (fp_line (start -2.221 2.648) (end -2.62 2.648)
      (stroke (width 0.15) (type solid)) (layer "F.SilkS"))
    (fp_line (start 2.581 -2.551) (end 2.178 -2.551)
      (stroke (width 0.15) (type solid)) (layer "F.SilkS"))
    (fp_line (start 2.581 -2.551) (end 2.581 -2.149)
      (stroke (width 0.15) (type solid)) (layer "F.SilkS"))
    (fp_line (start 2.581 2.249) (end 2.581 2.648)
      (stroke (width 0.15) (type solid)) (layer "F.SilkS"))
    (fp_line (start 2.581 2.648) (end 2.178 2.648)
      (stroke (width 0.15) (type solid)) (layer "F.SilkS"))
    (fp_circle (center -3.25 -1.702) (end -3.2 -1.702)
      (stroke (width 0.15) (type solid)) (fill solid) (layer "F.SilkS"))
    (fp_rect (start -2.74 -2.75) (end 2.75 2.74)
      (stroke (width 0.05) (type solid)) (fill none) (layer "F.CrtYd"))
    (fp_line (start -2.499 -2.299) (end -2.298 -2.5)
      (stroke (width 0.15) (type solid)) (layer "F.Fab"))
    (fp_rect (start -2.499 -2.5) (end 2.5 2.499)
      (stroke (width 0.15) (type solid)) (fill none) (layer "F.Fab"))
    (pad "1" smd rect locked (at -2.495 -1.702 180) (size 0.28 0.85) (layers "F.Cu" "F.Paste" "F.Mask")
      (net 1 "GND") (pinfunction "GND") (pintype "power_in") (solder_mask_margin 0.07))
    (pad "2" smd rect locked (at -2.495 -1.2 180) (size 0.28 0.85) (layers "F.Cu" "F.Paste" "F.Mask")
      (net 1 "GND") (pinfunction "GND") (pintype "passive") (solder_mask_margin 0.07))
    (pad "3" smd rect locked (at -2.495 -0.701 180) (size 0.28 0.85) (layers "F.Cu" "F.Paste" "F.Mask")
      (net 500 "unconnected-(U9-CPEN-Pad3)") (pinfunction "CPEN") (pintype "output+no_connect") (solder_mask_margin 0.07))
    (pad "4" smd rect locked (at -2.495 -0.201 180) (size 0.28 0.85) (layers "F.Cu" "F.Paste" "F.Mask")
      (net 406 "Net-(U9-VBUS)") (pinfunction "VBUS") (pintype "bidirectional") (solder_mask_margin 0.07))
    (pad "5" smd rect locked (at -2.495 0.296 180) (size 0.28 0.85) (layers "F.Cu" "F.Paste" "F.Mask")
      (net 501 "unconnected-(U9-ID-Pad5)") (pinfunction "ID") (pintype "input+no_connect") (solder_mask_margin 0.07))
    (pad "6" smd rect locked (at -2.495 0.8 180) (size 0.28 0.85) (layers "F.Cu" "F.Paste" "F.Mask")
      (net 2 "VCC3V3") (pinfunction "VDD3.3") (pintype "power_in") (solder_mask_margin 0.07))
    (pad "7" smd rect locked (at -2.495 1.3 180) (size 0.28 0.85) (layers "F.Cu" "F.Paste" "F.Mask")
      (net 100 "USB1_DP") (pinfunction "DP") (pintype "bidirectional") (solder_mask_margin 0.07))
    (pad "8" smd rect locked (at -2.495 1.8 180) (size 0.28 0.85) (layers "F.Cu" "F.Paste" "F.Mask")
      (net 101 "USB1_DN") (pinfunction "DM") (pintype "bidirectional") (solder_mask_margin 0.07))
    (pad "9" smd rect locked (at -1.768 2.523 180) (size 0.85 0.28) (layers "F.Cu" "F.Paste" "F.Mask")
      (net 330 "ULPI1_RESET") (pinfunction "RESET") (pintype "input") (solder_mask_margin 0.07))
    (pad "10" smd rect locked (at -1.269 2.523 180) (size 0.85 0.28) (layers "F.Cu" "F.Paste" "F.Mask")
      (net 502 "unconnected-(U9-EXTVBUS-Pad10)") (pinfunction "EXTVBUS") (pintype "input+no_connect") (solder_mask_margin 0.07))
    (pad "11" smd rect locked (at -0.772 2.523 180) (size 0.85 0.28) (layers "F.Cu" "F.Paste" "F.Mask")
      (net 331 "ULPI1_NXT") (pinfunction "NXT") (pintype "output") (solder_mask_margin 0.07))
    (pad "12" smd rect locked (at -0.272 2.523 180) (size 0.85 0.28) (layers "F.Cu" "F.Paste" "F.Mask")
      (net 332 "ULPI1_DIR") (pinfunction "DIR") (pintype "output") (solder_mask_margin 0.07))
    (pad "13" smd rect locked (at 0.229 2.523 180) (size 0.85 0.28) (layers "F.Cu" "F.Paste" "F.Mask")
      (net 333 "ULPI1_STP") (pinfunction "STP") (pintype "input") (solder_mask_margin 0.07))
    (pad "14" smd rect locked (at 0.728 2.523 180) (size 0.85 0.28) (layers "F.Cu" "F.Paste" "F.Mask")
      (net 334 "ULPI1_CLKO") (pinfunction "CLKOUT") (pintype "output") (solder_mask_margin 0.07))
    (pad "15" smd rect locked (at 1.23 2.523 180) (size 0.85 0.28) (layers "F.Cu" "F.Paste" "F.Mask")
      (net 672 "Net-(C76-Pad2)") (pinfunction "VDD1.8") (pintype "power_in") (solder_mask_margin 0.07))
    (pad "16" smd rect locked (at 1.73 2.523 180) (size 0.85 0.28) (layers "F.Cu" "F.Paste" "F.Mask")
      (net 2 "VCC3V3") (pinfunction "VDD3.3") (pintype "passive") (solder_mask_margin 0.07))
    (pad "17" smd rect locked (at 2.456 1.8 180) (size 0.28 0.85) (layers "F.Cu" "F.Paste" "F.Mask")
      (net 335 "ULPI1_D7") (pinfunction "DATA[7]") (pintype "bidirectional") (solder_mask_margin 0.07))
    (pad "18" smd rect locked (at 2.456 1.3 180) (size 0.28 0.85) (layers "F.Cu" "F.Paste" "F.Mask")
      (net 336 "ULPI1_D6") (pinfunction "DATA[6]") (pintype "bidirectional") (solder_mask_margin 0.07))
    (pad "19" smd rect locked (at 2.456 0.8 180) (size 0.28 0.85) (layers "F.Cu" "F.Paste" "F.Mask")
      (net 337 "ULPI1_D5") (pinfunction "DATA[5]") (pintype "bidirectional") (solder_mask_margin 0.07))
    (pad "20" smd rect locked (at 2.456 0.296 180) (size 0.28 0.85) (layers "F.Cu" "F.Paste" "F.Mask")
      (net 338 "ULPI1_D4") (pinfunction "DATA[4]") (pintype "bidirectional") (solder_mask_margin 0.07))
    (pad "21" smd rect locked (at 2.456 -0.201 180) (size 0.28 0.85) (layers "F.Cu" "F.Paste" "F.Mask")
      (net 339 "ULPI1_D3") (pinfunction "DATA[3]") (pintype "bidirectional") (solder_mask_margin 0.07))
    (pad "22" smd rect locked (at 2.456 -0.701 180) (size 0.28 0.85) (layers "F.Cu" "F.Paste" "F.Mask")
      (net 340 "ULPI1_D2") (pinfunction "DATA[2]") (pintype "bidirectional") (solder_mask_margin 0.07))
    (pad "23" smd rect locked (at 2.456 -1.2 180) (size 0.28 0.85) (layers "F.Cu" "F.Paste" "F.Mask")
      (net 341 "ULPI1_D1") (pinfunction "DATA[1]") (pintype "bidirectional") (solder_mask_margin 0.07))
    (pad "24" smd rect locked (at 2.456 -1.702 180) (size 0.28 0.85) (layers "F.Cu" "F.Paste" "F.Mask")
      (net 342 "ULPI1_D0") (pinfunction "DATA[0]") (pintype "bidirectional") (solder_mask_margin 0.07))
    (pad "25" smd rect locked (at 1.73 -2.426 180) (size 0.85 0.28) (layers "F.Cu" "F.Paste" "F.Mask")
      (net 2 "VCC3V3") (pinfunction "VDD3.3") (pintype "passive") (solder_mask_margin 0.07))
    (pad "26" smd rect locked (at 1.23 -2.426 180) (size 0.85 0.28) (layers "F.Cu" "F.Paste" "F.Mask")
      (net 672 "Net-(C76-Pad2)") (pinfunction "VDD1.8") (pintype "passive") (solder_mask_margin 0.07))
    (pad "27" smd rect locked (at 0.728 -2.426 180) (size 0.85 0.28) (layers "F.Cu" "F.Paste" "F.Mask")
      (net 503 "unconnected-(U9-XO-Pad27)") (pinfunction "XO") (pintype "output+no_connect") (solder_mask_margin 0.07))
    (pad "28" smd rect locked (at 0.229 -2.426 180) (size 0.85 0.28) (layers "F.Cu" "F.Paste" "F.Mask")
      (net 679 "/Interfaces/USB1_CLK") (pinfunction "XI") (pintype "input") (solder_mask_margin 0.07))
    (pad "29" smd rect locked (at -0.272 -2.426 180) (size 0.85 0.28) (layers "F.Cu" "F.Paste" "F.Mask")
      (net 226 "Net-(U9-VDDA1.8)") (pinfunction "VDDA1.8") (pintype "power_in") (solder_mask_margin 0.07))
    (pad "30" smd rect locked (at -0.772 -2.426 180) (size 0.85 0.28) (layers "F.Cu" "F.Paste" "F.Mask")
      (net 2 "VCC3V3") (pinfunction "VDD3.3") (pintype "passive") (solder_mask_margin 0.07))
    (pad "31" smd rect locked (at -1.269 -2.426 180) (size 0.85 0.28) (layers "F.Cu" "F.Paste" "F.Mask")
      (net 2 "VCC3V3") (pinfunction "REG_EN") (pintype "bidirectional") (solder_mask_margin 0.07))
    (pad "32" smd rect locked (at -1.768 -2.426 180) (size 0.85 0.28) (layers "F.Cu" "F.Paste" "F.Mask")
      (net 407 "Net-(U9-RBIAS)") (pinfunction "RBIAS") (pintype "bidirectional") (solder_mask_margin 0.07))
    (pad "33" smd rect locked (at -0.02 0.048 180) (size 3.45 3.45) (layers "F.Cu" "F.Mask")
      (net 1 "GND") (pinfunction "EP") (pintype "passive"))
  )

  (footprint "antmicro-footprints:R_0402_1005Metric" (layer "F.Cu")
    (at 129.3 113.65 -90)
    (descr "Resistor SMD 0402")
    (tags "resistor SMD 0402")
    (property "Author" "Antmicro")
    (property "License" "Apache-2.0")
    (property "MPN" "CR0402-FX-1202GLF")
    (property "Manufacturer" "Bourns")
    (property "Public" "False")
    (property "Sheetfile" "interfaces.kicad_sch")
    (property "Sheetname" "Interfaces")
    (property "Tolerance" "1%")
    (property "Val" "12k")
    (property "ki_description" "SMD Chip Resistor, 12 kohm, ± 1%, 62.5 mW, 0402 [1005 Metric], Thick Film, General Purpose")
    (property "ki_keywords" "0402, SMT, RESISTOR, PASSIVE")
    (attr smd)
    (fp_text reference "R77" (at -2.61 0.02 90) (layer "F.SilkS")
        (effects (font (size 0.7 0.7) (thickness 0.127)))
    )
    (fp_text value "R_12k_0402" (at 0 1.17 90) (layer "F.Fab")
        (effects (font (size 1 1) (thickness 0.15)))
    )
    (fp_text user "Author: Antmicro" (at -0.95 4.169 -90) (layer "F.Fab") hide
        (effects (font (size 0.7 0.7) (thickness 0.15)) (justify left bottom))
    )
    (fp_text user "${REFERENCE}" (at 0 0 90) (layer "F.Fab")
        (effects (font (size 0.25 0.25) (thickness 0.04)))
    )
    (fp_text user "License: Apache-2.0" (at -0.95 5.169 -90) (layer "F.Fab") hide
        (effects (font (size 0.7 0.7) (thickness 0.15)) (justify left bottom))
    )
    (fp_rect (start -0.925 -0.47) (end 0.925 0.47)
      (stroke (width 0.05) (type default)) (fill none) (layer "F.CrtYd"))
    (fp_rect (start -0.5 -0.25) (end 0.5 0.25)
      (stroke (width 0.15) (type solid)) (fill none) (layer "F.Fab"))
    (pad "1" smd roundrect (at -0.48 0 270) (size 0.59 0.64) (layers "F.Cu" "F.Paste" "F.Mask") (roundrect_rratio 0.25)
      (net 1 "GND") (pintype "passive"))
    (pad "2" smd roundrect (at 0.48 0 270) (size 0.59 0.64) (layers "F.Cu" "F.Paste" "F.Mask") (roundrect_rratio 0.25)
      (net 407 "Net-(U9-RBIAS)") (pintype "passive"))
  )

  (footprint "antmicro-footprints:C_0402_1005Metric" (layer "F.Cu")
    (at 135.7 154.9 -90)
    (descr "Capacitor SMD 0402")
    (tags "capacitor SMD 0402")
    (property "Author" "Antmicro")
    (property "Dielectric" "")
    (property "License" "Apache-2.0")
    (property "MPN" "CC0402MRX5R5BB106")
    (property "Manufacturer" "YAGEO")
    (property "Public" "False")
    (property "Sheetfile" "pcie-conn.kicad_sch")
    (property "Sheetname" "PCIe-connector")
    (property "Val" "10u")
    (property "Voltage" "")
    (property "ki_description" "SMD Multilayer Ceramic Capacitor, 10 µF, 6.3 V, 0402 [1005 Metric], ± 20%, X5R, CC Series")
    (property "ki_keywords" "0402, SMT, CAPACITOR, PASSIVE, MLCC, CERAMIC")
    (attr smd)
    (fp_text reference "C41" (at -2.505 0.03 90) (layer "F.SilkS")
        (effects (font (size 0.7 0.7) (thickness 0.127)))
    )
    (fp_text value "C_10u_0402" (at 0 1.17 90) (layer "F.Fab")
        (effects (font (size 1 1) (thickness 0.15)))
    )
    (fp_text user "Author: Antmicro" (at -0.939 3.399 -90) (layer "F.Fab") hide
        (effects (font (size 0.7 0.7) (thickness 0.15)) (justify left bottom))
    )
    (fp_text user "License: Apache-2.0" (at -0.939 5.799 -90) (layer "F.Fab") hide
        (effects (font (size 0.7 0.7) (thickness 0.15)) (justify left bottom))
    )
    (fp_text user "${REFERENCE}" (at 0 0 90) (layer "F.Fab")
        (effects (font (size 0.25 0.25) (thickness 0.04)))
    )
    (fp_rect (start -0.925 -0.47) (end 0.925 0.47)
      (stroke (width 0.05) (type default)) (fill none) (layer "F.CrtYd"))
    (fp_line (start -0.494 -0.25) (end 0.504 -0.25)
      (stroke (width 0.15) (type solid)) (layer "F.Fab"))
    (fp_line (start -0.494 0.248) (end -0.494 -0.25)
      (stroke (width 0.15) (type solid)) (layer "F.Fab"))
    (fp_line (start 0.504 -0.25) (end 0.504 0.248)
      (stroke (width 0.15) (type solid)) (layer "F.Fab"))
    (fp_line (start 0.504 0.248) (end -0.494 0.248)
      (stroke (width 0.15) (type solid)) (layer "F.Fab"))
    (pad "1" smd roundrect (at -0.48 0 270) (size 0.59 0.64) (layers "F.Cu" "F.Paste" "F.Mask") (roundrect_rratio 0.25)
      (net 1 "GND") (pintype "passive"))
    (pad "2" smd roundrect (at 0.48 0 270) (size 0.59 0.64) (layers "F.Cu" "F.Paste" "F.Mask") (roundrect_rratio 0.25)
      (net 2 "VCC3V3") (pintype "passive"))
  )

  (footprint "antmicro-footprints:C_0402_1005Metric" (layer "F.Cu")
    (at 136.525 168.325 -90)
    (descr "Capacitor SMD 0402")
    (tags "capacitor SMD 0402")
    (property "Author" "Antmicro")
    (property "Dielectric" "X5R")
    (property "License" "Apache-2.0")
    (property "MPN" "GRM155R61H104KE14D")
    (property "Manufacturer" "Murata")
    (property "Public" "False")
    (property "Sheetfile" "pcie-conn.kicad_sch")
    (property "Sheetname" "PCIe-connector")
    (property "Val" "100n")
    (property "Voltage" "50V")
    (property "ki_description" "SMD Multilayer Ceramic Capacitor, 0.1 µF, 50 V, 0402 [1005 Metric], ± 10%, X5R, GRM Series")
    (property "ki_keywords" "0402, SMT, CAPACITOR, PASSIVE, CERAMIC, MLCC")
    (attr smd)
    (fp_text reference "C38" (at 2.13 -0.05 90) (layer "F.SilkS")
        (effects (font (size 0.7 0.7) (thickness 0.127)))
    )
    (fp_text value "C_100n_0402" (at 0 1.17 90) (layer "F.Fab")
        (effects (font (size 1 1) (thickness 0.15)))
    )
    (fp_text user "Author: Antmicro" (at -0.939 3.399 -90) (layer "F.Fab") hide
        (effects (font (size 0.7 0.7) (thickness 0.15)) (justify left bottom))
    )
    (fp_text user "${REFERENCE}" (at 0 0 90) (layer "F.Fab")
        (effects (font (size 0.25 0.25) (thickness 0.04)))
    )
    (fp_text user "License: Apache-2.0" (at -0.939 5.799 -90) (layer "F.Fab") hide
        (effects (font (size 0.7 0.7) (thickness 0.15)) (justify left bottom))
    )
    (fp_rect (start -0.925 -0.47) (end 0.925 0.47)
      (stroke (width 0.05) (type default)) (fill none) (layer "F.CrtYd"))
    (fp_line (start -0.494 -0.25) (end 0.504 -0.25)
      (stroke (width 0.15) (type solid)) (layer "F.Fab"))
    (fp_line (start -0.494 0.248) (end -0.494 -0.25)
      (stroke (width 0.15) (type solid)) (layer "F.Fab"))
    (fp_line (start 0.504 -0.25) (end 0.504 0.248)
      (stroke (width 0.15) (type solid)) (layer "F.Fab"))
    (fp_line (start 0.504 0.248) (end -0.494 0.248)
      (stroke (width 0.15) (type solid)) (layer "F.Fab"))
    (pad "1" smd roundrect (at -0.48 0 270) (size 0.59 0.64) (layers "F.Cu" "F.Paste" "F.Mask") (roundrect_rratio 0.25)
      (net 216 "Net-(J2-PET3_N)") (pintype "passive"))
    (pad "2" smd roundrect (at 0.48 0 270) (size 0.59 0.64) (layers "F.Cu" "F.Paste" "F.Mask") (roundrect_rratio 0.25)
      (net 695 "PCIE_HPM_TX3_N") (pintype "passive"))
  )

  (footprint "antmicro-footprints:R_0402_1005Metric" (layer "F.Cu")
    (at 126.1 154.3 -90)
    (descr "Resistor SMD 0402")
    (tags "resistor SMD 0402")
    (property "Author" "Antmicro")
    (property "License" "Apache-2.0")
    (property "MPN" "CR0402-FX-1002GLF")
    (property "Manufacturer" "Bourns")
    (property "Public" "False")
    (property "Sheetfile" "pcie-conn.kicad_sch")
    (property "Sheetname" "PCIe-connector")
    (property "Tolerance" "1%")
    (property "Val" "10k")
    (property "ki_description" "SMD Chip Resistor, 10 kohm, ± 1%, 62.5 mW, 0402 [1005 Metric], Thick Film, General Purpose")
    (property "ki_keywords" "0402, SMT, RESISTOR, PASSIVE")
    (attr smd)
    (fp_text reference "R17" (at -2.75 0.08 90) (layer "F.SilkS")
        (effects (font (size 0.7 0.7) (thickness 0.127)))
    )
    (fp_text value "R_10k_0402" (at 0 1.17 90) (layer "F.Fab")
        (effects (font (size 1 1) (thickness 0.15)))
    )
    (fp_text user "${REFERENCE}" (at 0 0 90) (layer "F.Fab")
        (effects (font (size 0.25 0.25) (thickness 0.04)))
    )
    (fp_text user "License: Apache-2.0" (at -0.95 5.169 -90) (layer "F.Fab") hide
        (effects (font (size 0.7 0.7) (thickness 0.15)) (justify left bottom))
    )
    (fp_text user "Author: Antmicro" (at -0.95 4.169 -90) (layer "F.Fab") hide
        (effects (font (size 0.7 0.7) (thickness 0.15)) (justify left bottom))
    )
    (fp_rect (start -0.925 -0.47) (end 0.925 0.47)
      (stroke (width 0.05) (type default)) (fill none) (layer "F.CrtYd"))
    (fp_rect (start -0.5 -0.25) (end 0.5 0.25)
      (stroke (width 0.15) (type solid)) (fill none) (layer "F.Fab"))
    (pad "1" smd roundrect (at -0.48 0 270) (size 0.59 0.64) (layers "F.Cu" "F.Paste" "F.Mask") (roundrect_rratio 0.25)
      (net 2 "VCC3V3") (pintype "passive"))
    (pad "2" smd roundrect (at 0.48 0 270) (size 0.59 0.64) (layers "F.Cu" "F.Paste" "F.Mask") (roundrect_rratio 0.25)
      (net 380 "Net-(J2-~{CLKREQ})") (pintype "passive"))
  )

  (footprint "antmicro-footprints:R_0402_1005Metric" (layer "F.Cu")
    (at 143.2 167.75 90)
    (descr "Resistor SMD 0402")
    (tags "resistor SMD 0402")
    (property "Author" "Antmicro")
    (property "License" "Apache-2.0")
    (property "MPN" "CR0402-FX-3300GLF")
    (property "Manufacturer" "Bourns")
    (property "Public" "False")
    (property "Sheetfile" "pcie-conn.kicad_sch")
    (property "Sheetname" "PCIe-connector")
    (property "Tolerance" "1%")
    (property "Val" "330R")
    (property "ki_description" "SMD Chip Resistor, 330 ohm, ± 1%, 62.5 mW, 0402 [1005 Metric], Thick Film, General Purpose")
    (property "ki_keywords" "0402, SMT, RESISTOR, PASSIVE")
    (attr smd)
    (fp_text reference "R18" (at 0.005 1.05 90) (layer "F.SilkS")
        (effects (font (size 0.7 0.7) (thickness 0.127)))
    )
    (fp_text value "R_330R_0402" (at 0 1.17 90) (layer "F.Fab")
        (effects (font (size 1 1) (thickness 0.15)))
    )
    (fp_text user "License: Apache-2.0" (at -0.95 5.169 90) (layer "F.Fab") hide
        (effects (font (size 0.7 0.7) (thickness 0.15)) (justify left bottom))
    )
    (fp_text user "Author: Antmicro" (at -0.95 4.169 90) (layer "F.Fab") hide
        (effects (font (size 0.7 0.7) (thickness 0.15)) (justify left bottom))
    )
    (fp_text user "${REFERENCE}" (at 0 0 90) (layer "F.Fab")
        (effects (font (size 0.25 0.25) (thickness 0.04)))
    )
    (fp_rect (start -0.925 -0.47) (end 0.925 0.47)
      (stroke (width 0.05) (type default)) (fill none) (layer "F.CrtYd"))
    (fp_rect (start -0.5 -0.25) (end 0.5 0.25)
      (stroke (width 0.15) (type solid)) (fill none) (layer "F.Fab"))
    (pad "1" smd roundrect (at -0.48 0 90) (size 0.59 0.64) (layers "F.Cu" "F.Paste" "F.Mask") (roundrect_rratio 0.25)
      (net 777 "Net-(D1-A)") (pintype "passive"))
    (pad "2" smd roundrect (at 0.48 0 90) (size 0.59 0.64) (layers "F.Cu" "F.Paste" "F.Mask") (roundrect_rratio 0.25)
      (net 2 "VCC3V3") (pintype "passive"))
  )

  (footprint "antmicro-footprints:C_0402_1005Metric" (layer "F.Cu")
    (at 130.565 168.325 -90)
    (descr "Capacitor SMD 0402")
    (tags "capacitor SMD 0402")
    (property "Author" "Antmicro")
    (property "Dielectric" "X5R")
    (property "License" "Apache-2.0")
    (property "MPN" "GRM155R61H104KE14D")
    (property "Manufacturer" "Murata")
    (property "Public" "False")
    (property "Sheetfile" "pcie-conn.kicad_sch")
    (property "Sheetname" "PCIe-connector")
    (property "Val" "100n")
    (property "Voltage" "50V")
    (property "ki_description" "SMD Multilayer Ceramic Capacitor, 0.1 µF, 50 V, 0402 [1005 Metric], ± 10%, X5R, GRM Series")
    (property "ki_keywords" "0402, SMT, CAPACITOR, PASSIVE, CERAMIC, MLCC")
    (attr smd)
    (fp_text reference "C36" (at 2.11 -0.08 90) (layer "F.SilkS")
        (effects (font (size 0.7 0.7) (thickness 0.127)))
    )
    (fp_text value "C_100n_0402" (at 0 1.17 90) (layer "F.Fab")
        (effects (font (size 1 1) (thickness 0.15)))
    )
    (fp_text user "License: Apache-2.0" (at -0.939 5.799 -90) (layer "F.Fab") hide
        (effects (font (size 0.7 0.7) (thickness 0.15)) (justify left bottom))
    )
    (fp_text user "${REFERENCE}" (at 0 0 90) (layer "F.Fab")
        (effects (font (size 0.25 0.25) (thickness 0.04)))
    )
    (fp_text user "Author: Antmicro" (at -0.939 3.399 -90) (layer "F.Fab") hide
        (effects (font (size 0.7 0.7) (thickness 0.15)) (justify left bottom))
    )
    (fp_rect (start -0.925 -0.47) (end 0.925 0.47)
      (stroke (width 0.05) (type default)) (fill none) (layer "F.CrtYd"))
    (fp_line (start -0.494 -0.25) (end 0.504 -0.25)
      (stroke (width 0.15) (type solid)) (layer "F.Fab"))
    (fp_line (start -0.494 0.248) (end -0.494 -0.25)
      (stroke (width 0.15) (type solid)) (layer "F.Fab"))
    (fp_line (start 0.504 -0.25) (end 0.504 0.248)
      (stroke (width 0.15) (type solid)) (layer "F.Fab"))
    (fp_line (start 0.504 0.248) (end -0.494 0.248)
      (stroke (width 0.15) (type solid)) (layer "F.Fab"))
    (pad "1" smd roundrect (at -0.48 0 270) (size 0.59 0.64) (layers "F.Cu" "F.Paste" "F.Mask") (roundrect_rratio 0.25)
      (net 214 "Net-(J2-PET1_N)") (pintype "passive"))
    (pad "2" smd roundrect (at 0.48 0 270) (size 0.59 0.64) (layers "F.Cu" "F.Paste" "F.Mask") (roundrect_rratio 0.25)
      (net 693 "PCIE_HPM_TX1_N") (pintype "passive"))
  )

  (footprint "antmicro-footprints:C_0402_1005Metric" (layer "F.Cu")
    (at 129.565 168.325 -90)
    (descr "Capacitor SMD 0402")
    (tags "capacitor SMD 0402")
    (property "Author" "Antmicro")
    (property "Dielectric" "X5R")
    (property "License" "Apache-2.0")
    (property "MPN" "GRM155R61H104KE14D")
    (property "Manufacturer" "Murata")
    (property "Public" "False")
    (property "Sheetfile" "pcie-conn.kicad_sch")
    (property "Sheetname" "PCIe-connector")
    (property "Val" "100n")
    (property "Voltage" "50V")
    (property "ki_description" "SMD Multilayer Ceramic Capacitor, 0.1 µF, 50 V, 0402 [1005 Metric], ± 10%, X5R, GRM Series")
    (property "ki_keywords" "0402, SMT, CAPACITOR, PASSIVE, CERAMIC, MLCC")
    (attr smd)
    (fp_text reference "C32" (at 2.14 0.01 90) (layer "F.SilkS")
        (effects (font (size 0.7 0.7) (thickness 0.127)))
    )
    (fp_text value "C_100n_0402" (at 0 1.17 90) (layer "F.Fab")
        (effects (font (size 1 1) (thickness 0.15)))
    )
    (fp_text user "Author: Antmicro" (at -0.939 3.399 -90) (layer "F.Fab") hide
        (effects (font (size 0.7 0.7) (thickness 0.15)) (justify left bottom))
    )
    (fp_text user "License: Apache-2.0" (at -0.939 5.799 -90) (layer "F.Fab") hide
        (effects (font (size 0.7 0.7) (thickness 0.15)) (justify left bottom))
    )
    (fp_text user "${REFERENCE}" (at 0 0 90) (layer "F.Fab")
        (effects (font (size 0.25 0.25) (thickness 0.04)))
    )
    (fp_rect (start -0.925 -0.47) (end 0.925 0.47)
      (stroke (width 0.05) (type default)) (fill none) (layer "F.CrtYd"))
    (fp_line (start -0.494 -0.25) (end 0.504 -0.25)
      (stroke (width 0.15) (type solid)) (layer "F.Fab"))
    (fp_line (start -0.494 0.248) (end -0.494 -0.25)
      (stroke (width 0.15) (type solid)) (layer "F.Fab"))
    (fp_line (start 0.504 -0.25) (end 0.504 0.248)
      (stroke (width 0.15) (type solid)) (layer "F.Fab"))
    (fp_line (start 0.504 0.248) (end -0.494 0.248)
      (stroke (width 0.15) (type solid)) (layer "F.Fab"))
    (pad "1" smd roundrect (at -0.48 0 270) (size 0.59 0.64) (layers "F.Cu" "F.Paste" "F.Mask") (roundrect_rratio 0.25)
      (net 17 "Net-(J2-PET1_P)") (pintype "passive"))
    (pad "2" smd roundrect (at 0.48 0 270) (size 0.59 0.64) (layers "F.Cu" "F.Paste" "F.Mask") (roundrect_rratio 0.25)
      (net 689 "PCIE_HPM_TX1_P") (pintype "passive"))
  )

  (footprint "antmicro-footprints:R_0402_1005Metric" (layer "F.Cu")
    (at 127.1 154.3 -90)
    (descr "Resistor SMD 0402")
    (tags "resistor SMD 0402")
    (property "Author" "Antmicro")
    (property "License" "Apache-2.0")
    (property "MPN" "CR0402-FX-1002GLF")
    (property "Manufacturer" "Bourns")
    (property "Public" "False")
    (property "Sheetfile" "pcie-conn.kicad_sch")
    (property "Sheetname" "PCIe-connector")
    (property "Tolerance" "1%")
    (property "Val" "10k")
    (property "ki_description" "SMD Chip Resistor, 10 kohm, ± 1%, 62.5 mW, 0402 [1005 Metric], Thick Film, General Purpose")
    (property "ki_keywords" "0402, SMT, RESISTOR, PASSIVE")
    (attr smd)
    (fp_text reference "R19" (at -2.75 0.08 90) (layer "F.SilkS")
        (effects (font (size 0.7 0.7) (thickness 0.127)))
    )
    (fp_text value "R_10k_0402" (at 0 1.17 90) (layer "F.Fab")
        (effects (font (size 1 1) (thickness 0.15)))
    )
    (fp_text user "${REFERENCE}" (at 0 0 90) (layer "F.Fab")
        (effects (font (size 0.25 0.25) (thickness 0.04)))
    )
    (fp_text user "License: Apache-2.0" (at -0.95 5.169 -90) (layer "F.Fab") hide
        (effects (font (size 0.7 0.7) (thickness 0.15)) (justify left bottom))
    )
    (fp_text user "Author: Antmicro" (at -0.95 4.169 -90) (layer "F.Fab") hide
        (effects (font (size 0.7 0.7) (thickness 0.15)) (justify left bottom))
    )
    (fp_rect (start -0.925 -0.47) (end 0.925 0.47)
      (stroke (width 0.05) (type default)) (fill none) (layer "F.CrtYd"))
    (fp_rect (start -0.5 -0.25) (end 0.5 0.25)
      (stroke (width 0.15) (type solid)) (fill none) (layer "F.Fab"))
    (pad "1" smd roundrect (at -0.48 0 270) (size 0.59 0.64) (layers "F.Cu" "F.Paste" "F.Mask") (roundrect_rratio 0.25)
      (net 2 "VCC3V3") (pintype "passive"))
    (pad "2" smd roundrect (at 0.48 0 270) (size 0.59 0.64) (layers "F.Cu" "F.Paste" "F.Mask") (roundrect_rratio 0.25)
      (net 58 "PRSNT0_N") (pintype "passive"))
  )

  (footprint "antmicro-footprints:C_0402_1005Metric" (layer "F.Cu")
    (at 121.05 154.8 -90)
    (descr "Capacitor SMD 0402")
    (tags "capacitor SMD 0402")
    (property "Author" "Antmicro")
    (property "Dielectric" "")
    (property "License" "Apache-2.0")
    (property "MPN" "CC0402MRX5R5BB106")
    (property "Manufacturer" "YAGEO")
    (property "Public" "False")
    (property "Sheetfile" "pcie-conn.kicad_sch")
    (property "Sheetname" "PCIe-connector")
    (property "Val" "10u")
    (property "Voltage" "")
    (property "ki_description" "SMD Multilayer Ceramic Capacitor, 10 µF, 6.3 V, 0402 [1005 Metric], ± 20%, X5R, CC Series")
    (property "ki_keywords" "0402, SMT, CAPACITOR, PASSIVE, MLCC, CERAMIC")
    (attr smd)
    (fp_text reference "C40" (at 0.04 1.22 90) (layer "F.SilkS")
        (effects (font (size 0.7 0.7) (thickness 0.127)))
    )
    (fp_text value "C_10u_0402" (at 0 1.17 90) (layer "F.Fab")
        (effects (font (size 1 1) (thickness 0.15)))
    )
    (fp_text user "${REFERENCE}" (at 0 0 90) (layer "F.Fab")
        (effects (font (size 0.25 0.25) (thickness 0.04)))
    )
    (fp_text user "Author: Antmicro" (at -0.939 3.399 -90) (layer "F.Fab") hide
        (effects (font (size 0.7 0.7) (thickness 0.15)) (justify left bottom))
    )
    (fp_text user "License: Apache-2.0" (at -0.939 5.799 -90) (layer "F.Fab") hide
        (effects (font (size 0.7 0.7) (thickness 0.15)) (justify left bottom))
    )
    (fp_rect (start -0.925 -0.47) (end 0.925 0.47)
      (stroke (width 0.05) (type default)) (fill none) (layer "F.CrtYd"))
    (fp_line (start -0.494 -0.25) (end 0.504 -0.25)
      (stroke (width 0.15) (type solid)) (layer "F.Fab"))
    (fp_line (start -0.494 0.248) (end -0.494 -0.25)
      (stroke (width 0.15) (type solid)) (layer "F.Fab"))
    (fp_line (start 0.504 -0.25) (end 0.504 0.248)
      (stroke (width 0.15) (type solid)) (layer "F.Fab"))
    (fp_line (start 0.504 0.248) (end -0.494 0.248)
      (stroke (width 0.15) (type solid)) (layer "F.Fab"))
    (pad "1" smd roundrect (at -0.48 0 270) (size 0.59 0.64) (layers "F.Cu" "F.Paste" "F.Mask") (roundrect_rratio 0.25)
      (net 1 "GND") (pintype "passive"))
    (pad "2" smd roundrect (at 0.48 0 270) (size 0.59 0.64) (layers "F.Cu" "F.Paste" "F.Mask") (roundrect_rratio 0.25)
      (net 2 "VCC3V3") (pintype "passive"))
  )

  (footprint "antmicro-footprints:C_0402_1005Metric" (layer "F.Cu")
    (at 126.575 168.325 -90)
    (descr "Capacitor SMD 0402")
    (tags "capacitor SMD 0402")
    (property "Author" "Antmicro")
    (property "Dielectric" "X5R")
    (property "License" "Apache-2.0")
    (property "MPN" "GRM155R61H104KE14D")
    (property "Manufacturer" "Murata")
    (property "Public" "False")
    (property "Sheetfile" "pcie-conn.kicad_sch")
    (property "Sheetname" "PCIe-connector")
    (property "Val" "100n")
    (property "Voltage" "50V")
    (property "ki_description" "SMD Multilayer Ceramic Capacitor, 0.1 µF, 50 V, 0402 [1005 Metric], ± 10%, X5R, GRM Series")
    (property "ki_keywords" "0402, SMT, CAPACITOR, PASSIVE, CERAMIC, MLCC")
    (attr smd)
    (fp_text reference "C31" (at 2.11 0.01 90) (layer "F.SilkS")
        (effects (font (size 0.7 0.7) (thickness 0.127)))
    )
    (fp_text value "C_100n_0402" (at 0 1.17 90) (layer "F.Fab")
        (effects (font (size 1 1) (thickness 0.15)))
    )
    (fp_text user "Author: Antmicro" (at -0.939 3.399 -90) (layer "F.Fab") hide
        (effects (font (size 0.7 0.7) (thickness 0.15)) (justify left bottom))
    )
    (fp_text user "${REFERENCE}" (at 0 0 90) (layer "F.Fab")
        (effects (font (size 0.25 0.25) (thickness 0.04)))
    )
    (fp_text user "License: Apache-2.0" (at -0.939 5.799 -90) (layer "F.Fab") hide
        (effects (font (size 0.7 0.7) (thickness 0.15)) (justify left bottom))
    )
    (fp_rect (start -0.925 -0.47) (end 0.925 0.47)
      (stroke (width 0.05) (type default)) (fill none) (layer "F.CrtYd"))
    (fp_line (start -0.494 -0.25) (end 0.504 -0.25)
      (stroke (width 0.15) (type solid)) (layer "F.Fab"))
    (fp_line (start -0.494 0.248) (end -0.494 -0.25)
      (stroke (width 0.15) (type solid)) (layer "F.Fab"))
    (fp_line (start 0.504 -0.25) (end 0.504 0.248)
      (stroke (width 0.15) (type solid)) (layer "F.Fab"))
    (fp_line (start 0.504 0.248) (end -0.494 0.248)
      (stroke (width 0.15) (type solid)) (layer "F.Fab"))
    (pad "1" smd roundrect (at -0.48 0 270) (size 0.59 0.64) (layers "F.Cu" "F.Paste" "F.Mask") (roundrect_rratio 0.25)
      (net 16 "Net-(J2-PET0_P)") (pintype "passive"))
    (pad "2" smd roundrect (at 0.48 0 270) (size 0.59 0.64) (layers "F.Cu" "F.Paste" "F.Mask") (roundrect_rratio 0.25)
      (net 688 "PCIE_HPM_TX0_P") (pintype "passive"))
  )

  (footprint "antmicro-footprints:C_0402_1005Metric" (layer "F.Cu")
    (at 134.7 154.9 -90)
    (descr "Capacitor SMD 0402")
    (tags "capacitor SMD 0402")
    (property "Author" "Antmicro")
    (property "Dielectric" "")
    (property "License" "Apache-2.0")
    (property "MPN" "CC0402MRX5R5BB106")
    (property "Manufacturer" "YAGEO")
    (property "Public" "False")
    (property "Sheetfile" "pcie-conn.kicad_sch")
    (property "Sheetname" "PCIe-connector")
    (property "Val" "10u")
    (property "Voltage" "")
    (property "ki_description" "SMD Multilayer Ceramic Capacitor, 10 µF, 6.3 V, 0402 [1005 Metric], ± 20%, X5R, CC Series")
    (property "ki_keywords" "0402, SMT, CAPACITOR, PASSIVE, MLCC, CERAMIC")
    (attr smd)
    (fp_text reference "C42" (at -2.495 -0.01 90) (layer "F.SilkS")
        (effects (font (size 0.7 0.7) (thickness 0.127)))
    )
    (fp_text value "C_10u_0402" (at 0 1.17 90) (layer "F.Fab")
        (effects (font (size 1 1) (thickness 0.15)))
    )
    (fp_text user "Author: Antmicro" (at -0.939 3.399 -90) (layer "F.Fab") hide
        (effects (font (size 0.7 0.7) (thickness 0.15)) (justify left bottom))
    )
    (fp_text user "License: Apache-2.0" (at -0.939 5.799 -90) (layer "F.Fab") hide
        (effects (font (size 0.7 0.7) (thickness 0.15)) (justify left bottom))
    )
    (fp_text user "${REFERENCE}" (at 0 0 90) (layer "F.Fab")
        (effects (font (size 0.25 0.25) (thickness 0.04)))
    )
    (fp_rect (start -0.925 -0.47) (end 0.925 0.47)
      (stroke (width 0.05) (type default)) (fill none) (layer "F.CrtYd"))
    (fp_line (start -0.494 -0.25) (end 0.504 -0.25)
      (stroke (width 0.15) (type solid)) (layer "F.Fab"))
    (fp_line (start -0.494 0.248) (end -0.494 -0.25)
      (stroke (width 0.15) (type solid)) (layer "F.Fab"))
    (fp_line (start 0.504 -0.25) (end 0.504 0.248)
      (stroke (width 0.15) (type solid)) (layer "F.Fab"))
    (fp_line (start 0.504 0.248) (end -0.494 0.248)
      (stroke (width 0.15) (type solid)) (layer "F.Fab"))
    (pad "1" smd roundrect (at -0.48 0 270) (size 0.59 0.64) (layers "F.Cu" "F.Paste" "F.Mask") (roundrect_rratio 0.25)
      (net 1 "GND") (pintype "passive"))
    (pad "2" smd roundrect (at 0.48 0 270) (size 0.59 0.64) (layers "F.Cu" "F.Paste" "F.Mask") (roundrect_rratio 0.25)
      (net 2 "VCC3V3") (pintype "passive"))
  )

  (footprint "antmicro-footprints:R_0402_1005Metric" (layer "F.Cu")
    (at 128.1 154.3 90)
    (descr "Resistor SMD 0402")
    (tags "resistor SMD 0402")
    (property "Author" "Antmicro")
    (property "License" "Apache-2.0")
    (property "MPN" "CR0402-FX-1002GLF")
    (property "Manufacturer" "Bourns")
    (property "Public" "False")
    (property "Sheetfile" "pcie-conn.kicad_sch")
    (property "Sheetname" "PCIe-connector")
    (property "Tolerance" "1%")
    (property "Val" "10k")
    (property "ki_description" "SMD Chip Resistor, 10 kohm, ± 1%, 62.5 mW, 0402 [1005 Metric], Thick Film, General Purpose")
    (property "ki_keywords" "0402, SMT, RESISTOR, PASSIVE")
    (attr smd)
    (fp_text reference "R20" (at 2.735 0.05 90) (layer "F.SilkS")
        (effects (font (size 0.7 0.7) (thickness 0.127)))
    )
    (fp_text value "R_10k_0402" (at -0.2 1.1 90) (layer "F.Fab")
        (effects (font (size 1 1) (thickness 0.15)))
    )
    (fp_text user "Author: Antmicro" (at -0.95 4.169 90) (layer "F.Fab") hide
        (effects (font (size 0.7 0.7) (thickness 0.15)) (justify left bottom))
    )
    (fp_text user "License: Apache-2.0" (at -0.95 5.169 90) (layer "F.Fab") hide
        (effects (font (size 0.7 0.7) (thickness 0.15)) (justify left bottom))
    )
    (fp_text user "${REFERENCE}" (at 0 0 90) (layer "F.Fab")
        (effects (font (size 0.25 0.25) (thickness 0.04)))
    )
    (fp_rect (start -0.925 -0.47) (end 0.925 0.47)
      (stroke (width 0.05) (type default)) (fill none) (layer "F.CrtYd"))
    (fp_rect (start -0.5 -0.25) (end 0.5 0.25)
      (stroke (width 0.15) (type solid)) (fill none) (layer "F.Fab"))
    (pad "1" smd roundrect (at -0.48 0 90) (size 0.59 0.64) (layers "F.Cu" "F.Paste" "F.Mask") (roundrect_rratio 0.25)
      (net 376 "Net-(J2-ALERT)") (pintype "passive"))
    (pad "2" smd roundrect (at 0.48 0 90) (size 0.59 0.64) (layers "F.Cu" "F.Paste" "F.Mask") (roundrect_rratio 0.25)
      (net 218 "VCC1V8") (pintype "passive"))
  )

  (footprint "antmicro-footprints:C_0402_1005Metric" (layer "F.Cu")
    (at 133.535 168.325 -90)
    (descr "Capacitor SMD 0402")
    (tags "capacitor SMD 0402")
    (property "Author" "Antmicro")
    (property "Dielectric" "X5R")
    (property "License" "Apache-2.0")
    (property "MPN" "GRM155R61H104KE14D")
    (property "Manufacturer" "Murata")
    (property "Public" "False")
    (property "Sheetfile" "pcie-conn.kicad_sch")
    (property "Sheetname" "PCIe-connector")
    (property "Val" "100n")
    (property "Voltage" "50V")
    (property "ki_description" "SMD Multilayer Ceramic Capacitor, 0.1 µF, 50 V, 0402 [1005 Metric], ± 10%, X5R, GRM Series")
    (property "ki_keywords" "0402, SMT, CAPACITOR, PASSIVE, CERAMIC, MLCC")
    (attr smd)
    (fp_text reference "C37" (at 2.14 -0.13 90) (layer "F.SilkS")
        (effects (font (size 0.7 0.7) (thickness 0.127)))
    )
    (fp_text value "C_100n_0402" (at 0 1.17 90) (layer "F.Fab")
        (effects (font (size 1 1) (thickness 0.15)))
    )
    (fp_text user "Author: Antmicro" (at -0.939 3.399 -90) (layer "F.Fab") hide
        (effects (font (size 0.7 0.7) (thickness 0.15)) (justify left bottom))
    )
    (fp_text user "License: Apache-2.0" (at -0.939 5.799 -90) (layer "F.Fab") hide
        (effects (font (size 0.7 0.7) (thickness 0.15)) (justify left bottom))
    )
    (fp_text user "${REFERENCE}" (at 0 0 90) (layer "F.Fab")
        (effects (font (size 0.25 0.25) (thickness 0.04)))
    )
    (fp_rect (start -0.925 -0.47) (end 0.925 0.47)
      (stroke (width 0.05) (type default)) (fill none) (layer "F.CrtYd"))
    (fp_line (start -0.494 -0.25) (end 0.504 -0.25)
      (stroke (width 0.15) (type solid)) (layer "F.Fab"))
    (fp_line (start -0.494 0.248) (end -0.494 -0.25)
      (stroke (width 0.15) (type solid)) (layer "F.Fab"))
    (fp_line (start 0.504 -0.25) (end 0.504 0.248)
      (stroke (width 0.15) (type solid)) (layer "F.Fab"))
    (fp_line (start 0.504 0.248) (end -0.494 0.248)
      (stroke (width 0.15) (type solid)) (layer "F.Fab"))
    (pad "1" smd roundrect (at -0.48 0 270) (size 0.59 0.64) (layers "F.Cu" "F.Paste" "F.Mask") (roundrect_rratio 0.25)
      (net 215 "Net-(J2-PET2_N)") (pintype "passive"))
    (pad "2" smd roundrect (at 0.48 0 270) (size 0.59 0.64) (layers "F.Cu" "F.Paste" "F.Mask") (roundrect_rratio 0.25)
      (net 694 "PCIE_HPM_TX2_N") (pintype "passive"))
  )

  (footprint "antmicro-footprints:C_0402_1005Metric" (layer "F.Cu")
    (at 127.575 168.325 -90)
    (descr "Capacitor SMD 0402")
    (tags "capacitor SMD 0402")
    (property "Author" "Antmicro")
    (property "Dielectric" "X5R")
    (property "License" "Apache-2.0")
    (property "MPN" "GRM155R61H104KE14D")
    (property "Manufacturer" "Murata")
    (property "Public" "False")
    (property "Sheetfile" "pcie-conn.kicad_sch")
    (property "Sheetname" "PCIe-connector")
    (property "Val" "100n")
    (property "Voltage" "50V")
    (property "ki_description" "SMD Multilayer Ceramic Capacitor, 0.1 µF, 50 V, 0402 [1005 Metric], ± 10%, X5R, GRM Series")
    (property "ki_keywords" "0402, SMT, CAPACITOR, PASSIVE, CERAMIC, MLCC")
    (attr smd)
    (fp_text reference "C35" (at 2.14 -0.12 90) (layer "F.SilkS")
        (effects (font (size 0.7 0.7) (thickness 0.127)))
    )
    (fp_text value "C_100n_0402" (at 0 1.17 90) (layer "F.Fab")
        (effects (font (size 1 1) (thickness 0.15)))
    )
    (fp_text user "Author: Antmicro" (at -0.939 3.399 -90) (layer "F.Fab") hide
        (effects (font (size 0.7 0.7) (thickness 0.15)) (justify left bottom))
    )
    (fp_text user "${REFERENCE}" (at 0 0 90) (layer "F.Fab")
        (effects (font (size 0.25 0.25) (thickness 0.04)))
    )
    (fp_text user "License: Apache-2.0" (at -0.939 5.799 -90) (layer "F.Fab") hide
        (effects (font (size 0.7 0.7) (thickness 0.15)) (justify left bottom))
    )
    (fp_rect (start -0.925 -0.47) (end 0.925 0.47)
      (stroke (width 0.05) (type default)) (fill none) (layer "F.CrtYd"))
    (fp_line (start -0.494 -0.25) (end 0.504 -0.25)
      (stroke (width 0.15) (type solid)) (layer "F.Fab"))
    (fp_line (start -0.494 0.248) (end -0.494 -0.25)
      (stroke (width 0.15) (type solid)) (layer "F.Fab"))
    (fp_line (start 0.504 -0.25) (end 0.504 0.248)
      (stroke (width 0.15) (type solid)) (layer "F.Fab"))
    (fp_line (start 0.504 0.248) (end -0.494 0.248)
      (stroke (width 0.15) (type solid)) (layer "F.Fab"))
    (pad "1" smd roundrect (at -0.48 0 270) (size 0.59 0.64) (layers "F.Cu" "F.Paste" "F.Mask") (roundrect_rratio 0.25)
      (net 213 "Net-(J2-PET0_N)") (pintype "passive"))
    (pad "2" smd roundrect (at 0.48 0 270) (size 0.59 0.64) (layers "F.Cu" "F.Paste" "F.Mask") (roundrect_rratio 0.25)
      (net 692 "PCIE_HPM_TX0_N") (pintype "passive"))
  )

  (footprint "antmicro-footprints:C_0402_1005Metric" (layer "F.Cu")
    (at 132.535 168.325 -90)
    (descr "Capacitor SMD 0402")
    (tags "capacitor SMD 0402")
    (property "Author" "Antmicro")
    (property "Dielectric" "X5R")
    (property "License" "Apache-2.0")
    (property "MPN" "GRM155R61H104KE14D")
    (property "Manufacturer" "Murata")
    (property "Public" "False")
    (property "Sheetfile" "pcie-conn.kicad_sch")
    (property "Sheetname" "PCIe-connector")
    (property "Val" "100n")
    (property "Voltage" "50V")
    (property "ki_description" "SMD Multilayer Ceramic Capacitor, 0.1 µF, 50 V, 0402 [1005 Metric], ± 10%, X5R, GRM Series")
    (property "ki_keywords" "0402, SMT, CAPACITOR, PASSIVE, CERAMIC, MLCC")
    (attr smd)
    (fp_text reference "C33" (at 2.14 -0.04 90) (layer "F.SilkS")
        (effects (font (size 0.7 0.7) (thickness 0.127)))
    )
    (fp_text value "C_100n_0402" (at 0 1.17 90) (layer "F.Fab")
        (effects (font (size 1 1) (thickness 0.15)))
    )
    (fp_text user "License: Apache-2.0" (at -0.939 5.799 -90) (layer "F.Fab") hide
        (effects (font (size 0.7 0.7) (thickness 0.15)) (justify left bottom))
    )
    (fp_text user "Author: Antmicro" (at -0.939 3.399 -90) (layer "F.Fab") hide
        (effects (font (size 0.7 0.7) (thickness 0.15)) (justify left bottom))
    )
    (fp_text user "${REFERENCE}" (at 0 0 90) (layer "F.Fab")
        (effects (font (size 0.25 0.25) (thickness 0.04)))
    )
    (fp_rect (start -0.925 -0.47) (end 0.925 0.47)
      (stroke (width 0.05) (type default)) (fill none) (layer "F.CrtYd"))
    (fp_line (start -0.494 -0.25) (end 0.504 -0.25)
      (stroke (width 0.15) (type solid)) (layer "F.Fab"))
    (fp_line (start -0.494 0.248) (end -0.494 -0.25)
      (stroke (width 0.15) (type solid)) (layer "F.Fab"))
    (fp_line (start 0.504 -0.25) (end 0.504 0.248)
      (stroke (width 0.15) (type solid)) (layer "F.Fab"))
    (fp_line (start 0.504 0.248) (end -0.494 0.248)
      (stroke (width 0.15) (type solid)) (layer "F.Fab"))
    (pad "1" smd roundrect (at -0.48 0 270) (size 0.59 0.64) (layers "F.Cu" "F.Paste" "F.Mask") (roundrect_rratio 0.25)
      (net 18 "Net-(J2-PET2_P)") (pintype "passive"))
    (pad "2" smd roundrect (at 0.48 0 270) (size 0.59 0.64) (layers "F.Cu" "F.Paste" "F.Mask") (roundrect_rratio 0.25)
      (net 690 "PCIE_HPM_TX2_P") (pintype "passive"))
  )

  (footprint "antmicro-footprints:Bus_M.2_Socket_Key_M_TE_1-2199230-6" locked (layer "F.Cu")
    (at 129.545 161.1145 180)
    (property "Author" "Antmicro")
    (property "License" "Apache-2.0")
    (property "MPN" "1-2199230-6")
    (property "Manufacturer" "TE Connectivity")
    (property "Sheetfile" "pcie-conn.kicad_sch")
    (property "Sheetname" "PCIe-connector")
    (property "ki_description" "Key M Card Edge Connector, 0, Dual Side, 67 Contacts, Surface Mount, Right Angle, Solder")
    (property "ki_keywords" "HORIZONTAL, SMT, PCIE, CONNECTOR")
    (attr smd)
    (fp_text reference "J2" (at 12.06 3.2) (layer "F.SilkS")
        (effects (font (size 0.7 0.7) (thickness 0.127)))
    )
    (fp_text value "Bus_M.2_1-2199230-6" (at 2.99206 4.516565) (layer "F.Fab")
        (effects (font (size 1.40848 1.40848) (thickness 0.015)))
    )
    (fp_text user "Author: Antmicro" (at -11.35 9.325 180) (layer "F.Fab") hide
        (effects (font (size 0.7 0.7) (thickness 0.15)) (justify left bottom))
    )
    (fp_text user "${REFERENCE}" (at -11.35 8.124 180) (layer "F.Fab") hide
        (effects (font (size 0.7 0.7) (thickness 0.15)) (justify left bottom))
    )
    (fp_text user "License: Apache-2.0" (at -11.35 10.525 180) (layer "F.Fab") hide
        (effects (font (size 0.7 0.7) (thickness 0.15)) (justify left bottom))
    )
    (fp_line (start -10.951 -1.401) (end -10.951 0.55)
      (stroke (width 0.15) (type solid)) (layer "F.SilkS"))
    (fp_line (start -10.951 2.7) (end -10.951 3.999)
      (stroke (width 0.15) (type solid)) (layer "F.SilkS"))
    (fp_line (start -10.951 3.999) (end -9.352 3.999)
      (stroke (width 0.15) (type solid)) (layer "F.SilkS"))
    (fp_line (start 5.097 -3.75) (end 6.898 -3.75)
      (stroke (width 0.15) (type solid)) (layer "F.SilkS"))
    (fp_line (start 5.347 3.999) (end 7.148 3.999)
      (stroke (width 0.15) (type solid)) (layer "F.SilkS"))
    (fp_line (start 9.448 3.999) (end 10.948 3.999)
      (stroke (width 0.15) (type solid)) (layer "F.SilkS"))
    (fp_line (start 10.948 0.449) (end 10.948 -1.301)
      (stroke (width 0.15) (type solid)) (layer "F.SilkS"))
    (fp_line (start 10.948 3.999) (end 10.948 2.3)
      (stroke (width 0.15) (type solid)) (layer "F.SilkS"))
    (fp_circle (center -9.25 -5.651) (end -9.2 -5.651)
      (stroke (width 0.15) (type solid)) (fill solid) (layer "F.SilkS"))
    (fp_circle (center -9.25 -4.875) (end -9.201 -4.826)
      (stroke (width 0.15) (type solid)) (fill solid) (layer "F.SilkS"))
    (fp_line (start -11.16 -4.83) (end -11.16 4.78)
      (stroke (width 0.05) (type solid)) (layer "F.CrtYd"))
    (fp_line (start -11.16 4.78) (end 11.15 4.78)
      (stroke (width 0.05) (type solid)) (layer "F.CrtYd"))
    (fp_line (start 11.15 -4.83) (end -11.16 -4.83)
      (stroke (width 0.05) (type solid)) (layer "F.CrtYd"))
    (fp_line (start 11.15 4.78) (end 11.15 -4.83)
      (stroke (width 0.05) (type solid)) (layer "F.CrtYd"))
    (fp_line (start -10.949 -3.55) (end -10.4 -4.1)
      (stroke (width 0.15) (type solid)) (layer "F.Fab"))
    (fp_line (start -10.949 4.2) (end -10.949 -3.55)
      (stroke (width 0.15) (type solid)) (layer "F.Fab"))
    (fp_line (start -10.4 -4.1) (end 10.95 -4.1)
      (stroke (width 0.15) (type solid)) (layer "F.Fab"))
    (fp_line (start 10.95 -4.1) (end 10.95 4.2)
      (stroke (width 0.15) (type solid)) (layer "F.Fab"))
    (fp_line (start 10.95 4.2) (end -10.949 4.2)
      (stroke (width 0.15) (type solid)) (layer "F.Fab"))
    (pad "" np_thru_hole circle locked (at -10 1.499 180) (size 1.1 1.1) (drill 1.1) (layers "*.Mask"))
    (pad "" np_thru_hole circle locked (at 9.997 1.499 180) (size 1.6 1.6) (drill 1.6) (layers "*.Mask"))
    (pad "1" smd rect locked (at -9.25 -3.775 180) (size 0.3 1.55) (layers "F.Cu" "F.Paste" "F.Mask")
      (net 1 "GND") (pinfunction "GND") (pintype "power_in"))
    (pad "2" smd rect locked (at -9.003 3.773 180) (size 0.3 1.55) (layers "F.Cu" "F.Paste" "F.Mask")
      (net 2 "VCC3V3") (pinfunction "3V3") (pintype "passive"))
    (pad "3" smd rect locked (at -8.753 -3.775 180) (size 0.3 1.55) (layers "F.Cu" "F.Paste" "F.Mask")
      (net 1 "GND") (pinfunction "GND") (pintype "passive"))
    (pad "4" smd rect locked (at -8.503 3.773 180) (size 0.3 1.55) (layers "F.Cu" "F.Paste" "F.Mask")
      (net 2 "VCC3V3") (pinfunction "3V3") (pintype "passive"))
    (pad "5" smd rect locked (at -8.253 -3.775 180) (size 0.3 1.55) (layers "F.Cu" "F.Paste" "F.Mask")
      (net 696 "PCIE_HPM_RX3_N") (pinfunction "PER3_N") (pintype "output"))
    (pad "6" smd rect locked (at -8.001 3.773 180) (size 0.3 1.55) (layers "F.Cu" "F.Paste" "F.Mask")
      (net 351 "unconnected-(J2-NC-Pad6)") (pinfunction "NC") (pintype "no_connect"))
    (pad "7" smd rect locked (at -7.752 -3.775 180) (size 0.3 1.55) (layers "F.Cu" "F.Paste" "F.Mask")
      (net 697 "PCIE_HPM_RX3_P") (pinfunction "PER3_P") (pintype "output"))
    (pad "8" smd rect locked (at -7.502 3.773 180) (size 0.3 1.55) (layers "F.Cu" "F.Paste" "F.Mask")
      (net 353 "unconnected-(J2-NC-Pad8)") (pinfunction "NC") (pintype "no_connect"))
    (pad "9" smd rect locked (at -7.252 -3.775 180) (size 0.3 1.55) (layers "F.Cu" "F.Paste" "F.Mask")
      (net 1 "GND") (pinfunction "GND") (pintype "passive"))
    (pad "10" smd rect locked (at -7.002 3.773 180) (size 0.3 1.55) (layers "F.Cu" "F.Paste" "F.Mask")
      (net 308 "Net-(D1-C)") (pinfunction "LED") (pintype "passive"))
    (pad "11" smd rect locked (at -6.752 -3.775 180) (size 0.3 1.55) (layers "F.Cu" "F.Paste" "F.Mask")
      (net 216 "Net-(J2-PET3_N)") (pinfunction "PET3_N") (pintype "input"))
    (pad "12" smd rect locked (at -6.502 3.773 180) (size 0.3 1.55) (layers "F.Cu" "F.Paste" "F.Mask")
      (net 2 "VCC3V3") (pinfunction "3V3") (pintype "passive"))
    (pad "13" smd rect locked (at -6.252 -3.775 180) (size 0.3 1.55) (layers "F.Cu" "F.Paste" "F.Mask")
      (net 212 "Net-(J2-PET3_P)") (pinfunction "PET3_P") (pintype "input"))
    (pad "14" smd rect locked (at -6.002 3.773 180) (size 0.3 1.55) (layers "F.Cu" "F.Paste" "F.Mask")
      (net 2 "VCC3V3") (pinfunction "3V3") (pintype "passive"))
    (pad "15" smd rect locked (at -5.752 -3.775 180) (size 0.3 1.55) (layers "F.Cu" "F.Paste" "F.Mask")
      (net 1 "GND") (pinfunction "GND") (pintype "passive"))
    (pad "16" smd rect locked (at -5.502 3.773 180) (size 0.3 1.55) (layers "F.Cu" "F.Paste" "F.Mask")
      (net 2 "VCC3V3") (pinfunction "3V3") (pintype "passive"))
    (pad "17" smd rect locked (at -5.252 -3.775 180) (size 0.3 1.55) (layers "F.Cu" "F.Paste" "F.Mask")
      (net 698 "PCIE_HPM_RX2_N") (pinfunction "PER2_N") (pintype "output"))
    (pad "18" smd rect locked (at -5.002 3.773 180) (size 0.3 1.55) (layers "F.Cu" "F.Paste" "F.Mask")
      (net 2 "VCC3V3") (pinfunction "3V3") (pintype "passive"))
    (pad "19" smd rect locked (at -4.752 -3.775 180) (size 0.3 1.55) (layers "F.Cu" "F.Paste" "F.Mask")
      (net 699 "PCIE_HPM_RX2_P") (pinfunction "PER2_P") (pintype "output"))
    (pad "20" smd rect locked (at -4.502 3.773 180) (size 0.3 1.55) (layers "F.Cu" "F.Paste" "F.Mask")
      (net 360 "unconnected-(J2-NC-Pad20)") (pinfunction "NC") (pintype "no_connect"))
    (pad "21" smd rect locked (at -4.252 -3.775 180) (size 0.3 1.55) (layers "F.Cu" "F.Paste" "F.Mask")
      (net 1 "GND") (pinfunction "GND") (pintype "passive"))
    (pad "22" smd rect locked (at -4.002 3.773 180) (size 0.3 1.55) (layers "F.Cu" "F.Paste" "F.Mask")
      (net 361 "unconnected-(J2-NC-Pad22)") (pinfunction "NC") (pintype "no_connect"))
    (pad "23" smd rect locked (at -3.751 -3.775 180) (size 0.3 1.55) (layers "F.Cu" "F.Paste" "F.Mask")
      (net 215 "Net-(J2-PET2_N)") (pinfunction "PET2_N") (pintype "input"))
    (pad "24" smd rect locked (at -3.501 3.773 180) (size 0.3 1.55) (layers "F.Cu" "F.Paste" "F.Mask")
      (net 362 "unconnected-(J2-NC-Pad24)") (pinfunction "NC") (pintype "no_connect"))
    (pad "25" smd rect locked (at -3.251 -3.775 180) (size 0.3 1.55) (layers "F.Cu" "F.Paste" "F.Mask")
      (net 18 "Net-(J2-PET2_P)") (pinfunction "PET2_P") (pintype "input"))
    (pad "26" smd rect locked (at -3.001 3.773 180) (size 0.3 1.55) (layers "F.Cu" "F.Paste" "F.Mask")
      (net 363 "unconnected-(J2-NC-Pad26)") (pinfunction "NC") (pintype "no_connect"))
    (pad "27" smd rect locked (at -2.751 -3.775 180) (size 0.3 1.55) (layers "F.Cu" "F.Paste" "F.Mask")
      (net 1 "GND") (pinfunction "GND") (pintype "passive"))
    (pad "28" smd rect locked (at -2.501 3.773 180) (size 0.3 1.55) (layers "F.Cu" "F.Paste" "F.Mask")
      (net 365 "unconnected-(J2-NC-Pad28)") (pinfunction "NC") (pintype "no_connect"))
    (pad "29" smd rect locked (at -2.251 -3.775 180) (size 0.3 1.55) (layers "F.Cu" "F.Paste" "F.Mask")
      (net 700 "PCIE_HPM_RX1_N") (pinfunction "PER1_N") (pintype "output"))
    (pad "30" smd rect locked (at -2.001 3.773 180) (size 0.3 1.55) (layers "F.Cu" "F.Paste" "F.Mask")
      (net 369 "unconnected-(J2-NC-Pad30)") (pinfunction "NC") (pintype "no_connect"))
    (pad "31" smd rect locked (at -1.752 -3.775 180) (size 0.3 1.55) (layers "F.Cu" "F.Paste" "F.Mask")
      (net 701 "PCIE_HPM_RX1_P") (pinfunction "PER1_P") (pintype "output"))
    (pad "32" smd rect locked (at -1.502 3.773 180) (size 0.3 1.55) (layers "F.Cu" "F.Paste" "F.Mask")
      (net 370 "unconnected-(J2-NC-Pad32)") (pinfunction "NC") (pintype "no_connect"))
    (pad "33" smd rect locked (at -1.252 -3.775 180) (size 0.3 1.55) (layers "F.Cu" "F.Paste" "F.Mask")
      (net 1 "GND") (pinfunction "GND") (pintype "passive"))
    (pad "34" smd rect locked (at -1.002 3.773 180) (size 0.3 1.55) (layers "F.Cu" "F.Paste" "F.Mask")
      (net 371 "unconnected-(J2-NC-Pad34)") (pinfunction "NC") (pintype "no_connect"))
    (pad "35" smd rect locked (at -0.751 -3.775 180) (size 0.3 1.55) (layers "F.Cu" "F.Paste" "F.Mask")
      (net 214 "Net-(J2-PET1_N)") (pinfunction "PET1_N") (pintype "input"))
    (pad "36" smd rect locked (at -0.501 3.773 180) (size 0.3 1.55) (layers "F.Cu" "F.Paste" "F.Mask")
      (net 372 "unconnected-(J2-NC-Pad36)") (pinfunction "NC") (pintype "no_connect"))
    (pad "37" smd rect locked (at -0.251 -3.775 180) (size 0.3 1.55) (layers "F.Cu" "F.Paste" "F.Mask")
      (net 17 "Net-(J2-PET1_P)") (pinfunction "PET1_P") (pintype "input"))
    (pad "38" smd rect locked (at -0.001 3.773 180) (size 0.3 1.55) (layers "F.Cu" "F.Paste" "F.Mask")
      (net 373 "unconnected-(J2-NC-Pad38)") (pinfunction "NC") (pintype "no_connect"))
    (pad "39" smd rect locked (at 0.248 -3.775 180) (size 0.3 1.55) (layers "F.Cu" "F.Paste" "F.Mask")
      (net 1 "GND") (pinfunction "GND") (pintype "passive"))
    (pad "40" smd rect locked (at 0.498 3.773 180) (size 0.3 1.55) (layers "F.Cu" "F.Paste" "F.Mask")
      (net 374 "unconnected-(J2-SMB_CLK-Pad40)") (pinfunction "SMB_CLK") (pintype "input+no_connect"))
    (pad "41" smd rect locked (at 0.748 -3.775 180) (size 0.3 1.55) (layers "F.Cu" "F.Paste" "F.Mask")
      (net 703 "PCIE_HPM_RX0_N") (pinfunction "PER0_N") (pintype "output"))
    (pad "42" smd rect locked (at 0.998 3.773 180) (size 0.3 1.55) (layers "F.Cu" "F.Paste" "F.Mask")
      (net 375 "unconnected-(J2-SMB_DATA-Pad42)") (pinfunction "SMB_DATA") (pintype "bidirectional+no_connect"))
    (pad "43" smd rect locked (at 1.249 -3.775 180) (size 0.3 1.55) (layers "F.Cu" "F.Paste" "F.Mask")
      (net 702 "PCIE_HPM_RX0_P") (pinfunction "PER0_P") (pintype "output"))
    (pad "44" smd rect locked (at 1.499 3.773 180) (size 0.3 1.55) (layers "F.Cu" "F.Paste" "F.Mask")
      (net 376 "Net-(J2-ALERT)") (pinfunction "ALERT") (pintype "output"))
    (pad "45" smd rect locked (at 1.749 -3.775 180) (size 0.3 1.55) (layers "F.Cu" "F.Paste" "F.Mask")
      (net 1 "GND") (pinfunction "GND") (pintype "passive"))
    (pad "46" smd rect locked (at 1.999 3.773 180) (size 0.3 1.55) (layers "F.Cu" "F.Paste" "F.Mask")
      (net 378 "unconnected-(J2-NC-Pad46)") (pinfunction "NC") (pintype "no_connect"))
    (pad "47" smd rect locked (at 2.249 -3.775 180) (size 0.3 1.55) (layers "F.Cu" "F.Paste" "F.Mask")
      (net 213 "Net-(J2-PET0_N)") (pinfunction "PET0_N") (pintype "input"))
    (pad "48" smd rect locked (at 2.499 3.773 180) (size 0.3 1.55) (layers "F.Cu" "F.Paste" "F.Mask")
      (net 379 "unconnected-(J2-NC-Pad48)") (pinfunction "NC") (pintype "no_connect"))
    (pad "49" smd rect locked (at 2.749 -3.775 180) (size 0.3 1.55) (layers "F.Cu" "F.Paste" "F.Mask")
      (net 16 "Net-(J2-PET0_P)") (pinfunction "PET0_P") (pintype "input"))
    (pad "50" smd rect locked (at 2.999 3.773 180) (size 0.3 1.55) (layers "F.Cu" "F.Paste" "F.Mask")
      (net 58 "PRSNT0_N") (pinfunction "~{PERST}") (pintype "input"))
    (pad "51" smd rect locked (at 3.249 -3.775 180) (size 0.3 1.55) (layers "F.Cu" "F.Paste" "F.Mask")
      (net 1 "GND") (pinfunction "GND") (pintype "passive"))
    (pad "52" smd rect locked (at 3.499 3.773 180) (size 0.3 1.55) (layers "F.Cu" "F.Paste" "F.Mask")
      (net 380 "Net-(J2-~{CLKREQ})") (pinfunction "~{CLKREQ}") (pintype "output"))
    (pad "53" smd rect locked (at 3.749 -3.775 180) (size 0.3 1.55) (layers "F.Cu" "F.Paste" "F.Mask")
      (net 266 "CLK_PCIE_x4_DN") (pinfunction "REFCLK_N") (pintype "input"))
    (pad "54" smd rect locked (at 3.999 3.773 180) (size 0.3 1.55) (layers "F.Cu" "F.Paste" "F.Mask")
      (net 381 "Net-(J2-~{PEWAKE})") (pinfunction "~{PEWAKE}") (pintype "input"))
    (pad "55" smd rect locked (at 4.248 -3.775 180) (size 0.3 1.55) (layers "F.Cu" "F.Paste" "F.Mask")
      (net 264 "CLK_PCIE_x4_DP") (pinfunction "REFCLK_P") (pintype "input"))
    (pad "56" smd rect locked (at 4.498 3.773 180) (size 0.3 1.55) (layers "F.Cu" "F.Paste" "F.Mask")
      (net 382 "unconnected-(J2-NC-Pad56)") (pinfunction "NC") (pintype "no_connect"))
    (pad "57" smd rect locked (at 4.748 -3.775 180) (size 0.3 1.55) (layers "F.Cu" "F.Paste" "F.Mask")
      (net 1 "GND") (pinfunction "GND") (pintype "passive"))
    (pad "58" smd rect locked (at 4.998 3.773 180) (size 0.3 1.55) (layers "F.Cu" "F.Paste" "F.Mask")
      (net 383 "unconnected-(J2-NC-Pad58)") (pinfunction "NC") (pintype "no_connect"))
    (pad "67" smd rect locked (at 7.248 -3.775 180) (size 0.3 1.55) (layers "F.Cu" "F.Paste" "F.Mask")
      (net 384 "unconnected-(J2-NC-Pad67)") (pinfunction "NC") (pintype "no_connect"))
    (pad "68" smd rect locked (at 7.498 3.773 180) (size 0.3 1.55) (layers "F.Cu" "F.Paste" "F.Mask")
      (net 386 "unconnected-(J2-SUSCLK-Pad68)") (pinfunction "SUSCLK") (pintype "input+no_connect"))
    (pad "69" smd rect locked (at 7.748 -3.775 180) (size 0.3 1.55) (layers "F.Cu" "F.Paste" "F.Mask")
      (net 387 "unconnected-(J2-NC-Pad69)") (pinfunction "NC") (pintype "no_connect"))
    (pad "70" smd rect locked (at 7.998 3.773 180) (size 0.3 1.55) (layers "F.Cu" "F.Paste" "F.Mask")
      (net 2 "VCC3V3") (pinfunction "3V3") (pintype "passive"))
    (pad "71" smd rect locked (at 8.247 -3.775 180) (size 0.3 1.55) (layers "F.Cu" "F.Paste" "F.Mask")
      (net 1 "GND") (pinfunction "GND") (pintype "passive"))
    (pad "72" smd rect locked (at 8.497 3.773 180) (size 0.3 1.55) (layers "F.Cu" "F.Paste" "F.Mask")
      (net 2 "VCC3V3") (pinfunction "3V3") (pintype "passive"))
    (pad "73" smd rect locked (at 8.747 -3.775 180) (size 0.3 1.55) (layers "F.Cu" "F.Paste" "F.Mask")
      (net 1 "GND") (pinfunction "GND") (pintype "passive"))
    (pad "74" smd rect locked (at 8.997 3.773 180) (size 0.3 1.55) (layers "F.Cu" "F.Paste" "F.Mask")
      (net 2 "VCC3V3") (pinfunction "3V3") (pintype "passive"))
    (pad "75" smd rect locked (at 9.247 -3.775 180) (size 0.3 1.55) (layers "F.Cu" "F.Paste" "F.Mask")
      (net 1 "GND") (pinfunction "GND") (pintype "passive"))
    (pad "MP1" smd rect locked (at -10.352 -3 180) (size 1.2 2.75) (layers "F.Cu" "F.Paste" "F.Mask")
      (net 1 "GND") (pinfunction "MP") (pintype "passive"))
    (pad "MP2" smd rect locked (at 10.349 -3 180) (size 1.2 2.75) (layers "F.Cu" "F.Paste" "F.Mask")
      (net 1 "GND") (pinfunction "MP") (pintype "passive"))
  )

  (footprint "antmicro-footprints:LED_0603_1608Metric_G" (layer "F.Cu")
    (at 140.9 168.3)
    (descr "LED SMD 0603 Green")
    (tags "LED SMD 0603 Green")
    (property "Author" "Antmicro")
    (property "Color" "Green")
    (property "License" "Apache-2.0")
    (property "MPN" "LG L29K-G2J1-24-Z")
    (property "Manufacturer" "OSRAM")
    (property "Sheetfile" "pcie-conn.kicad_sch")
    (property "Sheetname" "PCIe-connector")
    (property "ki_description" "LED, Green, SMD, 0603, 20 mA, 1.7 V, 570 nm")
    (property "ki_keywords" "SMT, DIODE, SEMICONDUCTOR, LED")
    (attr smd)
    (fp_text reference "D1" (at 0.78 -1.245) (layer "F.SilkS")
        (effects (font (size 0.7 0.7) (thickness 0.127)))
    )
    (fp_text value "LED_G_0603_LG_L29K-G2J1-24-Z" (at 0 1.77) (layer "F.Fab")
        (effects (font (size 1 1) (thickness 0.15)))
    )
    (fp_text user "License: Apache-2.0" (at -1.4224 3.599) (layer "F.Fab") hide
        (effects (font (size 0.7 0.7) (thickness 0.15)) (justify left bottom))
    )
    (fp_text user "${REFERENCE}" (at -1.4224 5.999) (layer "F.Fab") hide
        (effects (font (size 0.7 0.7) (thickness 0.15)) (justify left bottom))
    )
    (fp_text user "Author: Antmicro" (at -1.4224 4.799) (layer "F.Fab") hide
        (effects (font (size 0.7 0.7) (thickness 0.15)) (justify left bottom))
    )
    (fp_line (start -1.18 -0.319) (end -1.18 0.321)
      (stroke (width 0.15) (type solid)) (layer "F.SilkS"))
    (fp_line (start -0.094672 0.001008) (end -0.24 0.001008)
      (stroke (width 0.1) (type solid)) (layer "F.SilkS"))
    (fp_line (start -0.094672 0.001008) (end 0.105328 -0.198992)
      (stroke (width 0.1) (type solid)) (layer "F.SilkS"))
    (fp_line (start -0.094672 0.201008) (end -0.094672 -0.198992)
      (stroke (width 0.1) (type solid)) (layer "F.SilkS"))
    (fp_line (start 0.105328 0.001008) (end 0.24 0.001)
      (stroke (width 0.1) (type solid)) (layer "F.SilkS"))
    (fp_line (start 0.105328 0.201008) (end -0.094672 0.001008)
      (stroke (width 0.1) (type solid)) (layer "F.SilkS"))
    (fp_line (start 0.105328 0.201008) (end 0.105328 -0.198992)
      (stroke (width 0.1) (type solid)) (layer "F.SilkS"))
    (fp_line (start 0.22 -0.35) (end -0.22 -0.35)
      (stroke (width 0.15) (type solid)) (layer "F.SilkS"))
    (fp_line (start 0.22 0.35) (end -0.22 0.35)
      (stroke (width 0.15) (type solid)) (layer "F.SilkS"))
    (fp_rect (start 1.25 0.65) (end -1.25 -0.65)
      (stroke (width 0.05) (type solid)) (fill none) (layer "F.CrtYd"))
    (fp_line (start -0.199 -0.202) (end -0.199 0.1)
      (stroke (width 0.15) (type solid)) (layer "F.Fab"))
    (fp_line (start -0.199 0) (end -0.597 0)
      (stroke (width 0.15) (type solid)) (layer "F.Fab"))
    (fp_line (start -0.199 0.2) (end -0.199 0.1)
      (stroke (width 0.15) (type solid)) (layer "F.Fab"))
    (fp_line (start -0.101 0) (end 0.201 0.2)
      (stroke (width 0.15) (type solid)) (layer "F.Fab"))
    (fp_line (start 0.201 -0.202) (end -0.101 0)
      (stroke (width 0.15) (type solid)) (layer "F.Fab"))
    (fp_line (start 0.201 0) (end 0.201 -0.202)
      (stroke (width 0.15) (type solid)) (layer "F.Fab"))
    (fp_line (start 0.201 0.2) (end 0.201 0)
      (stroke (width 0.15) (type solid)) (layer "F.Fab"))
    (fp_line (start 0.599 0) (end 0.201 0)
      (stroke (width 0.15) (type solid)) (layer "F.Fab"))
    (fp_rect (start 0.848 0.4) (end -0.85 -0.402)
      (stroke (width 0.15) (type solid)) (fill none) (layer "F.Fab"))
    (pad "1" smd roundrect (at -0.7 0 180) (size 0.8 1) (layers "F.Cu" "F.Paste" "F.Mask") (roundrect_rratio 0.2)
      (net 308 "Net-(D1-C)") (pinfunction "C") (pintype "passive"))
    (pad "2" smd roundrect (at 0.7 0 180) (size 0.8 1) (layers "F.Cu" "F.Paste" "F.Mask") (roundrect_rratio 0.2)
      (net 777 "Net-(D1-A)") (pinfunction "A") (pintype "passive"))
  )

  (footprint "antmicro-footprints:SOIC-8_5.3x5.3x2mm_P1.27mm" (layer "F.Cu")
    (at 68.245 134.11)
    (descr "8-Pin SOIC 208-mil")
    (property "Author" "Antmicro")
    (property "License" "Apache-2.0")
    (property "MPN" "W25Q32JVSSIQ")
    (property "Manufacturer" "Winbond")
    (property "Sheetfile" "rot.kicad_sch")
    (property "Sheetname" "RoT")
    (property "ki_description" "Flash Memory, Serial NOR, 32 Mbit, 4M x 8bit, SPI, SOIC, 8 Pins")
    (property "ki_keywords" "FLASH, SPI, MEMORY")
    (attr smd)
    (fp_text reference "U4" (at -0.0015 -3.2) (layer "F.SilkS")
        (effects (font (size 0.7 0.7) (thickness 0.15)) (justify left bottom))
    )
    (fp_text value "W25Q32JVSSIQ" (at 0 3.8) (layer "F.Fab")
        (effects (font (size 0.7 0.7) (thickness 0.15)) (justify left bottom))
    )
    (fp_text user "License: Apache-2.0" (at -4.675 6.938) (layer "F.Fab") hide
        (effects (font (size 0.7 0.7) (thickness 0.15)) (justify left bottom))
    )
    (fp_text user "Author: Antmicro" (at -4.675 5.938) (layer "F.Fab") hide
        (effects (font (size 0.7 0.7) (thickness 0.15)) (justify left bottom))
    )
    (fp_text user "${REFERENCE}" (at -4.675 4.938) (layer "F.Fab") hide
        (effects (font (size 0.7 0.7) (thickness 0.15)) (justify left bottom))
    )
    (fp_line (start -2.8 -2.641) (end -4.4 -2.641)
      (stroke (width 0.15) (type solid)) (layer "F.SilkS"))
    (fp_circle (center -4.85 -1.905) (end -4.8 -1.855)
      (stroke (width 0.15) (type solid)) (fill solid) (layer "F.SilkS"))
    (fp_rect (start 4.675 -3) (end -4.675 3)
      (stroke (width 0.05) (type solid)) (fill none) (layer "F.CrtYd"))
    (fp_line (start -2.641 -2.641) (end 2.64 -2.641)
      (stroke (width 0.15) (type solid)) (layer "F.Fab"))
    (fp_line (start -2.641 -1.371) (end -1.371 -2.641)
      (stroke (width 0.15) (type solid)) (layer "F.Fab"))
    (fp_line (start -2.641 2.64) (end -2.641 -2.641)
      (stroke (width 0.15) (type solid)) (layer "F.Fab"))
    (fp_line (start 2.64 -2.641) (end 2.64 2.64)
      (stroke (width 0.15) (type solid)) (layer "F.Fab"))
    (fp_line (start 2.64 2.64) (end -2.641 2.64)
      (stroke (width 0.15) (type solid)) (layer "F.Fab"))
    (pad "1" smd roundrect (at -3.601 -1.905 90) (size 0.65 1.65) (layers "F.Cu" "F.Paste" "F.Mask") (roundrect_rratio 0.25)
      (net 145 "QSPIA2_CS_N") (pinfunction "~{CS}") (pintype "input"))
    (pad "2" smd roundrect (at -3.601 -0.635 90) (size 0.65 1.65) (layers "F.Cu" "F.Paste" "F.Mask") (roundrect_rratio 0.25)
      (net 142 "QSPIA2_D1") (pinfunction "SO/IO1") (pintype "bidirectional"))
    (pad "3" smd roundrect (at -3.601 0.633 90) (size 0.65 1.65) (layers "F.Cu" "F.Paste" "F.Mask") (roundrect_rratio 0.25)
      (net 143 "QSPIA2_D2") (pinfunction "~{WP}/IO2") (pintype "bidirectional"))
    (pad "4" smd roundrect (at -3.601 1.904 90) (size 0.65 1.65) (layers "F.Cu" "F.Paste" "F.Mask") (roundrect_rratio 0.25)
      (net 1 "GND") (pinfunction "VSS") (pintype "power_in"))
    (pad "5" smd roundrect (at 3.6 1.904 90) (size 0.65 1.65) (layers "F.Cu" "F.Paste" "F.Mask") (roundrect_rratio 0.25)
      (net 141 "QSPIA2_D0") (pinfunction "SI/IO0") (pintype "bidirectional"))
    (pad "6" smd roundrect (at 3.6 0.633 90) (size 0.65 1.65) (layers "F.Cu" "F.Paste" "F.Mask") (roundrect_rratio 0.25)
      (net 135 "QSPIA_CLK") (pinfunction "SCLK") (pintype "input"))
    (pad "7" smd roundrect (at 3.6 -0.635 90) (size 0.65 1.65) (layers "F.Cu" "F.Paste" "F.Mask") (roundrect_rratio 0.25)
      (net 144 "QSPIA2_D3") (pinfunction "~{HOLD}/IO3") (pintype "bidirectional"))
    (pad "8" smd roundrect (at 3.6 -1.905 90) (size 0.65 1.65) (layers "F.Cu" "F.Paste" "F.Mask") (roundrect_rratio 0.25)
      (net 2 "VCC3V3") (pinfunction "VCC") (pintype "power_in"))
  )

  (footprint "antmicro-footprints:SOIC-8_5.3x5.3x2mm_P1.27mm" (layer "F.Cu")
    (at 68.245 143.01)
    (descr "8-Pin SOIC 208-mil")
    (property "Author" "Antmicro")
    (property "License" "Apache-2.0")
    (property "MPN" "W25Q32JVSSIQ")
    (property "Manufacturer" "Winbond")
    (property "Sheetfile" "rot.kicad_sch")
    (property "Sheetname" "RoT")
    (property "ki_description" "Flash Memory, Serial NOR, 32 Mbit, 4M x 8bit, SPI, SOIC, 8 Pins")
    (property "ki_keywords" "FLASH, SPI, MEMORY")
    (attr smd)
    (fp_text reference "U5" (at -0.0015 -3.2) (layer "F.SilkS")
        (effects (font (size 0.7 0.7) (thickness 0.15)) (justify left bottom))
    )
    (fp_text value "W25Q32JVSSIQ" (at 0 3.8) (layer "F.Fab")
        (effects (font (size 0.7 0.7) (thickness 0.15)) (justify left bottom))
    )
    (fp_text user "${REFERENCE}" (at -4.675 4.938) (layer "F.Fab") hide
        (effects (font (size 0.7 0.7) (thickness 0.15)) (justify left bottom))
    )
    (fp_text user "License: Apache-2.0" (at -4.675 6.938) (layer "F.Fab") hide
        (effects (font (size 0.7 0.7) (thickness 0.15)) (justify left bottom))
    )
    (fp_text user "Author: Antmicro" (at -4.675 5.938) (layer "F.Fab") hide
        (effects (font (size 0.7 0.7) (thickness 0.15)) (justify left bottom))
    )
    (fp_line (start -2.8 -2.641) (end -4.4 -2.641)
      (stroke (width 0.15) (type solid)) (layer "F.SilkS"))
    (fp_circle (center -4.85 -1.905) (end -4.8 -1.855)
      (stroke (width 0.15) (type solid)) (fill solid) (layer "F.SilkS"))
    (fp_rect (start 4.675 -3) (end -4.675 3)
      (stroke (width 0.05) (type solid)) (fill none) (layer "F.CrtYd"))
    (fp_line (start -2.641 -2.641) (end 2.64 -2.641)
      (stroke (width 0.15) (type solid)) (layer "F.Fab"))
    (fp_line (start -2.641 -1.371) (end -1.371 -2.641)
      (stroke (width 0.15) (type solid)) (layer "F.Fab"))
    (fp_line (start -2.641 2.64) (end -2.641 -2.641)
      (stroke (width 0.15) (type solid)) (layer "F.Fab"))
    (fp_line (start 2.64 -2.641) (end 2.64 2.64)
      (stroke (width 0.15) (type solid)) (layer "F.Fab"))
    (fp_line (start 2.64 2.64) (end -2.641 2.64)
      (stroke (width 0.15) (type solid)) (layer "F.Fab"))
    (pad "1" smd roundrect (at -3.601 -1.905 90) (size 0.65 1.65) (layers "F.Cu" "F.Paste" "F.Mask") (roundrect_rratio 0.25)
      (net 140 "QSPIA1_CS_N") (pinfunction "~{CS}") (pintype "input"))
    (pad "2" smd roundrect (at -3.601 -0.635 90) (size 0.65 1.65) (layers "F.Cu" "F.Paste" "F.Mask") (roundrect_rratio 0.25)
      (net 137 "QSPIA1_D1") (pinfunction "SO/IO1") (pintype "bidirectional"))
    (pad "3" smd roundrect (at -3.601 0.633 90) (size 0.65 1.65) (layers "F.Cu" "F.Paste" "F.Mask") (roundrect_rratio 0.25)
      (net 138 "QSPIA1_D2") (pinfunction "~{WP}/IO2") (pintype "bidirectional"))
    (pad "4" smd roundrect (at -3.601 1.904 90) (size 0.65 1.65) (layers "F.Cu" "F.Paste" "F.Mask") (roundrect_rratio 0.25)
      (net 1 "GND") (pinfunction "VSS") (pintype "power_in"))
    (pad "5" smd roundrect (at 3.6 1.904 90) (size 0.65 1.65) (layers "F.Cu" "F.Paste" "F.Mask") (roundrect_rratio 0.25)
      (net 136 "QSPIA1_D0") (pinfunction "SI/IO0") (pintype "bidirectional"))
    (pad "6" smd roundrect (at 3.6 0.633 90) (size 0.65 1.65) (layers "F.Cu" "F.Paste" "F.Mask") (roundrect_rratio 0.25)
      (net 135 "QSPIA_CLK") (pinfunction "SCLK") (pintype "input"))
    (pad "7" smd roundrect (at 3.6 -0.635 90) (size 0.65 1.65) (layers "F.Cu" "F.Paste" "F.Mask") (roundrect_rratio 0.25)
      (net 139 "QSPIA1_D3") (pinfunction "~{HOLD}/IO3") (pintype "bidirectional"))
    (pad "8" smd roundrect (at 3.6 -1.905 90) (size 0.65 1.65) (layers "F.Cu" "F.Paste" "F.Mask") (roundrect_rratio 0.25)
      (net 2 "VCC3V3") (pinfunction "VCC") (pintype "power_in"))
  )

  (footprint "antmicro-footprints:RJ45_BEL_L834-1G1T-S7" (layer "F.Cu")
    (at 99.955 80.845 180)
    (property "Author" "Antmicro")
    (property "License" "Apache-2.0")
    (property "MPN" "L834-1G1T-S7")
    (property "Manufacturer" "Bel Fuse")
    (property "Sheetfile" "ethernet.kicad_sch")
    (property "Sheetname" "Ethernet")
    (property "ki_description" "Modular connector with magnetics")
    (property "ki_keywords" "HORIZONTAL, THT, FILTERED, CONNECTOR, ETHERNET")
    (attr through_hole)
    (fp_text reference "J1" (at 6.97 -12.09) (layer "F.SilkS")
        (effects (font (size 0.7 0.7) (thickness 0.127)))
    )
    (fp_text value "L834-1G1T-S7" (at 2.16 -12.635) (layer "F.Fab")
        (effects (font (size 1 1) (thickness 0.015)))
    )
    (fp_text user "Author: Antmicro" (at -15.042 25.39 180) (layer "F.Fab") hide
        (effects (font (size 0.7 0.7) (thickness 0.15)) (justify left bottom))
    )
    (fp_text user "${REFERENCE}" (at -15.042 24.19 180) (layer "F.Fab") hide
        (effects (font (size 0.7 0.7) (thickness 0.15)) (justify left bottom))
    )
    (fp_text user "License: Apache-2.0" (at -15.042 26.589 180) (layer "F.Fab") hide
        (effects (font (size 0.7 0.7) (thickness 0.15)) (justify left bottom))
    )
    (fp_line (start -13.34 -4.121) (end -13.34 -0.471)
      (stroke (width 0.15) (type solid)) (layer "F.SilkS"))
    (fp_line (start -13.34 2.53) (end -13.34 3.93)
      (stroke (width 0.15) (type solid)) (layer "F.SilkS"))
    (fp_line (start -13.34 10.13) (end -13.34 18.158)
      (stroke (width 0.15) (type solid)) (layer "F.SilkS"))
    (fp_line (start 3.179 -4.121) (end -13.34 -4.121)
      (stroke (width 0.15) (type solid)) (layer "F.SilkS"))
    (fp_line (start 3.179 -4.121) (end 3.179 1.929)
      (stroke (width 0.15) (type solid)) (layer "F.SilkS"))
    (fp_line (start 3.179 8.13) (end 3.179 9.529)
      (stroke (width 0.15) (type solid)) (layer "F.SilkS"))
    (fp_line (start 3.179 12.53) (end 3.179 18.158)
      (stroke (width 0.15) (type solid)) (layer "F.SilkS"))
    (fp_line (start -15.06 22.19) (end -15.06 -0.3)
      (stroke (width 0.05) (type solid)) (layer "F.CrtYd"))
    (fp_line (start -13.6 -4.4) (end 3.5 -4.4)
      (stroke (width 0.05) (type solid)) (layer "F.CrtYd"))
    (fp_line (start -13.6 -0.3) (end -15.06 -0.3)
      (stroke (width 0.05) (type solid)) (layer "F.CrtYd"))
    (fp_line (start -13.6 -0.3) (end -13.6 -4.4)
      (stroke (width 0.05) (type solid)) (layer "F.CrtYd"))
    (fp_line (start 3.5 -0.3) (end 3.5 -4.4)
      (stroke (width 0.05) (type solid)) (layer "F.CrtYd"))
    (fp_line (start 4.87 -0.3) (end 3.5 -0.3)
      (stroke (width 0.05) (type solid)) (layer "F.CrtYd"))
    (fp_line (start 4.87 -0.3) (end 4.87 22.19)
      (stroke (width 0.05) (type solid)) (layer "F.CrtYd"))
    (fp_line (start 4.87 22.19) (end -15.06 22.19)
      (stroke (width 0.05) (type solid)) (layer "F.CrtYd"))
    (fp_line (start -13.34 -4.121) (end -13.34 21.94)
      (stroke (width 0.15) (type solid)) (layer "F.Fab"))
    (fp_line (start -13.34 21.94) (end 3.179 21.94)
      (stroke (width 0.15) (type solid)) (layer "F.Fab"))
    (fp_line (start 3.179 -4.121) (end -13.34 -4.121)
      (stroke (width 0.15) (type solid)) (layer "F.Fab"))
    (fp_line (start 3.179 21.94) (end 3.179 -4.121)
      (stroke (width 0.15) (type solid)) (layer "F.Fab"))
    (fp_arc (start -13.34 21.94) (mid -14.551 18.158) (end -14.74 14.192)
      (stroke (width 0.15) (type solid)) (layer "F.Fab"))
    (fp_arc (start 4.578 14.192) (mid 4.389 18.158) (end 3.179 21.94)
      (stroke (width 0.15) (type solid)) (layer "F.Fab"))
    (pad "" np_thru_hole circle (at -13.235 1.009 180) (size 2.31 2.31) (drill 2.31) (layers "*.Cu" "*.Mask"))
    (pad "" np_thru_hole circle (at -13.235 8.63 180) (size 2.31 2.31) (drill 2.31) (layers "*.Cu" "*.Mask"))
    (pad "" np_thru_hole circle (at 3.073 3.43 180) (size 2.31 2.31) (drill 2.31) (layers "*.Cu" "*.Mask"))
    (pad "" np_thru_hole circle (at 3.073 11.047 180) (size 2.31 2.31) (drill 2.31) (layers "*.Cu" "*.Mask"))
    (pad "1" thru_hole rect (at 0 0 180) (size 1.53 1.53) (drill 1.02) (layers "*.Cu" "*.Mask")
      (net 13 "Net-(J1-TRCT3)") (pinfunction "TRCT3") (pintype "passive"))
    (pad "2" thru_hole circle (at -2.032 0 180) (size 1.53 1.53) (drill 1.02) (layers "*.Cu" "*.Mask")
      (net 152 "/Ethernet/ETH3_N") (pinfunction "TRD3-") (pintype "passive"))
    (pad "3" thru_hole circle (at -4.064 0 180) (size 1.53 1.53) (drill 1.02) (layers "*.Cu" "*.Mask")
      (net 146 "/Ethernet/ETH3_P") (pinfunction "TRD3+") (pintype "passive"))
    (pad "4" thru_hole circle (at -6.096 0 180) (size 1.53 1.53) (drill 1.02) (layers "*.Cu" "*.Mask")
      (net 147 "/Ethernet/ETH2_P") (pinfunction "TRD2+") (pintype "passive"))
    (pad "5" thru_hole circle (at -8.128 0 180) (size 1.53 1.53) (drill 1.02) (layers "*.Cu" "*.Mask")
      (net 150 "/Ethernet/ETH2_N") (pinfunction "TRD2-") (pintype "passive"))
    (pad "6" thru_hole circle (at -10.16 0 180) (size 1.53 1.53) (drill 1.02) (layers "*.Cu" "*.Mask")
      (net 8 "Net-(J1-TRCT2)") (pinfunction "TRCT2") (pintype "passive"))
    (pad "7" thru_hole circle (at 1.015 -2.54 180) (size 1.53 1.53) (drill 1.02) (layers "*.Cu" "*.Mask")
      (net 14 "Net-(J1-TRCT4)") (pinfunction "TRCT4") (pintype "passive"))
    (pad "8" thru_hole circle (at -1.016 -2.54 180) (size 1.53 1.53) (drill 1.02) (layers "*.Cu" "*.Mask")
      (net 149 "/Ethernet/ETH4_P") (pinfunction "TRD4+") (pintype "passive"))
    (pad "9" thru_hole circle (at -3.048 -2.54 180) (size 1.53 1.53) (drill 1.02) (layers "*.Cu" "*.Mask")
      (net 153 "/Ethernet/ETH4_N") (pinfunction "TRD4-") (pintype "passive"))
    (pad "10" thru_hole circle (at -7.112 -2.54 180) (size 1.53 1.53) (drill 1.02) (layers "*.Cu" "*.Mask")
      (net 151 "/Ethernet/ETH1_N") (pinfunction "TRD1-") (pintype "passive"))
    (pad "11" thru_hole circle (at -9.144 -2.54 180) (size 1.53 1.53) (drill 1.02) (layers "*.Cu" "*.Mask")
      (net 148 "/Ethernet/ETH1_P") (pinfunction "TRD1+") (pintype "passive"))
    (pad "12" thru_hole circle (at -11.176 -2.54 180) (size 1.53 1.53) (drill 1.02) (layers "*.Cu" "*.Mask")
      (net 7 "Net-(J1-TRCT1)") (pinfunction "TRCT1") (pintype "passive"))
    (pad "13" thru_hole circle (at 1.945 13.97 180) (size 1.725 1.725) (drill 1.15) (layers "*.Cu" "*.Mask")
      (net 680 "Net-(J1-Pad13)") (pintype "passive"))
    (pad "14" thru_hole circle (at 1.945 16.508 180) (size 1.725 1.725) (drill 1.15) (layers "*.Cu" "*.Mask")
      (net 2 "VCC3V3") (pintype "passive"))
    (pad "15" thru_hole circle (at -12.106 13.97 180) (size 1.725 1.725) (drill 1.15) (layers "*.Cu" "*.Mask")
      (net 681 "Net-(J1-Pad15)") (pintype "passive"))
    (pad "16" thru_hole circle (at -12.106 16.508 180) (size 1.725 1.725) (drill 1.15) (layers "*.Cu" "*.Mask")
      (net 2 "VCC3V3") (pintype "passive"))
    (pad "SH" thru_hole circle (at -13.235 5.328 180) (size 2.1 2.1) (drill 1.4) (layers "*.Cu" "*.Mask")
      (net 1 "GND") (pinfunction "SH") (pintype "passive"))
    (pad "SH" thru_hole circle (at 3.073 6.73 180) (size 2.1 2.1) (drill 1.4) (layers "*.Cu" "*.Mask")
      (net 1 "GND") (pinfunction "SH") (pintype "passive"))
  )

  (footprint "antmicro-footprints:SOIC-8_5.3x5.3x2mm_P1.27mm" (layer "F.Cu")
    (at 79.495 134.11)
    (descr "8-Pin SOIC 208-mil")
    (property "Author" "Antmicro")
    (property "License" "Apache-2.0")
    (property "MPN" "W25Q32JVSSIQ")
    (property "Manufacturer" "Winbond")
    (property "Sheetfile" "rot.kicad_sch")
    (property "Sheetname" "RoT")
    (property "ki_description" "Flash Memory, Serial NOR, 32 Mbit, 4M x 8bit, SPI, SOIC, 8 Pins")
    (property "ki_keywords" "FLASH, SPI, MEMORY")
    (attr smd)
    (fp_text reference "U3" (at -0.0015 -3.2) (layer "F.SilkS")
        (effects (font (size 0.7 0.7) (thickness 0.15)) (justify left bottom))
    )
    (fp_text value "W25Q32JVSSIQ" (at 0 3.8) (layer "F.Fab")
        (effects (font (size 0.7 0.7) (thickness 0.15)) (justify left bottom))
    )
    (fp_text user "License: Apache-2.0" (at -4.675 6.938) (layer "F.Fab") hide
        (effects (font (size 0.7 0.7) (thickness 0.15)) (justify left bottom))
    )
    (fp_text user "${REFERENCE}" (at -4.675 4.938) (layer "F.Fab") hide
        (effects (font (size 0.7 0.7) (thickness 0.15)) (justify left bottom))
    )
    (fp_text user "Author: Antmicro" (at -4.675 5.938) (layer "F.Fab") hide
        (effects (font (size 0.7 0.7) (thickness 0.15)) (justify left bottom))
    )
    (fp_line (start -2.8 -2.641) (end -4.4 -2.641)
      (stroke (width 0.15) (type solid)) (layer "F.SilkS"))
    (fp_circle (center -4.85 -1.905) (end -4.8 -1.855)
      (stroke (width 0.15) (type solid)) (fill solid) (layer "F.SilkS"))
    (fp_rect (start 4.675 -3) (end -4.675 3)
      (stroke (width 0.05) (type solid)) (fill none) (layer "F.CrtYd"))
    (fp_line (start -2.641 -2.641) (end 2.64 -2.641)
      (stroke (width 0.15) (type solid)) (layer "F.Fab"))
    (fp_line (start -2.641 -1.371) (end -1.371 -2.641)
      (stroke (width 0.15) (type solid)) (layer "F.Fab"))
    (fp_line (start -2.641 2.64) (end -2.641 -2.641)
      (stroke (width 0.15) (type solid)) (layer "F.Fab"))
    (fp_line (start 2.64 -2.641) (end 2.64 2.64)
      (stroke (width 0.15) (type solid)) (layer "F.Fab"))
    (fp_line (start 2.64 2.64) (end -2.641 2.64)
      (stroke (width 0.15) (type solid)) (layer "F.Fab"))
    (pad "1" smd roundrect (at -3.601 -1.905 90) (size 0.65 1.65) (layers "F.Cu" "F.Paste" "F.Mask") (roundrect_rratio 0.25)
      (net 129 "QSPIB1_CS_N") (pinfunction "~{CS}") (pintype "input"))
    (pad "2" smd roundrect (at -3.601 -0.635 90) (size 0.65 1.65) (layers "F.Cu" "F.Paste" "F.Mask") (roundrect_rratio 0.25)
      (net 126 "QSPIB1_D1") (pinfunction "SO/IO1") (pintype "bidirectional"))
    (pad "3" smd roundrect (at -3.601 0.633 90) (size 0.65 1.65) (layers "F.Cu" "F.Paste" "F.Mask") (roundrect_rratio 0.25)
      (net 127 "QSPIB1_D2") (pinfunction "~{WP}/IO2") (pintype "bidirectional"))
    (pad "4" smd roundrect (at -3.601 1.904 90) (size 0.65 1.65) (layers "F.Cu" "F.Paste" "F.Mask") (roundrect_rratio 0.25)
      (net 1 "GND") (pinfunction "VSS") (pintype "power_in"))
    (pad "5" smd roundrect (at 3.6 1.904 90) (size 0.65 1.65) (layers "F.Cu" "F.Paste" "F.Mask") (roundrect_rratio 0.25)
      (net 125 "QSPIB1_D0") (pinfunction "SI/IO0") (pintype "bidirectional"))
    (pad "6" smd roundrect (at 3.6 0.633 90) (size 0.65 1.65) (layers "F.Cu" "F.Paste" "F.Mask") (roundrect_rratio 0.25)
      (net 124 "QSPIB_CLK") (pinfunction "SCLK") (pintype "input"))
    (pad "7" smd roundrect (at 3.6 -0.635 90) (size 0.65 1.65) (layers "F.Cu" "F.Paste" "F.Mask") (roundrect_rratio 0.25)
      (net 128 "QSPIB1_D3") (pinfunction "~{HOLD}/IO3") (pintype "bidirectional"))
    (pad "8" smd roundrect (at 3.6 -1.905 90) (size 0.65 1.65) (layers "F.Cu" "F.Paste" "F.Mask") (roundrect_rratio 0.25)
      (net 2 "VCC3V3") (pinfunction "VCC") (pintype "power_in"))
  )

  (footprint "antmicro-footprints:SOIC-8_5.3x5.3x2mm_P1.27mm" (layer "F.Cu")
    (at 79.495 143.01)
    (descr "8-Pin SOIC 208-mil")
    (property "Author" "Antmicro")
    (property "License" "Apache-2.0")
    (property "MPN" "W25Q32JVSSIQ")
    (property "Manufacturer" "Winbond")
    (property "Sheetfile" "rot.kicad_sch")
    (property "Sheetname" "RoT")
    (property "ki_description" "Flash Memory, Serial NOR, 32 Mbit, 4M x 8bit, SPI, SOIC, 8 Pins")
    (property "ki_keywords" "FLASH, SPI, MEMORY")
    (attr smd)
    (fp_text reference "U2" (at -0.0015 -3.2) (layer "F.SilkS")
        (effects (font (size 0.7 0.7) (thickness 0.15)) (justify left bottom))
    )
    (fp_text value "W25Q32JVSSIQ" (at 0 3.8) (layer "F.Fab")
        (effects (font (size 0.7 0.7) (thickness 0.15)) (justify left bottom))
    )
    (fp_text user "License: Apache-2.0" (at -4.675 6.938) (layer "F.Fab") hide
        (effects (font (size 0.7 0.7) (thickness 0.15)) (justify left bottom))
    )
    (fp_text user "${REFERENCE}" (at -4.675 4.938) (layer "F.Fab") hide
        (effects (font (size 0.7 0.7) (thickness 0.15)) (justify left bottom))
    )
    (fp_text user "Author: Antmicro" (at -4.675 5.938) (layer "F.Fab") hide
        (effects (font (size 0.7 0.7) (thickness 0.15)) (justify left bottom))
    )
    (fp_line (start -2.8 -2.641) (end -4.4 -2.641)
      (stroke (width 0.15) (type solid)) (layer "F.SilkS"))
    (fp_circle (center -4.85 -1.905) (end -4.8 -1.855)
      (stroke (width 0.15) (type solid)) (fill solid) (layer "F.SilkS"))
    (fp_rect (start 4.675 -3) (end -4.675 3)
      (stroke (width 0.05) (type solid)) (fill none) (layer "F.CrtYd"))
    (fp_line (start -2.641 -2.641) (end 2.64 -2.641)
      (stroke (width 0.15) (type solid)) (layer "F.Fab"))
    (fp_line (start -2.641 -1.371) (end -1.371 -2.641)
      (stroke (width 0.15) (type solid)) (layer "F.Fab"))
    (fp_line (start -2.641 2.64) (end -2.641 -2.641)
      (stroke (width 0.15) (type solid)) (layer "F.Fab"))
    (fp_line (start 2.64 -2.641) (end 2.64 2.64)
      (stroke (width 0.15) (type solid)) (layer "F.Fab"))
    (fp_line (start 2.64 2.64) (end -2.641 2.64)
      (stroke (width 0.15) (type solid)) (layer "F.Fab"))
    (pad "1" smd roundrect (at -3.601 -1.905 90) (size 0.65 1.65) (layers "F.Cu" "F.Paste" "F.Mask") (roundrect_rratio 0.25)
      (net 134 "QSPIB2_CS_N") (pinfunction "~{CS}") (pintype "input"))
    (pad "2" smd roundrect (at -3.601 -0.635 90) (size 0.65 1.65) (layers "F.Cu" "F.Paste" "F.Mask") (roundrect_rratio 0.25)
      (net 131 "QSPIB2_D1") (pinfunction "SO/IO1") (pintype "bidirectional"))
    (pad "3" smd roundrect (at -3.601 0.633 90) (size 0.65 1.65) (layers "F.Cu" "F.Paste" "F.Mask") (roundrect_rratio 0.25)
      (net 132 "QSPIB2_D2") (pinfunction "~{WP}/IO2") (pintype "bidirectional"))
    (pad "4" smd roundrect (at -3.601 1.904 90) (size 0.65 1.65) (layers "F.Cu" "F.Paste" "F.Mask") (roundrect_rratio 0.25)
      (net 1 "GND") (pinfunction "VSS") (pintype "power_in"))
    (pad "5" smd roundrect (at 3.6 1.904 90) (size 0.65 1.65) (layers "F.Cu" "F.Paste" "F.Mask") (roundrect_rratio 0.25)
      (net 130 "QSPIB2_D0") (pinfunction "SI/IO0") (pintype "bidirectional"))
    (pad "6" smd roundrect (at 3.6 0.633 90) (size 0.65 1.65) (layers "F.Cu" "F.Paste" "F.Mask") (roundrect_rratio 0.25)
      (net 124 "QSPIB_CLK") (pinfunction "SCLK") (pintype "input"))
    (pad "7" smd roundrect (at 3.6 -0.635 90) (size 0.65 1.65) (layers "F.Cu" "F.Paste" "F.Mask") (roundrect_rratio 0.25)
      (net 133 "QSPIB2_D3") (pinfunction "~{HOLD}/IO3") (pintype "bidirectional"))
    (pad "8" smd roundrect (at 3.6 -1.905 90) (size 0.65 1.65) (layers "F.Cu" "F.Paste" "F.Mask") (roundrect_rratio 0.25)
      (net 2 "VCC3V3") (pinfunction "VCC") (pintype "power_in"))
  )

  (footprint "antmicro-footprints:R_0402_1005Metric" (layer "F.Cu")
    (at 75.975 165.36 180)
    (descr "Resistor SMD 0402")
    (tags "resistor SMD 0402")
    (property "Author" "Antmicro")
    (property "License" "Apache-2.0")
    (property "MPN" "CR0402-FX-1002GLF")
    (property "Manufacturer" "Bourns")
    (property "Public" "False")
    (property "Sheetfile" "fpga-banks.kicad_sch")
    (property "Sheetname" "FPGA banks")
    (property "Tolerance" "1%")
    (property "Val" "10k")
    (property "ki_description" "SMD Chip Resistor, 10 kohm, ± 1%, 62.5 mW, 0402 [1005 Metric], Thick Film, General Purpose")
    (property "ki_keywords" "0402, SMT, RESISTOR, PASSIVE")
    (attr smd)
    (fp_text reference "R126" (at -2.4 -0.07) (layer "F.SilkS")
        (effects (font (size 0.7 0.7) (thickness 0.127)))
    )
    (fp_text value "R_10k_0402" (at 0 1.17) (layer "F.Fab")
        (effects (font (size 1 1) (thickness 0.15)))
    )
    (fp_text user "Author: Antmicro" (at -0.95 4.169 180) (layer "F.Fab") hide
        (effects (font (size 0.7 0.7) (thickness 0.15)) (justify left bottom))
    )
    (fp_text user "${REFERENCE}" (at 0 0) (layer "F.Fab")
        (effects (font (size 0.25 0.25) (thickness 0.04)))
    )
    (fp_text user "License: Apache-2.0" (at -0.95 5.169 180) (layer "F.Fab") hide
        (effects (font (size 0.7 0.7) (thickness 0.15)) (justify left bottom))
    )
    (fp_rect (start -0.925 -0.47) (end 0.925 0.47)
      (stroke (width 0.05) (type default)) (fill none) (layer "F.CrtYd"))
    (fp_rect (start -0.5 -0.25) (end 0.5 0.25)
      (stroke (width 0.15) (type solid)) (fill none) (layer "F.Fab"))
    (pad "1" smd roundrect (at -0.48 0 180) (size 0.59 0.64) (layers "F.Cu" "F.Paste" "F.Mask") (roundrect_rratio 0.25)
      (net 278 "DONE") (pintype "passive"))
    (pad "2" smd roundrect (at 0.48 0 180) (size 0.59 0.64) (layers "F.Cu" "F.Paste" "F.Mask") (roundrect_rratio 0.25)
      (net 2 "VCC3V3") (pintype "passive"))
  )

  (footprint "antmicro-footprints:R_0402_1005Metric" (layer "F.Cu")
    (at 73.77 161.02 180)
    (descr "Resistor SMD 0402")
    (tags "resistor SMD 0402")
    (property "Author" "Antmicro")
    (property "License" "Apache-2.0")
    (property "MPN" "CR0402-FX-1002GLF")
    (property "Manufacturer" "Bourns")
    (property "Public" "False")
    (property "Sheetfile" "fpga-banks.kicad_sch")
    (property "Sheetname" "FPGA banks")
    (property "Tolerance" "1%")
    (property "Val" "10k")
    (property "ki_description" "SMD Chip Resistor, 10 kohm, ± 1%, 62.5 mW, 0402 [1005 Metric], Thick Film, General Purpose")
    (property "ki_keywords" "0402, SMT, RESISTOR, PASSIVE")
    (attr smd)
    (fp_text reference "R127" (at -0.64 0.96) (layer "F.SilkS")
        (effects (font (size 0.7 0.7) (thickness 0.127)))
    )
    (fp_text value "R_10k_0402" (at 0 1.17) (layer "F.Fab")
        (effects (font (size 1 1) (thickness 0.15)))
    )
    (fp_text user "License: Apache-2.0" (at -0.95 5.169 180) (layer "F.Fab") hide
        (effects (font (size 0.7 0.7) (thickness 0.15)) (justify left bottom))
    )
    (fp_text user "Author: Antmicro" (at -0.95 4.169 180) (layer "F.Fab") hide
        (effects (font (size 0.7 0.7) (thickness 0.15)) (justify left bottom))
    )
    (fp_text user "${REFERENCE}" (at 0 0) (layer "F.Fab")
        (effects (font (size 0.25 0.25) (thickness 0.04)))
    )
    (fp_rect (start -0.925 -0.47) (end 0.925 0.47)
      (stroke (width 0.05) (type default)) (fill none) (layer "F.CrtYd"))
    (fp_rect (start -0.5 -0.25) (end 0.5 0.25)
      (stroke (width 0.15) (type solid)) (fill none) (layer "F.Fab"))
    (pad "1" smd roundrect (at -0.48 0 180) (size 0.59 0.64) (layers "F.Cu" "F.Paste" "F.Mask") (roundrect_rratio 0.25)
      (net 269 "INIT_N") (pintype "passive"))
    (pad "2" smd roundrect (at 0.48 0 180) (size 0.59 0.64) (layers "F.Cu" "F.Paste" "F.Mask") (roundrect_rratio 0.25)
      (net 2 "VCC3V3") (pintype "passive"))
  )

  (footprint "antmicro-footprints:R_0402_1005Metric" (layer "F.Cu")
    (at 75.99 164.16)
    (descr "Resistor SMD 0402")
    (tags "resistor SMD 0402")
    (property "Author" "Antmicro")
    (property "License" "Apache-2.0")
    (property "MPN" "CR0402-FX-22R0GLF")
    (property "Manufacturer" "Bourns")
    (property "Public" "False")
    (property "Sheetfile" "fpga-banks.kicad_sch")
    (property "Sheetname" "FPGA banks")
    (property "Tolerance" "1%")
    (property "Val" "22R")
    (property "ki_description" "SMD Chip Resistor, 22 ohm, ± 1%, 62.5 mW, 0402 [1005 Metric], Thick Film, General Purpose")
    (property "ki_keywords" "0402, SMT, RESISTOR, PASSIVE")
    (attr smd)
    (fp_text reference "R128" (at -0.04 -0.915) (layer "F.SilkS")
        (effects (font (size 0.7 0.7) (thickness 0.127)))
    )
    (fp_text value "R_22R_0402" (at 0 1.17) (layer "F.Fab")
        (effects (font (size 1 1) (thickness 0.15)))
    )
    (fp_text user "Author: Antmicro" (at -0.95 4.169) (layer "F.Fab") hide
        (effects (font (size 0.7 0.7) (thickness 0.15)) (justify left bottom))
    )
    (fp_text user "${REFERENCE}" (at 0 0) (layer "F.Fab")
        (effects (font (size 0.25 0.25) (thickness 0.04)))
    )
    (fp_text user "License: Apache-2.0" (at -0.95 5.169) (layer "F.Fab") hide
        (effects (font (size 0.7 0.7) (thickness 0.15)) (justify left bottom))
    )
    (fp_rect (start -0.925 -0.47) (end 0.925 0.47)
      (stroke (width 0.05) (type default)) (fill none) (layer "F.CrtYd"))
    (fp_rect (start -0.5 -0.25) (end 0.5 0.25)
      (stroke (width 0.15) (type solid)) (fill none) (layer "F.Fab"))
    (pad "1" smd roundrect (at -0.48 0) (size 0.59 0.64) (layers "F.Cu" "F.Paste" "F.Mask") (roundrect_rratio 0.25)
      (net 401 "Net-(Q17-G)") (pintype "passive"))
    (pad "2" smd roundrect (at 0.48 0) (size 0.59 0.64) (layers "F.Cu" "F.Paste" "F.Mask") (roundrect_rratio 0.25)
      (net 278 "DONE") (pintype "passive"))
  )

  (footprint "antmicro-footprints:R_0402_1005Metric" (layer "F.Cu")
    (at 71.78 161.02 180)
    (descr "Resistor SMD 0402")
    (tags "resistor SMD 0402")
    (property "Author" "Antmicro")
    (property "License" "Apache-2.0")
    (property "MPN" "CR0402-FX-1001GLF")
    (property "Manufacturer" "Bourns")
    (property "Public" "False")
    (property "Sheetfile" "fpga-banks.kicad_sch")
    (property "Sheetname" "FPGA banks")
    (property "Tolerance" "1%")
    (property "Val" "1k")
    (property "ki_description" "SMD Chip Resistor, 1 kohm, ± 1%, 63 mW, 0402 [1005 Metric], Thick Film, General Purpose")
    (property "ki_keywords" "0402, SMT, RESISTOR, PASSIVE")
    (attr smd)
    (fp_text reference "R129" (at 0.37 0.96) (layer "F.SilkS")
        (effects (font (size 0.7 0.7) (thickness 0.127)))
    )
    (fp_text value "R_1k_0402" (at 0 1.17) (layer "F.Fab")
        (effects (font (size 1 1) (thickness 0.15)))
    )
    (fp_text user "${REFERENCE}" (at 0 0) (layer "F.Fab")
        (effects (font (size 0.25 0.25) (thickness 0.04)))
    )
    (fp_text user "License: Apache-2.0" (at -0.95 5.169 180) (layer "F.Fab") hide
        (effects (font (size 0.7 0.7) (thickness 0.15)) (justify left bottom))
    )
    (fp_text user "Author: Antmicro" (at -0.95 4.169 180) (layer "F.Fab") hide
        (effects (font (size 0.7 0.7) (thickness 0.15)) (justify left bottom))
    )
    (fp_rect (start -0.925 -0.47) (end 0.925 0.47)
      (stroke (width 0.05) (type default)) (fill none) (layer "F.CrtYd"))
    (fp_rect (start -0.5 -0.25) (end 0.5 0.25)
      (stroke (width 0.15) (type solid)) (fill none) (layer "F.Fab"))
    (pad "1" smd roundrect (at -0.48 0 180) (size 0.59 0.64) (layers "F.Cu" "F.Paste" "F.Mask") (roundrect_rratio 0.25)
      (net 2 "VCC3V3") (pintype "passive"))
    (pad "2" smd roundrect (at 0.48 0 180) (size 0.59 0.64) (layers "F.Cu" "F.Paste" "F.Mask") (roundrect_rratio 0.25)
      (net 348 "Net-(D14-A)") (pintype "passive"))
  )

  (footprint "antmicro-footprints:LED_0603_1608Metric_G" (layer "F.Cu")
    (at 73.31 162.33 180)
    (descr "LED SMD 0603 Green")
    (tags "LED SMD 0603 Green")
    (property "Author" "Antmicro")
    (property "Color" "Green")
    (property "License" "Apache-2.0")
    (property "MPN" "LG L29K-G2J1-24-Z")
    (property "Manufacturer" "OSRAM")
    (property "Sheetfile" "fpga-banks.kicad_sch")
    (property "Sheetname" "FPGA banks")
    (property "ki_description" "LED, Green, SMD, 0603, 20 mA, 1.7 V, 570 nm")
    (property "ki_keywords" "SMT, DIODE, SEMICONDUCTOR, LED")
    (attr smd)
    (fp_text reference "D14" (at -2.3 0.025) (layer "F.SilkS")
        (effects (font (size 0.7 0.7) (thickness 0.127)))
    )
    (fp_text value "LED_G_0603_LG_L29K-G2J1-24-Z" (at 0 1.77) (layer "F.Fab")
        (effects (font (size 1 1) (thickness 0.15)))
    )
    (fp_text user "${REFERENCE}" (at -1.4224 5.999 180) (layer "F.Fab") hide
        (effects (font (size 0.7 0.7) (thickness 0.15)) (justify left bottom))
    )
    (fp_text user "License: Apache-2.0" (at -1.4224 3.599 180) (layer "F.Fab") hide
        (effects (font (size 0.7 0.7) (thickness 0.15)) (justify left bottom))
    )
    (fp_text user "Author: Antmicro" (at -1.4224 4.799 180) (layer "F.Fab") hide
        (effects (font (size 0.7 0.7) (thickness 0.15)) (justify left bottom))
    )
    (fp_line (start -1.18 -0.319) (end -1.18 0.321)
      (stroke (width 0.15) (type solid)) (layer "F.SilkS"))
    (fp_line (start -0.094672 0.001008) (end -0.24 0.001008)
      (stroke (width 0.1) (type solid)) (layer "F.SilkS"))
    (fp_line (start -0.094672 0.001008) (end 0.105328 -0.198992)
      (stroke (width 0.1) (type solid)) (layer "F.SilkS"))
    (fp_line (start -0.094672 0.201008) (end -0.094672 -0.198992)
      (stroke (width 0.1) (type solid)) (layer "F.SilkS"))
    (fp_line (start 0.105328 0.001008) (end 0.24 0.001)
      (stroke (width 0.1) (type solid)) (layer "F.SilkS"))
    (fp_line (start 0.105328 0.201008) (end -0.094672 0.001008)
      (stroke (width 0.1) (type solid)) (layer "F.SilkS"))
    (fp_line (start 0.105328 0.201008) (end 0.105328 -0.198992)
      (stroke (width 0.1) (type solid)) (layer "F.SilkS"))
    (fp_line (start 0.22 -0.35) (end -0.22 -0.35)
      (stroke (width 0.15) (type solid)) (layer "F.SilkS"))
    (fp_line (start 0.22 0.35) (end -0.22 0.35)
      (stroke (width 0.15) (type solid)) (layer "F.SilkS"))
    (fp_rect (start 1.25 0.65) (end -1.25 -0.65)
      (stroke (width 0.05) (type solid)) (fill none) (layer "F.CrtYd"))
    (fp_line (start -0.199 -0.202) (end -0.199 0.1)
      (stroke (width 0.15) (type solid)) (layer "F.Fab"))
    (fp_line (start -0.199 0) (end -0.597 0)
      (stroke (width 0.15) (type solid)) (layer "F.Fab"))
    (fp_line (start -0.199 0.2) (end -0.199 0.1)
      (stroke (width 0.15) (type solid)) (layer "F.Fab"))
    (fp_line (start -0.101 0) (end 0.201 0.2)
      (stroke (width 0.15) (type solid)) (layer "F.Fab"))
    (fp_line (start 0.201 -0.202) (end -0.101 0)
      (stroke (width 0.15) (type solid)) (layer "F.Fab"))
    (fp_line (start 0.201 0) (end 0.201 -0.202)
      (stroke (width 0.15) (type solid)) (layer "F.Fab"))
    (fp_line (start 0.201 0.2) (end 0.201 0)
      (stroke (width 0.15) (type solid)) (layer "F.Fab"))
    (fp_line (start 0.599 0) (end 0.201 0)
      (stroke (width 0.15) (type solid)) (layer "F.Fab"))
    (fp_rect (start 0.848 0.4) (end -0.85 -0.402)
      (stroke (width 0.15) (type solid)) (fill none) (layer "F.Fab"))
    (pad "1" smd roundrect (at -0.7 0) (size 0.8 1) (layers "F.Cu" "F.Paste" "F.Mask") (roundrect_rratio 0.2)
      (net 269 "INIT_N") (pinfunction "C") (pintype "passive"))
    (pad "2" smd roundrect (at 0.7 0) (size 0.8 1) (layers "F.Cu" "F.Paste" "F.Mask") (roundrect_rratio 0.2)
      (net 348 "Net-(D14-A)") (pinfunction "A") (pintype "passive"))
  )

  (footprint "antmicro-footprints:C_0402_1005Metric" (layer "F.Cu")
    (at 137.15 154.9 -90)
    (descr "Capacitor SMD 0402")
    (tags "capacitor SMD 0402")
    (property "Author" "Antmicro")
    (property "Dielectric" "")
    (property "License" "Apache-2.0")
    (property "MPN" "CC0402MRX5R5BB106")
    (property "Manufacturer" "YAGEO")
    (property "Public" "False")
    (property "Sheetfile" "pcie-conn.kicad_sch")
    (property "Sheetname" "PCIe-connector")
    (property "Val" "10u")
    (property "Voltage" "")
    (property "ki_description" "SMD Multilayer Ceramic Capacitor, 10 µF, 6.3 V, 0402 [1005 Metric], ± 20%, X5R, CC Series")
    (property "ki_keywords" "0402, SMT, CAPACITOR, PASSIVE, MLCC, CERAMIC")
    (attr smd)
    (fp_text reference "C39" (at -2.525 0 90) (layer "F.SilkS")
        (effects (font (size 0.7 0.7) (thickness 0.127)))
    )
    (fp_text value "C_10u_0402" (at 0 1.17 90) (layer "F.Fab")
        (effects (font (size 1 1) (thickness 0.15)))
    )
    (fp_text user "Author: Antmicro" (at -0.939 3.399 -90) (layer "F.Fab") hide
        (effects (font (size 0.7 0.7) (thickness 0.15)) (justify left bottom))
    )
    (fp_text user "${REFERENCE}" (at 0 0 90) (layer "F.Fab")
        (effects (font (size 0.25 0.25) (thickness 0.04)))
    )
    (fp_text user "License: Apache-2.0" (at -0.939 5.799 -90) (layer "F.Fab") hide
        (effects (font (size 0.7 0.7) (thickness 0.15)) (justify left bottom))
    )
    (fp_rect (start -0.925 -0.47) (end 0.925 0.47)
      (stroke (width 0.05) (type default)) (fill none) (layer "F.CrtYd"))
    (fp_line (start -0.494 -0.25) (end 0.504 -0.25)
      (stroke (width 0.15) (type solid)) (layer "F.Fab"))
    (fp_line (start -0.494 0.248) (end -0.494 -0.25)
      (stroke (width 0.15) (type solid)) (layer "F.Fab"))
    (fp_line (start 0.504 -0.25) (end 0.504 0.248)
      (stroke (width 0.15) (type solid)) (layer "F.Fab"))
    (fp_line (start 0.504 0.248) (end -0.494 0.248)
      (stroke (width 0.15) (type solid)) (layer "F.Fab"))
    (pad "1" smd roundrect (at -0.48 0 270) (size 0.59 0.64) (layers "F.Cu" "F.Paste" "F.Mask") (roundrect_rratio 0.25)
      (net 1 "GND") (pintype "passive"))
    (pad "2" smd roundrect (at 0.48 0 270) (size 0.59 0.64) (layers "F.Cu" "F.Paste" "F.Mask") (roundrect_rratio 0.25)
      (net 2 "VCC3V3") (pintype "passive"))
  )

  (footprint "antmicro-footprints:TP_SMD_1mm" (layer "F.Cu")
    (at 115.270001 162.7492 180)
    (property "Author" "Antmicro")
    (property "License" "Apache-2.0")
    (property "MPN" "")
    (property "Manufacturer" "")
    (property "Sheetfile" "pcie-conn.kicad_sch")
    (property "Sheetname" "PCIe-connector")
    (property "exclude_from_bom" "")
    (property "ki_description" "Test point 1mm SMD")
    (property "ki_keywords" "TESTPOINT")
    (attr exclude_from_pos_files exclude_from_bom)
    (fp_text reference "TP1" (at 2.640001 -0.4158 180) (layer "F.SilkS")
        (effects (font (size 0.7 0.7) (thickness 0.15)) (justify left bottom))
    )
    (fp_text value "TP_1mm_SMD" (at 0 1.4 180) (layer "F.Fab")
        (effects (font (size 0.7 0.7) (thickness 0.15)) (justify left bottom))
    )
    (fp_text user "${REFERENCE}" (at -0.5 2.8 180) (layer "F.Fab") hide
        (effects (font (size 0.7 0.7) (thickness 0.15)) (justify left bottom))
    )
    (fp_text user "Author: Antmicro" (at -0.5 4 180) (layer "F.Fab") hide
        (effects (font (size 0.7 0.7) (thickness 0.15)) (justify left bottom))
    )
    (fp_text user "License: Apache-2.0" (at -0.5 5.2 180) (layer "F.Fab") hide
        (effects (font (size 0.7 0.7) (thickness 0.15)) (justify left bottom))
    )
    (fp_circle (center 0 0) (end 0.6 0)
      (stroke (width 0.05) (type default)) (fill none) (layer "F.CrtYd"))
    (pad "1" smd circle (at 0 0 180) (size 1 1) (layers "F.Cu" "F.Mask")
      (net 381 "Net-(J2-~{PEWAKE})") (pinfunction "1") (pintype "passive"))
  )

  (footprint "antmicro-footprints:C_0402_1005Metric" (layer "F.Cu")
    (at 86.1 113.1 90)
    (descr "Capacitor SMD 0402")
    (tags "capacitor SMD 0402")
    (property "Author" "Antmicro")
    (property "Dielectric" "X5R")
    (property "License" "Apache-2.0")
    (property "MPN" "GRM155R61H104KE14D")
    (property "Manufacturer" "Murata")
    (property "Public" "False")
    (property "Sheetfile" "fpga-banks.kicad_sch")
    (property "Sheetname" "FPGA banks")
    (property "Val" "100n")
    (property "Voltage" "50V")
    (property "ki_description" "SMD Multilayer Ceramic Capacitor, 0.1 µF, 50 V, 0402 [1005 Metric], ± 10%, X5R, GRM Series")
    (property "ki_keywords" "0402, SMT, CAPACITOR, PASSIVE, CERAMIC, MLCC")
    (attr smd)
    (fp_text reference "C241" (at 1.295 -1.06 90) (layer "F.SilkS")
        (effects (font (size 0.7 0.7) (thickness 0.127)))
    )
    (fp_text value "C_100n_0402" (at 0 1.17 90) (layer "F.Fab")
        (effects (font (size 1 1) (thickness 0.15)))
    )
    (fp_text user "Author: Antmicro" (at -0.939 3.399 90) (layer "F.Fab") hide
        (effects (font (size 0.7 0.7) (thickness 0.15)) (justify left bottom))
    )
    (fp_text user "License: Apache-2.0" (at -0.939 5.799 90) (layer "F.Fab") hide
        (effects (font (size 0.7 0.7) (thickness 0.15)) (justify left bottom))
    )
    (fp_text user "${REFERENCE}" (at 0 0 90) (layer "F.Fab")
        (effects (font (size 0.25 0.25) (thickness 0.04)))
    )
    (fp_rect (start -0.925 -0.47) (end 0.925 0.47)
      (stroke (width 0.05) (type default)) (fill none) (layer "F.CrtYd"))
    (fp_line (start -0.494 -0.25) (end 0.504 -0.25)
      (stroke (width 0.15) (type solid)) (layer "F.Fab"))
    (fp_line (start -0.494 0.248) (end -0.494 -0.25)
      (stroke (width 0.15) (type solid)) (layer "F.Fab"))
    (fp_line (start 0.504 -0.25) (end 0.504 0.248)
      (stroke (width 0.15) (type solid)) (layer "F.Fab"))
    (fp_line (start 0.504 0.248) (end -0.494 0.248)
      (stroke (width 0.15) (type solid)) (layer "F.Fab"))
    (pad "1" smd roundrect (at -0.48 0 90) (size 0.59 0.64) (layers "F.Cu" "F.Paste" "F.Mask") (roundrect_rratio 0.25)
      (net 1 "GND") (pintype "passive"))
    (pad "2" smd roundrect (at 0.48 0 90) (size 0.59 0.64) (layers "F.Cu" "F.Paste" "F.Mask") (roundrect_rratio 0.25)
      (net 2 "VCC3V3") (pintype "passive"))
  )

  (footprint "antmicro-footprints:R_0603_1608Metric" (layer "F.Cu")
    (at 89.5 79.005 180)
    (descr "Resistor SMD 0603")
    (tags "resistor SMD 0603")
    (property "Author" "Antmicro")
    (property "Current" "1A")
    (property "License" "Apache-2.0")
    (property "MPN" "CR0603-J/-000ELF")
    (property "Manufacturer" "Bourns")
    (property "Public" "False")
    (property "Sheetfile" "power-supply.kicad_sch")
    (property "Sheetname" "Power supply")
    (property "Tolerance" "")
    (property "Val" "0R")
    (property "ki_description" "Zero Ohm Resistor, Jumper, 0603 [1608 Metric], Thick Film, 100 mW, 1 A, Surface Mount Device, CR")
    (property "ki_keywords" "0603, SMT, RESISTOR, PASSIVE")
    (attr smd)
    (fp_text reference "R140" (at -0.26 -1.5) (layer "F.SilkS")
        (effects (font (size 0.7 0.7) (thickness 0.127)))
    )
    (fp_text value "R_0R_0603" (at 0 1.9) (layer "F.Fab")
        (effects (font (size 1 1) (thickness 0.15)))
    )
    (fp_text user "${REFERENCE}" (at -1.25 3.898 180) (layer "F.Fab") hide
        (effects (font (size 0.7 0.7) (thickness 0.15)) (justify left bottom))
    )
    (fp_text user "License: Apache-2.0" (at -1.25 5.9 180) (layer "F.Fab") hide
        (effects (font (size 0.7 0.7) (thickness 0.15)) (justify left bottom))
    )
    (fp_text user "Author: Antmicro" (at -1.25 4.9 180) (layer "F.Fab") hide
        (effects (font (size 0.7 0.7) (thickness 0.15)) (justify left bottom))
    )
    (fp_line (start -0.15 -0.4) (end 0.15 -0.4)
      (stroke (width 0.15) (type solid)) (layer "F.SilkS"))
    (fp_line (start -0.15 0.4) (end 0.15 0.4)
      (stroke (width 0.15) (type solid)) (layer "F.SilkS"))
    (fp_rect (start -1.25 -0.65) (end 1.25 0.65)
      (stroke (width 0.05) (type solid)) (fill none) (layer "F.CrtYd"))
    (fp_rect (start -0.8 -0.4) (end 0.8 0.4)
      (stroke (width 0.15) (type solid)) (fill none) (layer "F.Fab"))
    (pad "1" smd roundrect (at -0.7 0 180) (size 0.8 1) (layers "F.Cu" "F.Paste" "F.Mask") (roundrect_rratio 0.2)
      (net 211 "VCC1V2") (pintype "passive"))
    (pad "2" smd roundrect (at 0.7 0 180) (size 0.8 1) (layers "F.Cu" "F.Paste" "F.Mask") (roundrect_rratio 0.2)
      (net 354 "Net-(C108-Pad2)") (pintype "passive"))
  )

  (footprint "antmicro-footprints:TP_SMD_1mm" (layer "F.Cu")
    (at 77 92.6 180)
    (property "Author" "Antmicro")
    (property "License" "Apache-2.0")
    (property "MPN" "")
    (property "Manufacturer" "")
    (property "Sheetfile" "power-supply.kicad_sch")
    (property "Sheetname" "Power supply")
    (property "exclude_from_bom" "")
    (property "ki_description" "Test point 1mm SMD")
    (property "ki_keywords" "TESTPOINT")
    (attr exclude_from_pos_files exclude_from_bom)
    (fp_text reference "TP8" (at -0.42 -2.665 270) (layer "F.SilkS")
        (effects (font (size 0.7 0.7) (thickness 0.15)) (justify left bottom))
    )
    (fp_text value "TP_1mm_SMD" (at 0 1.4 180) (layer "F.Fab")
        (effects (font (size 0.7 0.7) (thickness 0.15)) (justify left bottom))
    )
    (fp_text user "License: Apache-2.0" (at -0.5 5.2 180) (layer "F.Fab") hide
        (effects (font (size 0.7 0.7) (thickness 0.15)) (justify left bottom))
    )
    (fp_text user "Author: Antmicro" (at -0.5 4 180) (layer "F.Fab") hide
        (effects (font (size 0.7 0.7) (thickness 0.15)) (justify left bottom))
    )
    (fp_text user "${REFERENCE}" (at -0.5 2.8 180) (layer "F.Fab") hide
        (effects (font (size 0.7 0.7) (thickness 0.15)) (justify left bottom))
    )
    (fp_circle (center 0 0) (end 0.6 0)
      (stroke (width 0.05) (type default)) (fill none) (layer "F.CrtYd"))
    (pad "1" smd circle (at 0 0 180) (size 1 1) (layers "F.Cu" "F.Mask")
      (net 355 "Net-(C118-Pad2)") (pinfunction "1") (pintype "passive"))
  )

  (footprint "antmicro-footprints:TP_SMD_1mm" (layer "F.Cu")
    (at 123.2 76.9508)
    (property "Author" "Antmicro")
    (property "License" "Apache-2.0")
    (property "MPN" "")
    (property "Manufacturer" "")
    (property "Sheetfile" "power-supply.kicad_sch")
    (property "Sheetname" "Power supply")
    (property "exclude_from_bom" "")
    (property "ki_description" "Test point 1mm SMD")
    (property "ki_keywords" "TESTPOINT")
    (attr exclude_from_pos_files exclude_from_bom)
    (fp_text reference "TP9" (at -1.02 -0.6758) (layer "F.SilkS")
        (effects (font (size 0.7 0.7) (thickness 0.15)) (justify left bottom))
    )
    (fp_text value "TP_1mm_SMD" (at 0 1.4) (layer "F.Fab")
        (effects (font (size 0.7 0.7) (thickness 0.15)) (justify left bottom))
    )
    (fp_text user "${REFERENCE}" (at -0.5 2.8) (layer "F.Fab") hide
        (effects (font (size 0.7 0.7) (thickness 0.15)) (justify left bottom))
    )
    (fp_text user "Author: Antmicro" (at -0.5 4) (layer "F.Fab") hide
        (effects (font (size 0.7 0.7) (thickness 0.15)) (justify left bottom))
    )
    (fp_text user "License: Apache-2.0" (at -0.5 5.2) (layer "F.Fab") hide
        (effects (font (size 0.7 0.7) (thickness 0.15)) (justify left bottom))
    )
    (fp_circle (center 0 0) (end 0.6 0)
      (stroke (width 0.05) (type default)) (fill none) (layer "F.CrtYd"))
    (pad "1" smd circle (at 0 0) (size 1 1) (layers "F.Cu" "F.Mask")
      (net 356 "Net-(C119-Pad2)") (pinfunction "1") (pintype "passive"))
  )

  (footprint "antmicro-footprints:TP_SMD_1mm" (layer "F.Cu")
    (at 74.64 92.28 180)
    (property "Author" "Antmicro")
    (property "License" "Apache-2.0")
    (property "MPN" "")
    (property "Manufacturer" "")
    (property "Sheetfile" "power-supply.kicad_sch")
    (property "Sheetname" "Power supply")
    (property "exclude_from_bom" "")
    (property "ki_description" "Test point 1mm SMD")
    (property "ki_keywords" "TESTPOINT")
    (attr exclude_from_pos_files exclude_from_bom)
    (fp_text reference "TP10" (at -0.4 -3.245 270) (layer "F.SilkS")
        (effects (font (size 0.7 0.7) (thickness 0.15)) (justify left bottom))
    )
    (fp_text value "TP_1mm_SMD" (at 0 1.4 180) (layer "F.Fab")
        (effects (font (size 0.7 0.7) (thickness 0.15)) (justify left bottom))
    )
    (fp_text user "${REFERENCE}" (at -0.5 2.8 180) (layer "F.Fab") hide
        (effects (font (size 0.7 0.7) (thickness 0.15)) (justify left bottom))
    )
    (fp_text user "License: Apache-2.0" (at -0.5 5.2 180) (layer "F.Fab") hide
        (effects (font (size 0.7 0.7) (thickness 0.15)) (justify left bottom))
    )
    (fp_text user "Author: Antmicro" (at -0.5 4 180) (layer "F.Fab") hide
        (effects (font (size 0.7 0.7) (thickness 0.15)) (justify left bottom))
    )
    (fp_circle (center 0 0) (end 0.6 0)
      (stroke (width 0.05) (type default)) (fill none) (layer "F.CrtYd"))
    (pad "1" smd circle (at 0 0 180) (size 1 1) (layers "F.Cu" "F.Mask")
      (net 357 "Net-(C120-Pad2)") (pinfunction "1") (pintype "passive"))
  )

  (footprint "antmicro-footprints:TP_SMD_1mm" (layer "F.Cu")
    (at 72.2 92.3 180)
    (property "Author" "Antmicro")
    (property "License" "Apache-2.0")
    (property "MPN" "")
    (property "Manufacturer" "")
    (property "Sheetfile" "power-supply.kicad_sch")
    (property "Sheetname" "Power supply")
    (property "exclude_from_bom" "")
    (property "ki_description" "Test point 1mm SMD")
    (property "ki_keywords" "TESTPOINT")
    (attr exclude_from_pos_files exclude_from_bom)
    (fp_text reference "TP11" (at 3.03 -0.645 180) (layer "F.SilkS")
        (effects (font (size 0.7 0.7) (thickness 0.15)) (justify left bottom))
    )
    (fp_text value "TP_1mm_SMD" (at 0 1.4 180) (layer "F.Fab")
        (effects (font (size 0.7 0.7) (thickness 0.15)) (justify left bottom))
    )
    (fp_text user "${REFERENCE}" (at -0.5 2.8 180) (layer "F.Fab") hide
        (effects (font (size 0.7 0.7) (thickness 0.15)) (justify left bottom))
    )
    (fp_text user "Author: Antmicro" (at -0.5 4 180) (layer "F.Fab") hide
        (effects (font (size 0.7 0.7) (thickness 0.15)) (justify left bottom))
    )
    (fp_text user "License: Apache-2.0" (at -0.5 5.2 180) (layer "F.Fab") hide
        (effects (font (size 0.7 0.7) (thickness 0.15)) (justify left bottom))
    )
    (fp_circle (center 0 0) (end 0.6 0)
      (stroke (width 0.05) (type default)) (fill none) (layer "F.CrtYd"))
    (pad "1" smd circle (at 0 0 180) (size 1 1) (layers "F.Cu" "F.Mask")
      (net 358 "Net-(C121-Pad2)") (pinfunction "1") (pintype "passive"))
  )

  (footprint "antmicro-footprints:R_0402_1005Metric" (layer "F.Cu")
    (at 76.4 61.2)
    (descr "Resistor SMD 0402")
    (tags "resistor SMD 0402")
    (property "Author" "Antmicro")
    (property "License" "Apache-2.0")
    (property "MPN" "CR0402-FX-5362GLF")
    (property "Manufacturer" "Bourns")
    (property "Public" "False")
    (property "Sheetfile" "power-supply.kicad_sch")
    (property "Sheetname" "Power supply")
    (property "Tolerance" "1%")
    (property "Val" "53k6")
    (property "ki_description" "SMD Chip Resistor")
    (property "ki_keywords" "0402, SMT, RESISTOR, PASSIVE")
    (attr smd)
    (fp_text reference "R96" (at 0.18 -1.765) (layer "F.SilkS")
        (effects (font (size 0.7 0.7) (thickness 0.127)))
    )
    (fp_text value "R_53k6_0402" (at 0 1.17) (layer "F.Fab")
        (effects (font (size 1 1) (thickness 0.15)))
    )
    (fp_text user "License: Apache-2.0" (at -0.95 5.169) (layer "F.Fab") hide
        (effects (font (size 0.7 0.7) (thickness 0.15)) (justify left bottom))
    )
    (fp_text user "${REFERENCE}" (at 0 0) (layer "F.Fab")
        (effects (font (size 0.25 0.25) (thickness 0.04)))
    )
    (fp_text user "Author: Antmicro" (at -0.95 4.169) (layer "F.Fab") hide
        (effects (font (size 0.7 0.7) (thickness 0.15)) (justify left bottom))
    )
    (fp_rect (start -0.925 -0.47) (end 0.925 0.47)
      (stroke (width 0.05) (type default)) (fill none) (layer "F.CrtYd"))
    (fp_rect (start -0.5 -0.25) (end 0.5 0.25)
      (stroke (width 0.15) (type solid)) (fill none) (layer "F.Fab"))
    (pad "1" smd roundrect (at -0.48 0) (size 0.59 0.64) (layers "F.Cu" "F.Paste" "F.Mask") (roundrect_rratio 0.25)
      (net 364 "Net-(R95-Pad2)") (pintype "passive"))
    (pad "2" smd roundrect (at 0.48 0) (size 0.59 0.64) (layers "F.Cu" "F.Paste" "F.Mask") (roundrect_rratio 0.25)
      (net 784 "Net-(U15-FB)") (pintype "passive"))
  )

  (footprint "antmicro-footprints:C_0402_1005Metric" (layer "F.Cu")
    (at 74 63.4)
    (descr "Capacitor SMD 0402")
    (tags "capacitor SMD 0402")
    (property "Author" "Antmicro")
    (property "Dielectric" "C0G")
    (property "License" "Apache-2.0")
    (property "MPN" "C0402C470J5GACTU")
    (property "Manufacturer" "KEMET")
    (property "Public" "False")
    (property "Sheetfile" "power-supply.kicad_sch")
    (property "Sheetname" "Power supply")
    (property "Val" "47p")
    (property "Voltage" "")
    (property "ki_description" "SMD Multilayer Ceramic Capacitor, 47 pF, 50 V, 0402 [1005 Metric], ± 5%, C0G / NP0, C Series KEMET")
    (property "ki_keywords" "0402, SMT, CAPACITOR, PASSIVE, CERAMIC, MLCC")
    (attr smd)
    (fp_text reference "C104" (at -0.2 2.465) (layer "F.SilkS")
        (effects (font (size 0.7 0.7) (thickness 0.127)))
    )
    (fp_text value "C_47p_0402" (at 0 1.17) (layer "F.Fab")
        (effects (font (size 1 1) (thickness 0.15)))
    )
    (fp_text user "${REFERENCE}" (at 0 0) (layer "F.Fab")
        (effects (font (size 0.25 0.25) (thickness 0.04)))
    )
    (fp_text user "Author: Antmicro" (at -0.939 3.399) (layer "F.Fab") hide
        (effects (font (size 0.7 0.7) (thickness 0.15)) (justify left bottom))
    )
    (fp_text user "License: Apache-2.0" (at -0.939 5.799) (layer "F.Fab") hide
        (effects (font (size 0.7 0.7) (thickness 0.15)) (justify left bottom))
    )
    (fp_rect (start -0.925 -0.47) (end 0.925 0.47)
      (stroke (width 0.05) (type default)) (fill none) (layer "F.CrtYd"))
    (fp_line (start -0.494 -0.25) (end 0.504 -0.25)
      (stroke (width 0.15) (type solid)) (layer "F.Fab"))
    (fp_line (start -0.494 0.248) (end -0.494 -0.25)
      (stroke (width 0.15) (type solid)) (layer "F.Fab"))
    (fp_line (start 0.504 -0.25) (end 0.504 0.248)
      (stroke (width 0.15) (type solid)) (layer "F.Fab"))
    (fp_line (start 0.504 0.248) (end -0.494 0.248)
      (stroke (width 0.15) (type solid)) (layer "F.Fab"))
    (pad "1" smd roundrect (at -0.48 0) (size 0.59 0.64) (layers "F.Cu" "F.Paste" "F.Mask") (roundrect_rratio 0.25)
      (net 1 "GND") (pintype "passive"))
    (pad "2" smd roundrect (at 0.48 0) (size 0.59 0.64) (layers "F.Cu" "F.Paste" "F.Mask") (roundrect_rratio 0.25)
      (net 781 "Net-(U15-COMP)") (pintype "passive"))
  )

  (footprint "antmicro-footprints:C_0402_1005Metric" (layer "F.Cu")
    (at 74 62.35)
    (descr "Capacitor SMD 0402")
    (tags "capacitor SMD 0402")
    (property "Author" "Antmicro")
    (property "Dielectric" "")
    (property "License" "Apache-2.0")
    (property "MPN" "CGA2B3X7S2A472K050BB")
    (property "Manufacturer" "TDK")
    (property "Public" "False")
    (property "Sheetfile" "power-supply.kicad_sch")
    (property "Sheetname" "Power supply")
    (property "Val" "4n7")
    (property "Voltage" "")
    (property "ki_description" "SMD Multilayer Ceramic Capacitor, 4700 pF, 100 V, 0402 [1005 Metric], ± 10%, X7S, CGA")
    (property "ki_keywords" "0402, SMT, CAPACITOR, PASSIVE, CERAMIC, MLCC")
    (attr smd)
    (fp_text reference "C102" (at -0.18 2.615) (layer "F.SilkS")
        (effects (font (size 0.7 0.7) (thickness 0.127)))
    )
    (fp_text value "C_4n7_0402" (at 0 1.17) (layer "F.Fab")
        (effects (font (size 1 1) (thickness 0.15)))
    )
    (fp_text user "License: Apache-2.0" (at -0.939 5.799) (layer "F.Fab") hide
        (effects (font (size 0.7 0.7) (thickness 0.15)) (justify left bottom))
    )
    (fp_text user "Author: Antmicro" (at -0.939 3.399) (layer "F.Fab") hide
        (effects (font (size 0.7 0.7) (thickness 0.15)) (justify left bottom))
    )
    (fp_text user "${REFERENCE}" (at 0 0) (layer "F.Fab")
        (effects (font (size 0.25 0.25) (thickness 0.04)))
    )
    (fp_rect (start -0.925 -0.47) (end 0.925 0.47)
      (stroke (width 0.05) (type default)) (fill none) (layer "F.CrtYd"))
    (fp_line (start -0.494 -0.25) (end 0.504 -0.25)
      (stroke (width 0.15) (type solid)) (layer "F.Fab"))
    (fp_line (start -0.494 0.248) (end -0.494 -0.25)
      (stroke (width 0.15) (type solid)) (layer "F.Fab"))
    (fp_line (start 0.504 -0.25) (end 0.504 0.248)
      (stroke (width 0.15) (type solid)) (layer "F.Fab"))
    (fp_line (start 0.504 0.248) (end -0.494 0.248)
      (stroke (width 0.15) (type solid)) (layer "F.Fab"))
    (pad "1" smd roundrect (at -0.48 0) (size 0.59 0.64) (layers "F.Cu" "F.Paste" "F.Mask") (roundrect_rratio 0.25)
      (net 1 "GND") (pintype "passive"))
    (pad "2" smd roundrect (at 0.48 0) (size 0.59 0.64) (layers "F.Cu" "F.Paste" "F.Mask") (roundrect_rratio 0.25)
      (net 233 "Net-(C102-Pad2)") (pintype "passive"))
  )

  (footprint "antmicro-footprints:R_0402_1005Metric" (layer "F.Cu")
    (at 75.55 62.9 90)
    (descr "Resistor SMD 0402")
    (tags "resistor SMD 0402")
    (property "Author" "Antmicro")
    (property "License" "Apache-2.0")
    (property "MPN" "CR0402-FX-1692GLF")
    (property "Manufacturer" "Bourns")
    (property "Public" "False")
    (property "Sheetfile" "power-supply.kicad_sch")
    (property "Sheetname" "Power supply")
    (property "Tolerance" "1%")
    (property "Val" "16k9")
    (property "ki_description" "SMD Chip Resistor, Ceramic, 16.9 kohm, ± 1%, 62.5 mW, 0402 [1005 Metric], Thick Film")
    (property "ki_keywords" "0402, SMT, RESISTOR, PASSIVE")
    (attr smd)
    (fp_text reference "R90" (at -3.445 -0.07 90) (layer "F.SilkS")
        (effects (font (size 0.7 0.7) (thickness 0.127)))
    )
    (fp_text value "R_16k9_0402" (at 0 1.17 90) (layer "F.Fab")
        (effects (font (size 1 1) (thickness 0.15)))
    )
    (fp_text user "${REFERENCE}" (at 0 0 90) (layer "F.Fab")
        (effects (font (size 0.25 0.25) (thickness 0.04)))
    )
    (fp_text user "Author: Antmicro" (at -0.95 4.169 90) (layer "F.Fab") hide
        (effects (font (size 0.7 0.7) (thickness 0.15)) (justify left bottom))
    )
    (fp_text user "License: Apache-2.0" (at -0.95 5.169 90) (layer "F.Fab") hide
        (effects (font (size 0.7 0.7) (thickness 0.15)) (justify left bottom))
    )
    (fp_rect (start -0.925 -0.47) (end 0.925 0.47)
      (stroke (width 0.05) (type default)) (fill none) (layer "F.CrtYd"))
    (fp_rect (start -0.5 -0.25) (end 0.5 0.25)
      (stroke (width 0.15) (type solid)) (fill none) (layer "F.Fab"))
    (pad "1" smd roundrect (at -0.48 0 90) (size 0.59 0.64) (layers "F.Cu" "F.Paste" "F.Mask") (roundrect_rratio 0.25)
      (net 781 "Net-(U15-COMP)") (pintype "passive"))
    (pad "2" smd roundrect (at 0.48 0 90) (size 0.59 0.64) (layers "F.Cu" "F.Paste" "F.Mask") (roundrect_rratio 0.25)
      (net 233 "Net-(C102-Pad2)") (pintype "passive"))
  )

  (footprint "antmicro-footprints:R_0402_1005Metric" (layer "F.Cu")
    (at 77.145 62.255)
    (descr "Resistor SMD 0402")
    (tags "resistor SMD 0402")
    (property "Author" "Antmicro")
    (property "License" "Apache-2.0")
    (property "MPN" "CR0402-FX-1022GLF")
    (property "Manufacturer" "Bourns")
    (property "Public" "False")
    (property "Sheetfile" "power-supply.kicad_sch")
    (property "Sheetname" "Power supply")
    (property "Tolerance" "1%")
    (property "Val" "10k2")
    (property "ki_description" "SMD Chip Resistor")
    (property "ki_keywords" "0402, SMT, RESISTOR, PASSIVE")
    (attr smd)
    (fp_text reference "R97" (at 0.165 -1.88) (layer "F.SilkS")
        (effects (font (size 0.7 0.7) (thickness 0.127)))
    )
    (fp_text value "R_10k2_0402" (at 0 1.17) (layer "F.Fab")
        (effects (font (size 1 1) (thickness 0.15)))
    )
    (fp_text user "License: Apache-2.0" (at -0.95 5.169) (layer "F.Fab") hide
        (effects (font (size 0.7 0.7) (thickness 0.15)) (justify left bottom))
    )
    (fp_text user "Author: Antmicro" (at -0.95 4.169) (layer "F.Fab") hide
        (effects (font (size 0.7 0.7) (thickness 0.15)) (justify left bottom))
    )
    (fp_text user "${REFERENCE}" (at 0 0) (layer "F.Fab")
        (effects (font (size 0.25 0.25) (thickness 0.04)))
    )
    (fp_rect (start -0.925 -0.47) (end 0.925 0.47)
      (stroke (width 0.05) (type default)) (fill none) (layer "F.CrtYd"))
    (fp_rect (start -0.5 -0.25) (end 0.5 0.25)
      (stroke (width 0.15) (type solid)) (fill none) (layer "F.Fab"))
    (pad "1" smd roundrect (at -0.48 0) (size 0.59 0.64) (layers "F.Cu" "F.Paste" "F.Mask") (roundrect_rratio 0.25)
      (net 784 "Net-(U15-FB)") (pintype "passive"))
    (pad "2" smd roundrect (at 0.48 0) (size 0.59 0.64) (layers "F.Cu" "F.Paste" "F.Mask") (roundrect_rratio 0.25)
      (net 1 "GND") (pintype "passive"))
  )

  (footprint "antmicro-footprints:C_0402_1005Metric" (layer "F.Cu")
    (at 82 66.95 -90)
    (descr "Capacitor SMD 0402")
    (tags "capacitor SMD 0402")
    (property "Author" "Antmicro")
    (property "Dielectric" "X5R")
    (property "License" "Apache-2.0")
    (property "MPN" "GRM155R61H104KE14D")
    (property "Manufacturer" "Murata")
    (property "Public" "False")
    (property "Sheetfile" "power-supply.kicad_sch")
    (property "Sheetname" "Power supply")
    (property "Val" "100n")
    (property "Voltage" "50V")
    (property "ki_description" "SMD Multilayer Ceramic Capacitor, 0.1 µF, 50 V, 0402 [1005 Metric], ± 10%, X5R, GRM Series")
    (property "ki_keywords" "0402, SMT, CAPACITOR, PASSIVE, CERAMIC, MLCC")
    (attr smd)
    (fp_text reference "C105" (at 2.145 0.21 -90) (layer "F.SilkS")
        (effects (font (size 0.7 0.7) (thickness 0.127)))
    )
    (fp_text value "C_100n_0402" (at 0 1.17 90) (layer "F.Fab")
        (effects (font (size 1 1) (thickness 0.15)))
    )
    (fp_text user "${REFERENCE}" (at 0 0 90) (layer "F.Fab")
        (effects (font (size 0.25 0.25) (thickness 0.04)))
    )
    (fp_text user "Author: Antmicro" (at -0.939 3.399 -90) (layer "F.Fab") hide
        (effects (font (size 0.7 0.7) (thickness 0.15)) (justify left bottom))
    )
    (fp_text user "License: Apache-2.0" (at -0.939 5.799 -90) (layer "F.Fab") hide
        (effects (font (size 0.7 0.7) (thickness 0.15)) (justify left bottom))
    )
    (fp_rect (start -0.925 -0.47) (end 0.925 0.47)
      (stroke (width 0.05) (type default)) (fill none) (layer "F.CrtYd"))
    (fp_line (start -0.494 -0.25) (end 0.504 -0.25)
      (stroke (width 0.15) (type solid)) (layer "F.Fab"))
    (fp_line (start -0.494 0.248) (end -0.494 -0.25)
      (stroke (width 0.15) (type solid)) (layer "F.Fab"))
    (fp_line (start 0.504 -0.25) (end 0.504 0.248)
      (stroke (width 0.15) (type solid)) (layer "F.Fab"))
    (fp_line (start 0.504 0.248) (end -0.494 0.248)
      (stroke (width 0.15) (type solid)) (layer "F.Fab"))
    (pad "1" smd roundrect (at -0.48 0 270) (size 0.59 0.64) (layers "F.Cu" "F.Paste" "F.Mask") (roundrect_rratio 0.25)
      (net 782 "Net-(U15-BOOT)") (pintype "passive"))
    (pad "2" smd roundrect (at 0.48 0 270) (size 0.59 0.64) (layers "F.Cu" "F.Paste" "F.Mask") (roundrect_rratio 0.25)
      (net 265 "Net-(D6-C)") (pintype "passive"))
  )

  (footprint "antmicro-footprints:R_0402_1005Metric" (layer "F.Cu")
    (at 80.33 62.305)
    (descr "Resistor SMD 0402")
    (tags "resistor SMD 0402")
    (property "Author" "Antmicro")
    (property "License" "Apache-2.0")
    (property "MPN" "CR0402-FX-2433GLF")
    (property "Manufacturer" "Bourns")
    (property "Public" "False")
    (property "Sheetfile" "power-supply.kicad_sch")
    (property "Sheetname" "Power supply")
    (property "Tolerance" "1%")
    (property "Val" "243k")
    (property "ki_description" "SMD Chip Resistor")
    (property "ki_keywords" "0402, SMT, RESISTOR, PASSIVE")
    (attr smd)
    (fp_text reference "R91" (at 0.03 -0.93) (layer "F.SilkS")
        (effects (font (size 0.7 0.7) (thickness 0.127)))
    )
    (fp_text value "R_243k_0402" (at 0 1.17) (layer "F.Fab")
        (effects (font (size 1 1) (thickness 0.15)))
    )
    (fp_text user "${REFERENCE}" (at 0 0) (layer "F.Fab")
        (effects (font (size 0.25 0.25) (thickness 0.04)))
    )
    (fp_text user "License: Apache-2.0" (at -0.95 5.169) (layer "F.Fab") hide
        (effects (font (size 0.7 0.7) (thickness 0.15)) (justify left bottom))
    )
    (fp_text user "Author: Antmicro" (at -0.95 4.169) (layer "F.Fab") hide
        (effects (font (size 0.7 0.7) (thickness 0.15)) (justify left bottom))
    )
    (fp_rect (start -0.925 -0.47) (end 0.925 0.47)
      (stroke (width 0.05) (type default)) (fill none) (layer "F.CrtYd"))
    (fp_rect (start -0.5 -0.25) (end 0.5 0.25)
      (stroke (width 0.15) (type solid)) (fill none) (layer "F.Fab"))
    (pad "1" smd roundrect (at -0.48 0) (size 0.59 0.64) (layers "F.Cu" "F.Paste" "F.Mask") (roundrect_rratio 0.25)
      (net 1 "GND") (pintype "passive"))
    (pad "2" smd roundrect (at 0.48 0) (size 0.59 0.64) (layers "F.Cu" "F.Paste" "F.Mask") (roundrect_rratio 0.25)
      (net 783 "Net-(U15-RT{slash}CLK)") (pintype "passive"))
  )

  (footprint "antmicro-footprints:R_0402_1005Metric" (layer "F.Cu")
    (at 72.7 77.75 180)
    (descr "Resistor SMD 0402")
    (tags "resistor SMD 0402")
    (property "Author" "Antmicro")
    (property "Current" "1A")
    (property "License" "Apache-2.0")
    (property "MPN" "ERJ2GE0R00X")
    (property "Manufacturer" "Panasonic")
    (property "Public" "False")
    (property "Sheetfile" "power-supply.kicad_sch")
    (property "Sheetname" "Power supply")
    (property "Tolerance" "")
    (property "Val" "0R")
    (property "ki_description" "SMD Chip Resistor, Jumper, 0 ohm, 100 mW, 0402 [1005 Metric], Thick Film, General Purpose")
    (property "ki_keywords" "0402, SMT, RESISTOR, PASSIVE")
    (attr smd)
    (fp_text reference "R137" (at 3.07 -0.61) (layer "F.SilkS")
        (effects (font (size 0.7 0.7) (thickness 0.127)))
    )
    (fp_text value "R_0R_0402" (at 0 1.17) (layer "F.Fab")
        (effects (font (size 1 1) (thickness 0.15)))
    )
    (fp_text user "License: Apache-2.0" (at -0.95 5.169 180) (layer "F.Fab") hide
        (effects (font (size 0.7 0.7) (thickness 0.15)) (justify left bottom))
    )
    (fp_text user "Author: Antmicro" (at -0.95 4.169 180) (layer "F.Fab") hide
        (effects (font (size 0.7 0.7) (thickness 0.15)) (justify left bottom))
    )
    (fp_text user "${REFERENCE}" (at 0 0) (layer "F.Fab")
        (effects (font (size 0.25 0.25) (thickness 0.04)))
    )
    (fp_rect (start -0.925 -0.47) (end 0.925 0.47)
      (stroke (width 0.05) (type default)) (fill none) (layer "F.CrtYd"))
    (fp_rect (start -0.5 -0.25) (end 0.5 0.25)
      (stroke (width 0.15) (type solid)) (fill none) (layer "F.Fab"))
    (pad "1" smd roundrect (at -0.48 0 180) (size 0.59 0.64) (layers "F.Cu" "F.Paste" "F.Mask") (roundrect_rratio 0.25)
      (net 419 "Net-(U12-FLAG1)") (pintype "passive"))
    (pad "2" smd roundrect (at 0.48 0 180) (size 0.59 0.64) (layers "F.Cu" "F.Paste" "F.Mask") (roundrect_rratio 0.25)
      (net 366 "/Power supply/VCCA0_EN") (pintype "passive"))
  )

  (footprint "antmicro-footprints:R_0402_1005Metric" (layer "F.Cu")
    (at 72.7 76.7 180)
    (descr "Resistor SMD 0402")
    (tags "resistor SMD 0402")
    (property "Author" "Antmicro")
    (property "Current" "1A")
    (property "License" "Apache-2.0")
    (property "MPN" "ERJ2GE0R00X")
    (property "Manufacturer" "Panasonic")
    (property "Public" "False")
    (property "Sheetfile" "power-supply.kicad_sch")
    (property "Sheetname" "Power supply")
    (property "Tolerance" "")
    (property "Val" "0R")
    (property "ki_description" "SMD Chip Resistor, Jumper, 0 ohm, 100 mW, 0402 [1005 Metric], Thick Film, General Purpose")
    (property "ki_keywords" "0402, SMT, RESISTOR, PASSIVE")
    (attr smd)
    (fp_text reference "R138" (at 3.07 -0.61) (layer "F.SilkS")
        (effects (font (size 0.7 0.7) (thickness 0.127)))
    )
    (fp_text value "R_0R_0402" (at 0 1.17) (layer "F.Fab")
        (effects (font (size 1 1) (thickness 0.15)))
    )
    (fp_text user "License: Apache-2.0" (at -0.95 5.169 180) (layer "F.Fab") hide
        (effects (font (size 0.7 0.7) (thickness 0.15)) (justify left bottom))
    )
    (fp_text user "${REFERENCE}" (at 0 0) (layer "F.Fab")
        (effects (font (size 0.25 0.25) (thickness 0.04)))
    )
    (fp_text user "Author: Antmicro" (at -0.95 4.169 180) (layer "F.Fab") hide
        (effects (font (size 0.7 0.7) (thickness 0.15)) (justify left bottom))
    )
    (fp_rect (start -0.925 -0.47) (end 0.925 0.47)
      (stroke (width 0.05) (type default)) (fill none) (layer "F.CrtYd"))
    (fp_rect (start -0.5 -0.25) (end 0.5 0.25)
      (stroke (width 0.15) (type solid)) (fill none) (layer "F.Fab"))
    (pad "1" smd roundrect (at -0.48 0 180) (size 0.59 0.64) (layers "F.Cu" "F.Paste" "F.Mask") (roundrect_rratio 0.25)
      (net 420 "Net-(U12-FLAG2)") (pintype "passive"))
    (pad "2" smd roundrect (at 0.48 0 180) (size 0.59 0.64) (layers "F.Cu" "F.Paste" "F.Mask") (roundrect_rratio 0.25)
      (net 231 "/Power supply/VCCIO_EN") (pintype "passive"))
  )

  (footprint "antmicro-footprints:R_0402_1005Metric" (layer "F.Cu")
    (at 72.7 75.65 180)
    (descr "Resistor SMD 0402")
    (tags "resistor SMD 0402")
    (property "Author" "Antmicro")
    (property "Current" "1A")
    (property "License" "Apache-2.0")
    (property "MPN" "ERJ2GE0R00X")
    (property "Manufacturer" "Panasonic")
    (property "Public" "False")
    (property "Sheetfile" "power-supply.kicad_sch")
    (property "Sheetname" "Power supply")
    (property "Tolerance" "")
    (property "Val" "0R")
    (property "ki_description" "SMD Chip Resistor, Jumper, 0 ohm, 100 mW, 0402 [1005 Metric], Thick Film, General Purpose")
    (property "ki_keywords" "0402, SMT, RESISTOR, PASSIVE")
    (attr smd)
    (fp_text reference "R139" (at 3.07 -0.61) (layer "F.SilkS")
        (effects (font (size 0.7 0.7) (thickness 0.127)))
    )
    (fp_text value "R_0R_0402" (at 0 1.17) (layer "F.Fab")
        (effects (font (size 1 1) (thickness 0.15)))
    )
    (fp_text user "${REFERENCE}" (at 0 0) (layer "F.Fab")
        (effects (font (size 0.25 0.25) (thickness 0.04)))
    )
    (fp_text user "License: Apache-2.0" (at -0.95 5.169 180) (layer "F.Fab") hide
        (effects (font (size 0.7 0.7) (thickness 0.15)) (justify left bottom))
    )
    (fp_text user "Author: Antmicro" (at -0.95 4.169 180) (layer "F.Fab") hide
        (effects (font (size 0.7 0.7) (thickness 0.15)) (justify left bottom))
    )
    (fp_rect (start -0.925 -0.47) (end 0.925 0.47)
      (stroke (width 0.05) (type default)) (fill none) (layer "F.CrtYd"))
    (fp_rect (start -0.5 -0.25) (end 0.5 0.25)
      (stroke (width 0.15) (type solid)) (fill none) (layer "F.Fab"))
    (pad "1" smd roundrect (at -0.48 0 180) (size 0.59 0.64) (layers "F.Cu" "F.Paste" "F.Mask") (roundrect_rratio 0.25)
      (net 422 "Net-(U12-FLAG3)") (pintype "passive"))
    (pad "2" smd roundrect (at 0.48 0 180) (size 0.59 0.64) (layers "F.Cu" "F.Paste" "F.Mask") (roundrect_rratio 0.25)
      (net 230 "/Power supply/VCCAUX_EN") (pintype "passive"))
  )

  (footprint "antmicro-footprints:C_0402_1005Metric" (layer "F.Cu")
    (at 76.24 73.64 -90)
    (descr "Capacitor SMD 0402")
    (tags "capacitor SMD 0402")
    (property "Author" "Antmicro")
    (property "Dielectric" "X7R")
    (property "License" "Apache-2.0")
    (property "MPN" "GRM155R71H103KA88D")
    (property "Manufacturer" "Murata")
    (property "Public" "False")
    (property "Sheetfile" "power-supply.kicad_sch")
    (property "Sheetname" "Power supply")
    (property "Val" "10n")
    (property "Voltage" "50V")
    (property "ki_description" "SMD Multilayer Ceramic Capacitor, 10000 pF, 50 V, 0402 [1005 Metric], ± 10%, X7R, GRM Series")
    (property "ki_keywords" "0402, SMT, CAPACITOR, PASSIVE")
    (attr smd)
    (fp_text reference "C95" (at -0.095 1.54 90) (layer "F.SilkS")
        (effects (font (size 0.7 0.7) (thickness 0.127)))
    )
    (fp_text value "C_10n_0402" (at 0 1.17 90) (layer "F.Fab")
        (effects (font (size 1 1) (thickness 0.15)))
    )
    (fp_text user "Author: Antmicro" (at -0.939 3.399 -90) (layer "F.Fab") hide
        (effects (font (size 0.7 0.7) (thickness 0.15)) (justify left bottom))
    )
    (fp_text user "${REFERENCE}" (at 0 0 90) (layer "F.Fab")
        (effects (font (size 0.25 0.25) (thickness 0.04)))
    )
    (fp_text user "License: Apache-2.0" (at -0.939 5.799 -90) (layer "F.Fab") hide
        (effects (font (size 0.7 0.7) (thickness 0.15)) (justify left bottom))
    )
    (fp_rect (start -0.925 -0.47) (end 0.925 0.47)
      (stroke (width 0.05) (type default)) (fill none) (layer "F.CrtYd"))
    (fp_line (start -0.494 -0.25) (end 0.504 -0.25)
      (stroke (width 0.15) (type solid)) (layer "F.Fab"))
    (fp_line (start -0.494 0.248) (end -0.494 -0.25)
      (stroke (width 0.15) (type solid)) (layer "F.Fab"))
    (fp_line (start 0.504 -0.25) (end 0.504 0.248)
      (stroke (width 0.15) (type solid)) (layer "F.Fab"))
    (fp_line (start 0.504 0.248) (end -0.494 0.248)
      (stroke (width 0.15) (type solid)) (layer "F.Fab"))
    (pad "1" smd roundrect (at -0.48 0 270) (size 0.59 0.64) (layers "F.Cu" "F.Paste" "F.Mask") (roundrect_rratio 0.25)
      (net 1 "GND") (pintype "passive"))
    (pad "2" smd roundrect (at 0.48 0 270) (size 0.59 0.64) (layers "F.Cu" "F.Paste" "F.Mask") (roundrect_rratio 0.25)
      (net 229 "Net-(U12-TADJ)") (pintype "passive"))
  )

  (footprint "antmicro-footprints:R_0402_1005Metric" (layer "F.Cu")
    (at 79.24 73.64 -90)
    (descr "Resistor SMD 0402")
    (tags "resistor SMD 0402")
    (property "Author" "Antmicro")
    (property "License" "Apache-2.0")
    (property "MPN" "CR0402-FX-1003GLF")
    (property "Manufacturer" "Bourns")
    (property "Public" "False")
    (property "Sheetfile" "power-supply.kicad_sch")
    (property "Sheetname" "Power supply")
    (property "Tolerance" "1%")
    (property "Val" "100k")
    (property "ki_description" "SMD Chip Resistor, 100 kohm, ± 1%, 62.5 mW, 0402 [1005 Metric], Thick Film, General Purpose")
    (property "ki_keywords" "0402, SMT, RESISTOR, PASSIVE")
    (attr smd)
    (fp_text reference "R85" (at -2.45 4.8 -90) (layer "F.SilkS")
        (effects (font (size 0.7 0.7) (thickness 0.127)))
    )
    (fp_text value "R_100k_0402" (at 0 1.17 -90) (layer "F.Fab")
        (effects (font (size 1 1) (thickness 0.15)))
    )
    (fp_text user "Author: Antmicro" (at -0.95 4.169 -90) (layer "F.Fab") hide
        (effects (font (size 0.7 0.7) (thickness 0.15)) (justify left bottom))
    )
    (fp_text user "License: Apache-2.0" (at -0.95 5.169 -90) (layer "F.Fab") hide
        (effects (font (size 0.7 0.7) (thickness 0.15)) (justify left bottom))
    )
    (fp_text user "${REFERENCE}" (at 0 0 -90) (layer "F.Fab")
        (effects (font (size 0.25 0.25) (thickness 0.04)))
    )
    (fp_rect (start -0.925 -0.47) (end 0.925 0.47)
      (stroke (width 0.05) (type default)) (fill none) (layer "F.CrtYd"))
    (fp_rect (start -0.5 -0.25) (end 0.5 0.25)
      (stroke (width 0.15) (type solid)) (fill none) (layer "F.Fab"))
    (pad "1" smd roundrect (at -0.48 0 270) (size 0.59 0.64) (layers "F.Cu" "F.Paste" "F.Mask") (roundrect_rratio 0.25)
      (net 11 "VCC5V0") (pintype "passive"))
    (pad "2" smd roundrect (at 0.48 0 270) (size 0.59 0.64) (layers "F.Cu" "F.Paste" "F.Mask") (roundrect_rratio 0.25)
      (net 419 "Net-(U12-FLAG1)") (pintype "passive"))
  )

  (footprint "antmicro-footprints:PowerDI5" (layer "F.Cu")
    (at 69.25 61 180)
    (property "Author" "Antmicro")
    (property "License" "Apache-2.0")
    (property "MPN" "PDS760-13")
    (property "Manufacturer" "Diodes Incorporated")
    (property "Sheetfile" "power-supply.kicad_sch")
    (property "Sheetname" "Power supply")
    (property "ki_description" "Schottky Rectifier, POWERDI®, 60 V, 7 A, Single, PowerDI 5, 2 Pins, 620 mV")
    (property "ki_keywords" "SMT, RECTIFIER, SEMICONDUCTOR, DIODE, SCHOTTKY")
    (attr smd)
    (fp_text reference "D6" (at 0.51 -2.975 180) (layer "F.SilkS")
        (effects (font (size 0.7 0.7) (thickness 0.15)) (justify left bottom))
    )
    (fp_text value "PDS760" (at 0 3.4) (layer "F.Fab")
        (effects (font (size 0.7 0.7) (thickness 0.15)) (justify left bottom))
    )
    (fp_text user "Author: Antmicro" (at -3.32 5.701 180) (layer "F.Fab") hide
        (effects (font (size 0.7 0.7) (thickness 0.15)) (justify left bottom))
    )
    (fp_text user "License: Apache-2.0" (at -3.32 6.901 180) (layer "F.Fab") hide
        (effects (font (size 0.7 0.7) (thickness 0.15)) (justify left bottom))
    )
    (fp_text user "${REFERENCE}" (at -3.32 4.5 180) (layer "F.Fab") hide
        (effects (font (size 0.7 0.7) (thickness 0.15)) (justify left bottom))
    )
    (fp_line (start -2.7 -2) (end 2.7 -2)
      (stroke (width 0.12) (type solid)) (layer "F.SilkS"))
    (fp_line (start -2.7 -1.8) (end -2.7 -2)
      (stroke (width 0.12) (type solid)) (layer "F.SilkS"))
    (fp_line (start -2.7 2.023) (end -2.7 1.823)
      (stroke (width 0.12) (type solid)) (layer "F.SilkS"))
    (fp_line (start 2.7 -2) (end 2.7 -1.8)
      (stroke (width 0.12) (type solid)) (layer "F.SilkS"))
    (fp_line (start 2.7 1.823) (end 2.7 2.023)
      (stroke (width 0.12) (type solid)) (layer "F.SilkS"))
    (fp_line (start 2.7 2.023) (end -2.7 2.023)
      (stroke (width 0.12) (type solid)) (layer "F.SilkS"))
    (fp_rect (start -3.702 -2.3) (end 3.7 2.3)
      (stroke (width 0.05) (type solid)) (fill none) (layer "F.CrtYd"))
    (pad "1" smd roundrect (at 1.1 0 90) (size 3.36 4.86) (layers "F.Cu" "F.Paste" "F.Mask") (roundrect_rratio 0.05)
      (net 265 "Net-(D6-C)") (pinfunction "C") (pintype "passive"))
    (pad "2" smd roundrect (at -2.862 -0.94 270) (size 1.39 1.4) (layers "F.Cu" "F.Paste" "F.Mask") (roundrect_rratio 0.25)
      (net 1 "GND") (pinfunction "A") (pintype "passive"))
    (pad "2" smd roundrect (at -2.862 0.941 90) (size 1.39 1.4) (layers "F.Cu" "F.Paste" "F.Mask") (roundrect_rratio 0.25)
      (net 1 "GND") (pinfunction "A") (pintype "passive"))
  )

  (footprint "antmicro-footprints:R_0402_1005Metric" (layer "F.Cu")
    (at 72.65 88.7)
    (descr "Resistor SMD 0402")
    (tags "resistor SMD 0402")
    (property "Author" "Antmicro")
    (property "License" "Apache-2.0")
    (property "MPN" "CR0402-FX-6652GLF")
    (property "Manufacturer" "Bourns")
    (property "Public" "False")
    (property "Sheetfile" "power-supply.kicad_sch")
    (property "Sheetname" "Power supply")
    (property "Tolerance" "1%")
    (property "Val" "66k5")
    (property "ki_description" "SMD Chip Resistor")
    (property "ki_keywords" "0402, SMT, RESISTOR, PASSIVE")
    (attr smd)
    (fp_text reference "R120" (at -0.31 1.845) (layer "F.SilkS")
        (effects (font (size 0.7 0.7) (thickness 0.127)))
    )
    (fp_text value "R_66k5_0402" (at 0 1.17) (layer "F.Fab")
        (effects (font (size 1 1) (thickness 0.15)))
    )
    (fp_text user "License: Apache-2.0" (at -0.95 5.169) (layer "F.Fab") hide
        (effects (font (size 0.7 0.7) (thickness 0.15)) (justify left bottom))
    )
    (fp_text user "${REFERENCE}" (at 0 0) (layer "F.Fab")
        (effects (font (size 0.25 0.25) (thickness 0.04)))
    )
    (fp_text user "Author: Antmicro" (at -0.95 4.169) (layer "F.Fab") hide
        (effects (font (size 0.7 0.7) (thickness 0.15)) (justify left bottom))
    )
    (fp_rect (start -0.925 -0.47) (end 0.925 0.47)
      (stroke (width 0.05) (type default)) (fill none) (layer "F.CrtYd"))
    (fp_rect (start -0.5 -0.25) (end 0.5 0.25)
      (stroke (width 0.15) (type solid)) (fill none) (layer "F.Fab"))
    (pad "1" smd roundrect (at -0.48 0) (size 0.59 0.64) (layers "F.Cu" "F.Paste" "F.Mask") (roundrect_rratio 0.25)
      (net 300 "Net-(U20-FB)") (pintype "passive"))
    (pad "2" smd roundrect (at 0.48 0) (size 0.59 0.64) (layers "F.Cu" "F.Paste" "F.Mask") (roundrect_rratio 0.25)
      (net 358 "Net-(C121-Pad2)") (pintype "passive"))
  )

  (footprint "antmicro-footprints:R_0603_1608Metric" (layer "F.Cu")
    (at 121.489056 84.693104 90)
    (descr "Resistor SMD 0603")
    (tags "resistor SMD 0603")
    (property "Author" "Antmicro")
    (property "Current" "1A")
    (property "License" "Apache-2.0")
    (property "MPN" "CR0603-J/-000ELF")
    (property "Manufacturer" "Bourns")
    (property "Public" "False")
    (property "Sheetfile" "power-supply.kicad_sch")
    (property "Sheetname" "Power supply")
    (property "Tolerance" "")
    (property "Val" "0R")
    (property "ki_description" "Zero Ohm Resistor, Jumper, 0603 [1608 Metric], Thick Film, 100 mW, 1 A, Surface Mount Device, CR")
    (property "ki_keywords" "0603, SMT, RESISTOR, PASSIVE")
    (attr smd)
    (fp_text reference "R142" (at -0.246896 1.080944 90) (layer "F.SilkS")
        (effects (font (size 0.7 0.7) (thickness 0.127)))
    )
    (fp_text value "R_0R_0603" (at 0 1.9 90) (layer "F.Fab")
        (effects (font (size 1 1) (thickness 0.15)))
    )
    (fp_text user "${REFERENCE}" (at -1.25 3.898 90) (layer "F.Fab") hide
        (effects (font (size 0.7 0.7) (thickness 0.15)) (justify left bottom))
    )
    (fp_text user "License: Apache-2.0" (at -1.25 5.9 90) (layer "F.Fab") hide
        (effects (font (size 0.7 0.7) (thickness 0.15)) (justify left bottom))
    )
    (fp_text user "Author: Antmicro" (at -1.25 4.9 90) (layer "F.Fab") hide
        (effects (font (size 0.7 0.7) (thickness 0.15)) (justify left bottom))
    )
    (fp_line (start -0.15 -0.4) (end 0.15 -0.4)
      (stroke (width 0.15) (type solid)) (layer "F.SilkS"))
    (fp_line (start -0.15 0.4) (end 0.15 0.4)
      (stroke (width 0.15) (type solid)) (layer "F.SilkS"))
    (fp_rect (start -1.25 -0.65) (end 1.25 0.65)
      (stroke (width 0.05) (type solid)) (fill none) (layer "F.CrtYd"))
    (fp_rect (start -0.8 -0.4) (end 0.8 0.4)
      (stroke (width 0.15) (type solid)) (fill none) (layer "F.Fab"))
    (pad "1" smd roundrect (at -0.7 0 90) (size 0.8 1) (layers "F.Cu" "F.Paste" "F.Mask") (roundrect_rratio 0.2)
      (net 218 "VCC1V8") (pintype "passive"))
    (pad "2" smd roundrect (at 0.7 0 90) (size 0.8 1) (layers "F.Cu" "F.Paste" "F.Mask") (roundrect_rratio 0.2)
      (net 356 "Net-(C119-Pad2)") (pintype "passive"))
  )

  (footprint "antmicro-footprints:L_Vishay-IHLP-1212AE" (layer "F.Cu")
    (at 79.25 81.55)
    (property "Author" "Antmicro")
    (property "IMax" "6.7 A")
    (property "ISat" "6.7 A")
    (property "License" "Apache-2.0")
    (property "MPN" "IHLP1212AEERR47M11")
    (property "Manufacturer" "Vishay")
    (property "Public" "False")
    (property "Sheetfile" "power-supply.kicad_sch")
    (property "Sheetname" "Power supply")
    (property "Size" "3.0x3.0")
    (property "Val" "470n/6.7A")
    (property "ki_description" "Power Inductor (SMT), 470 nH, 6.7 A, Shielded, 6.7 A")
    (property "ki_keywords" "SMT, INDUCTOR, PASSIVE")
    (attr smd)
    (fp_text reference "L5" (at -2.49 -1.295) (layer "F.SilkS")
        (effects (font (size 0.7 0.7) (thickness 0.127)))
    )
    (fp_text value "IHLP1212AEERR47M11" (at 0 0 270) (layer "F.SilkS") hide
        (effects (font (size 1.524 1.524) (thickness 0.05)))
    )
    (fp_text user "${REFERENCE}" (at -2.35 5.4) (layer "F.Fab") hide
        (effects (font (size 0.7 0.7) (thickness 0.15)) (justify left bottom))
    )
    (fp_text user "License: Apache-2.0" (at -2.35 7.8) (layer "F.Fab") hide
        (effects (font (size 0.7 0.7) (thickness 0.15)) (justify left bottom))
    )
    (fp_text user "Author: Antmicro" (at -2.35 6.6) (layer "F.Fab") hide
        (effects (font (size 0.7 0.7) (thickness 0.15)) (justify left bottom))
    )
    (fp_line (start -1.647 -1.6) (end 1.653 -1.6)
      (stroke (width 0.15) (type solid)) (layer "F.SilkS"))
    (fp_line (start -1.647 -0.9) (end -1.647 -1.6)
      (stroke (width 0.15) (type solid)) (layer "F.SilkS"))
    (fp_line (start -1.647 1.6) (end -1.647 0.9)
      (stroke (width 0.15) (type solid)) (layer "F.SilkS"))
    (fp_line (start 1.653 -1.6) (end 1.653 -0.9)
      (stroke (width 0.15) (type solid)) (layer "F.SilkS"))
    (fp_line (start 1.653 0.9) (end 1.653 1.601)
      (stroke (width 0.15) (type solid)) (layer "F.SilkS"))
    (fp_line (start 1.653 1.601) (end -1.647 1.6)
      (stroke (width 0.15) (type solid)) (layer "F.SilkS"))
    (fp_rect (start -2.35 -1.85) (end 2.35 1.85)
      (stroke (width 0.05) (type solid)) (fill none) (layer "F.CrtYd"))
    (fp_rect (start -1.803 -1.601) (end 1.803 1.601)
      (stroke (width 0.15) (type solid)) (fill none) (layer "F.Fab"))
    (pad "1" smd roundrect (at -1.35 0) (size 1.5 1.2) (layers "F.Cu" "F.Paste" "F.Mask") (roundrect_rratio 0.1)
      (net 391 "Net-(U19-SW)") (pintype "passive"))
    (pad "2" smd roundrect (at 1.35 0) (size 1.5 1.2) (layers "F.Cu" "F.Paste" "F.Mask") (roundrect_rratio 0.1)
      (net 357 "Net-(C120-Pad2)") (pintype "passive"))
  )

  (footprint "antmicro-footprints:L_Vishay-IHLP-1212AE" (layer "F.Cu")
    (at 73.2 81.55)
    (property "Author" "Antmicro")
    (property "IMax" "6.7 A")
    (property "ISat" "6.7 A")
    (property "License" "Apache-2.0")
    (property "MPN" "IHLP1212AEERR47M11")
    (property "Manufacturer" "Vishay")
    (property "Public" "False")
    (property "Sheetfile" "power-supply.kicad_sch")
    (property "Sheetname" "Power supply")
    (property "Size" "3.0x3.0")
    (property "Val" "470n/6.7A")
    (property "ki_description" "Power Inductor (SMT), 470 nH, 6.7 A, Shielded, 6.7 A")
    (property "ki_keywords" "SMT, INDUCTOR, PASSIVE")
    (attr smd)
    (fp_text reference "L6" (at -2.75 0 180) (layer "F.SilkS")
        (effects (font (size 0.7 0.7) (thickness 0.127)))
    )
    (fp_text value "IHLP1212AEERR47M11" (at 0 0 270) (layer "F.SilkS") hide
        (effects (font (size 1.524 1.524) (thickness 0.05)))
    )
    (fp_text user "${REFERENCE}" (at -2.35 5.4) (layer "F.Fab") hide
        (effects (font (size 0.7 0.7) (thickness 0.15)) (justify left bottom))
    )
    (fp_text user "Author: Antmicro" (at -2.35 6.6) (layer "F.Fab") hide
        (effects (font (size 0.7 0.7) (thickness 0.15)) (justify left bottom))
    )
    (fp_text user "License: Apache-2.0" (at -2.35 7.8) (layer "F.Fab") hide
        (effects (font (size 0.7 0.7) (thickness 0.15)) (justify left bottom))
    )
    (fp_line (start -1.647 -1.6) (end 1.653 -1.6)
      (stroke (width 0.15) (type solid)) (layer "F.SilkS"))
    (fp_line (start -1.647 -0.9) (end -1.647 -1.6)
      (stroke (width 0.15) (type solid)) (layer "F.SilkS"))
    (fp_line (start -1.647 1.6) (end -1.647 0.9)
      (stroke (width 0.15) (type solid)) (layer "F.SilkS"))
    (fp_line (start 1.653 -1.6) (end 1.653 -0.9)
      (stroke (width 0.15) (type solid)) (layer "F.SilkS"))
    (fp_line (start 1.653 0.9) (end 1.653 1.601)
      (stroke (width 0.15) (type solid)) (layer "F.SilkS"))
    (fp_line (start 1.653 1.601) (end -1.647 1.6)
      (stroke (width 0.15) (type solid)) (layer "F.SilkS"))
    (fp_rect (start -2.35 -1.85) (end 2.35 1.85)
      (stroke (width 0.05) (type solid)) (fill none) (layer "F.CrtYd"))
    (fp_rect (start -1.803 -1.601) (end 1.803 1.601)
      (stroke (width 0.15) (type solid)) (fill none) (layer "F.Fab"))
    (pad "1" smd roundrect (at -1.35 0) (size 1.5 1.2) (layers "F.Cu" "F.Paste" "F.Mask") (roundrect_rratio 0.1)
      (net 392 "Net-(U20-SW)") (pintype "passive"))
    (pad "2" smd roundrect (at 1.35 0) (size 1.5 1.2) (layers "F.Cu" "F.Paste" "F.Mask") (roundrect_rratio 0.1)
      (net 358 "Net-(C121-Pad2)") (pintype "passive"))
  )

  (footprint "antmicro-footprints:QFN-8_2x1.5mm" (layer "F.Cu")
    (at 117.989056 83.643104 90)
    (property "Author" "Antmicro")
    (property "License" "Apache-2.0")
    (property "MPN" "TPS62823DLCT")
    (property "Manufacturer" "Texas Instruments")
    (property "Sheetfile" "power-supply.kicad_sch")
    (property "Sheetname" "Power supply")
    (property "ki_description" "DC/DC converter")
    (property "ki_keywords" "SMT, PMIC, IC, SWITCHING, VOLTAGE, REGULATOR, DC-DC")
    (attr smd)
    (fp_text reference "U18" (at -0.05 -2.48 90) (layer "F.SilkS")
        (effects (font (size 0.7 0.7) (thickness 0.127)))
    )
    (fp_text value "TPS62823DLCT" (at 0 2.075 90) (layer "F.Fab")
        (effects (font (size 1 1) (thickness 0.15)))
    )
    (fp_text user "License: Apache-2.0" (at -1.651 6.475 90) (layer "F.Fab") hide
        (effects (font (size 0.7 0.7) (thickness 0.15)) (justify left bottom))
    )
    (fp_text user "Author: Antmicro" (at -1.651 5.275 90) (layer "F.Fab") hide
        (effects (font (size 0.7 0.7) (thickness 0.15)) (justify left bottom))
    )
    (fp_text user "${REFERENCE}" (at 0 0 90) (layer "F.Fab")
        (effects (font (size 0.5 0.5) (thickness 0.075)))
    )
    (fp_line (start -0.9 1.05) (end 0.9 1.05)
      (stroke (width 0.15) (type solid)) (layer "F.SilkS"))
    (fp_line (start -0.25 -1.05) (end 0.9 -1.05)
      (stroke (width 0.15) (type solid)) (layer "F.SilkS"))
    (fp_circle (center -0.9 -1.05) (end -0.849 -1.05)
      (stroke (width 0.15) (type solid)) (fill solid) (layer "F.SilkS"))
    (fp_rect (start -1.1 -1.25) (end 1.1 1.25)
      (stroke (width 0.05) (type solid)) (fill none) (layer "F.CrtYd"))
    (fp_line (start -1 -0.5) (end -0.5 -1)
      (stroke (width 0.15) (type solid)) (layer "F.Fab"))
    (fp_line (start -1 0.998) (end -1 -0.5)
      (stroke (width 0.15) (type solid)) (layer "F.Fab"))
    (fp_line (start -0.5 -1) (end 0.998 -1)
      (stroke (width 0.15) (type solid)) (layer "F.Fab"))
    (fp_line (start 0.998 -1) (end 0.998 0.998)
      (stroke (width 0.15) (type solid)) (layer "F.Fab"))
    (fp_line (start 0.998 0.998) (end -1 0.998)
      (stroke (width 0.15) (type solid)) (layer "F.Fab"))
    (pad "1" smd rect (at -0.677 -0.75 90) (size 0.55 0.25) (layers "F.Cu" "F.Paste" "F.Mask")
      (net 231 "/Power supply/VCCIO_EN") (pinfunction "EN") (pintype "input"))
    (pad "2" smd rect (at -0.677 -0.25 90) (size 0.55 0.25) (layers "F.Cu" "F.Paste" "F.Mask")
      (net 292 "Net-(U18-FB)") (pinfunction "FB") (pintype "bidirectional"))
    (pad "3" smd rect (at -0.677 0.248 90) (size 0.55 0.25) (layers "F.Cu" "F.Paste" "F.Mask")
      (net 1 "GND") (pinfunction "AGND") (pintype "power_in"))
    (pad "4" smd rect (at -0.677 0.748 90) (size 0.55 0.25) (layers "F.Cu" "F.Paste" "F.Mask")
      (net 544 "unconnected-(U18-NC-Pad4)") (pinfunction "NC") (pintype "no_connect"))
    (pad "5" smd rect (at 0.675 0.748 90) (size 0.55 0.25) (layers "F.Cu" "F.Paste" "F.Mask")
      (net 1 "GND") (pinfunction "PGND") (pintype "power_in"))
    (pad "6" smd rect (at 0.675 0.248 90) (size 0.55 0.25) (layers "F.Cu" "F.Paste" "F.Mask")
      (net 390 "Net-(U18-SW)") (pinfunction "SW") (pintype "bidirectional"))
    (pad "7" smd rect (at 0.675 -0.25 90) (size 0.55 0.25) (layers "F.Cu" "F.Paste" "F.Mask")
      (net 11 "VCC5V0") (pinfunction "VIN") (pintype "power_in"))
    (pad "8" smd rect (at 0.675 -0.75 90) (size 0.55 0.25) (layers "F.Cu" "F.Paste" "F.Mask")
      (net 223 "/Power supply/1V8_PG") (pinfunction "PG") (pintype "output"))
  )

  (footprint "antmicro-footprints:QFN-8_2x1.5mm" (layer "F.Cu")
    (at 77.15 86.15 90)
    (property "Author" "Antmicro")
    (property "License" "Apache-2.0")
    (property "MPN" "TPS62823DLCT")
    (property "Manufacturer" "Texas Instruments")
    (property "Sheetfile" "power-supply.kicad_sch")
    (property "Sheetname" "Power supply")
    (property "ki_description" "DC/DC converter")
    (property "ki_keywords" "SMT, PMIC, IC, SWITCHING, VOLTAGE, REGULATOR, DC-DC")
    (attr smd)
    (fp_text reference "U19" (at -1.59 -0.02 180) (layer "F.SilkS")
        (effects (font (size 0.7 0.7) (thickness 0.127)))
    )
    (fp_text value "TPS62823DLCT" (at 0 2.075 90) (layer "F.Fab")
        (effects (font (size 1 1) (thickness 0.15)))
    )
    (fp_text user "License: Apache-2.0" (at -1.651 6.475 90) (layer "F.Fab") hide
        (effects (font (size 0.7 0.7) (thickness 0.15)) (justify left bottom))
    )
    (fp_text user "${REFERENCE}" (at 0 0 90) (layer "F.Fab")
        (effects (font (size 0.5 0.5) (thickness 0.075)))
    )
    (fp_text user "Author: Antmicro" (at -1.651 5.275 90) (layer "F.Fab") hide
        (effects (font (size 0.7 0.7) (thickness 0.15)) (justify left bottom))
    )
    (fp_line (start -0.9 1.05) (end 0.9 1.05)
      (stroke (width 0.15) (type solid)) (layer "F.SilkS"))
    (fp_line (start -0.25 -1.05) (end 0.9 -1.05)
      (stroke (width 0.15) (type solid)) (layer "F.SilkS"))
    (fp_circle (center -0.9 -1.05) (end -0.849 -1.05)
      (stroke (width 0.15) (type solid)) (fill solid) (layer "F.SilkS"))
    (fp_rect (start -1.1 -1.25) (end 1.1 1.25)
      (stroke (width 0.05) (type solid)) (fill none) (layer "F.CrtYd"))
    (fp_line (start -1 -0.5) (end -0.5 -1)
      (stroke (width 0.15) (type solid)) (layer "F.Fab"))
    (fp_line (start -1 0.998) (end -1 -0.5)
      (stroke (width 0.15) (type solid)) (layer "F.Fab"))
    (fp_line (start -0.5 -1) (end 0.998 -1)
      (stroke (width 0.15) (type solid)) (layer "F.Fab"))
    (fp_line (start 0.998 -1) (end 0.998 0.998)
      (stroke (width 0.15) (type solid)) (layer "F.Fab"))
    (fp_line (start 0.998 0.998) (end -1 0.998)
      (stroke (width 0.15) (type solid)) (layer "F.Fab"))
    (pad "1" smd rect (at -0.677 -0.75 90) (size 0.55 0.25) (layers "F.Cu" "F.Paste" "F.Mask")
      (net 231 "/Power supply/VCCIO_EN") (pinfunction "EN") (pintype "input"))
    (pad "2" smd rect (at -0.677 -0.25 90) (size 0.55 0.25) (layers "F.Cu" "F.Paste" "F.Mask")
      (net 299 "Net-(U19-FB)") (pinfunction "FB") (pintype "bidirectional"))
    (pad "3" smd rect (at -0.677 0.248 90) (size 0.55 0.25) (layers "F.Cu" "F.Paste" "F.Mask")
      (net 1 "GND") (pinfunction "AGND") (pintype "power_in"))
    (pad "4" smd rect (at -0.677 0.748 90) (size 0.55 0.25) (layers "F.Cu" "F.Paste" "F.Mask")
      (net 545 "unconnected-(U19-NC-Pad4)") (pinfunction "NC") (pintype "no_connect"))
    (pad "5" smd rect (at 0.675 0.748 90) (size 0.55 0.25) (layers "F.Cu" "F.Paste" "F.Mask")
      (net 1 "GND") (pinfunction "PGND") (pintype "power_in"))
    (pad "6" smd rect (at 0.675 0.248 90) (size 0.55 0.25) (layers "F.Cu" "F.Paste" "F.Mask")
      (net 391 "Net-(U19-SW)") (pinfunction "SW") (pintype "bidirectional"))
    (pad "7" smd rect (at 0.675 -0.25 90) (size 0.55 0.25) (layers "F.Cu" "F.Paste" "F.Mask")
      (net 11 "VCC5V0") (pinfunction "VIN") (pintype "power_in"))
    (pad "8" smd rect (at 0.675 -0.75 90) (size 0.55 0.25) (layers "F.Cu" "F.Paste" "F.Mask")
      (net 224 "/Power supply/1V35_PG") (pinfunction "PG") (pintype "output"))
  )

  (footprint "antmicro-footprints:QFN-8_2x1.5mm" (layer "F.Cu")
    (at 71.05 86.15 90)
    (property "Author" "Antmicro")
    (property "License" "Apache-2.0")
    (property "MPN" "TPS62823DLCT")
    (property "Manufacturer" "Texas Instruments")
    (property "Sheetfile" "power-supply.kicad_sch")
    (property "Sheetname" "Power supply")
    (property "ki_description" "DC/DC converter")
    (property "ki_keywords" "SMT, PMIC, IC, SWITCHING, VOLTAGE, REGULATOR, DC-DC")
    (attr smd)
    (fp_text reference "U20" (at 0.295 1.65 90) (layer "F.SilkS")
        (effects (font (size 0.7 0.7) (thickness 0.127)))
    )
    (fp_text value "TPS62823DLCT" (at 0 2.075 90) (layer "F.Fab")
        (effects (font (size 1 1) (thickness 0.15)))
    )
    (fp_text user "License: Apache-2.0" (at -1.651 6.475 90) (layer "F.Fab") hide
        (effects (font (size 0.7 0.7) (thickness 0.15)) (justify left bottom))
    )
    (fp_text user "${REFERENCE}" (at 0 0 90) (layer "F.Fab")
        (effects (font (size 0.5 0.5) (thickness 0.075)))
    )
    (fp_text user "Author: Antmicro" (at -1.651 5.275 90) (layer "F.Fab") hide
        (effects (font (size 0.7 0.7) (thickness 0.15)) (justify left bottom))
    )
    (fp_line (start -0.9 1.05) (end 0.9 1.05)
      (stroke (width 0.15) (type solid)) (layer "F.SilkS"))
    (fp_line (start -0.25 -1.05) (end 0.9 -1.05)
      (stroke (width 0.15) (type solid)) (layer "F.SilkS"))
    (fp_circle (center -0.9 -1.05) (end -0.849 -1.05)
      (stroke (width 0.15) (type solid)) (fill solid) (layer "F.SilkS"))
    (fp_rect (start -1.1 -1.25) (end 1.1 1.25)
      (stroke (width 0.05) (type solid)) (fill none) (layer "F.CrtYd"))
    (fp_line (start -1 -0.5) (end -0.5 -1)
      (stroke (width 0.15) (type solid)) (layer "F.Fab"))
    (fp_line (start -1 0.998) (end -1 -0.5)
      (stroke (width 0.15) (type solid)) (layer "F.Fab"))
    (fp_line (start -0.5 -1) (end 0.998 -1)
      (stroke (width 0.15) (type solid)) (layer "F.Fab"))
    (fp_line (start 0.998 -1) (end 0.998 0.998)
      (stroke (width 0.15) (type solid)) (layer "F.Fab"))
    (fp_line (start 0.998 0.998) (end -1 0.998)
      (stroke (width 0.15) (type solid)) (layer "F.Fab"))
    (pad "1" smd rect (at -0.677 -0.75 90) (size 0.55 0.25) (layers "F.Cu" "F.Paste" "F.Mask")
      (net 366 "/Power supply/VCCA0_EN") (pinfunction "EN") (pintype "input"))
    (pad "2" smd rect (at -0.677 -0.25 90) (size 0.55 0.25) (layers "F.Cu" "F.Paste" "F.Mask")
      (net 300 "Net-(U20-FB)") (pinfunction "FB") (pintype "bidirectional"))
    (pad "3" smd rect (at -0.677 0.248 90) (size 0.55 0.25) (layers "F.Cu" "F.Paste" "F.Mask")
      (net 1 "GND") (pinfunction "AGND") (pintype "power_in"))
    (pad "4" smd rect (at -0.677 0.748 90) (size 0.55 0.25) (layers "F.Cu" "F.Paste" "F.Mask")
      (net 546 "unconnected-(U20-NC-Pad4)") (pinfunction "NC") (pintype "no_connect"))
    (pad "5" smd rect (at 0.675 0.748 90) (size 0.55 0.25) (layers "F.Cu" "F.Paste" "F.Mask")
      (net 1 "GND") (pinfunction "PGND") (pintype "power_in"))
    (pad "6" smd rect (at 0.675 0.248 90) (size 0.55 0.25) (layers "F.Cu" "F.Paste" "F.Mask")
      (net 392 "Net-(U20-SW)") (pinfunction "SW") (pintype "bidirectional"))
    (pad "7" smd rect (at 0.675 -0.25 90) (size 0.55 0.25) (layers "F.Cu" "F.Paste" "F.Mask")
      (net 11 "VCC5V0") (pinfunction "VIN") (pintype "power_in"))
    (pad "8" smd rect (at 0.675 -0.75 90) (size 0.55 0.25) (layers "F.Cu" "F.Paste" "F.Mask")
      (net 385 "1V0_PG") (pinfunction "PG") (pintype "output"))
  )

  (footprint "antmicro-footprints:R_0402_1005Metric" (layer "F.Cu")
    (at 76.75 88.7)
    (descr "Resistor SMD 0402")
    (tags "resistor SMD 0402")
    (property "Author" "Antmicro")
    (property "License" "Apache-2.0")
    (property "MPN" "CR0402-FX-1003GLF")
    (property "Manufacturer" "Bourns")
    (property "Public" "False")
    (property "Sheetfile" "power-supply.kicad_sch")
    (property "Sheetname" "Power supply")
    (property "Tolerance" "1%")
    (property "Val" "100k")
    (property "ki_description" "SMD Chip Resistor, 100 kohm, ± 1%, 62.5 mW, 0402 [1005 Metric], Thick Film, General Purpose")
    (property "ki_keywords" "0402, SMT, RESISTOR, PASSIVE")
    (attr smd)
    (fp_text reference "R119" (at -0.29 0.96) (layer "F.SilkS")
        (effects (font (size 0.7 0.7) (thickness 0.127)))
    )
    (fp_text value "R_100k_0402" (at 0 1.17) (layer "F.Fab")
        (effects (font (size 1 1) (thickness 0.15)))
    )
    (fp_text user "License: Apache-2.0" (at -0.95 5.169) (layer "F.Fab") hide
        (effects (font (size 0.7 0.7) (thickness 0.15)) (justify left bottom))
    )
    (fp_text user "Author: Antmicro" (at -0.95 4.169) (layer "F.Fab") hide
        (effects (font (size 0.7 0.7) (thickness 0.15)) (justify left bottom))
    )
    (fp_text user "${REFERENCE}" (at 0 0) (layer "F.Fab")
        (effects (font (size 0.25 0.25) (thickness 0.04)))
    )
    (fp_rect (start -0.925 -0.47) (end 0.925 0.47)
      (stroke (width 0.05) (type default)) (fill none) (layer "F.CrtYd"))
    (fp_rect (start -0.5 -0.25) (end 0.5 0.25)
      (stroke (width 0.15) (type solid)) (fill none) (layer "F.Fab"))
    (pad "1" smd roundrect (at -0.48 0) (size 0.59 0.64) (layers "F.Cu" "F.Paste" "F.Mask") (roundrect_rratio 0.25)
      (net 299 "Net-(U19-FB)") (pintype "passive"))
    (pad "2" smd roundrect (at 0.48 0) (size 0.59 0.64) (layers "F.Cu" "F.Paste" "F.Mask") (roundrect_rratio 0.25)
      (net 1 "GND") (pintype "passive"))
  )

  (footprint "antmicro-footprints:R_0402_1005Metric" (layer "F.Cu")
    (at 78.75 88.7 180)
    (descr "Resistor SMD 0402")
    (tags "resistor SMD 0402")
    (property "Author" "Antmicro")
    (property "License" "Apache-2.0")
    (property "MPN" "CR0402-FX-1243GLF")
    (property "Manufacturer" "Bourns")
    (property "Public" "False")
    (property "Sheetfile" "power-supply.kicad_sch")
    (property "Sheetname" "Power supply")
    (property "Tolerance" "1%")
    (property "Val" "124k")
    (property "ki_description" "SMD Chip Resistor, 124 kohm, ± 1%, 100 mW, 0402 [1005 Metric], Thick Film, Precision")
    (property "ki_keywords" "0402, SMT, RESISTOR, PASSIVE")
    (attr smd)
    (fp_text reference "R118" (at 1.05 -1.94) (layer "F.SilkS")
        (effects (font (size 0.7 0.7) (thickness 0.127)))
    )
    (fp_text value "R_124k_0402" (at 0 1.17) (layer "F.Fab")
        (effects (font (size 1 1) (thickness 0.15)))
    )
    (fp_text user "Author: Antmicro" (at -0.95 4.169 180) (layer "F.Fab") hide
        (effects (font (size 0.7 0.7) (thickness 0.15)) (justify left bottom))
    )
    (fp_text user "${REFERENCE}" (at 0 0) (layer "F.Fab")
        (effects (font (size 0.25 0.25) (thickness 0.04)))
    )
    (fp_text user "License: Apache-2.0" (at -0.95 5.169 180) (layer "F.Fab") hide
        (effects (font (size 0.7 0.7) (thickness 0.15)) (justify left bottom))
    )
    (fp_rect (start -0.925 -0.47) (end 0.925 0.47)
      (stroke (width 0.05) (type default)) (fill none) (layer "F.CrtYd"))
    (fp_rect (start -0.5 -0.25) (end 0.5 0.25)
      (stroke (width 0.15) (type solid)) (fill none) (layer "F.Fab"))
    (pad "1" smd roundrect (at -0.48 0 180) (size 0.59 0.64) (layers "F.Cu" "F.Paste" "F.Mask") (roundrect_rratio 0.25)
      (net 357 "Net-(C120-Pad2)") (pintype "passive"))
    (pad "2" smd roundrect (at 0.48 0 180) (size 0.59 0.64) (layers "F.Cu" "F.Paste" "F.Mask") (roundrect_rratio 0.25)
      (net 299 "Net-(U19-FB)") (pintype "passive"))
  )

  (footprint "antmicro-footprints:R_0402_1005Metric" (layer "F.Cu")
    (at 70.585 88.7 180)
    (descr "Resistor SMD 0402")
    (tags "resistor SMD 0402")
    (property "Author" "Antmicro")
    (property "License" "Apache-2.0")
    (property "MPN" "CR0402-FX-1003GLF")
    (property "Manufacturer" "Bourns")
    (property "Public" "False")
    (property "Sheetfile" "power-supply.kicad_sch")
    (property "Sheetname" "Power supply")
    (property "Tolerance" "1%")
    (property "Val" "100k")
    (property "ki_description" "SMD Chip Resistor, 100 kohm, ± 1%, 62.5 mW, 0402 [1005 Metric], Thick Film, General Purpose")
    (property "ki_keywords" "0402, SMT, RESISTOR, PASSIVE")
    (attr smd)
    (fp_text reference "R121" (at -0.515 0.925) (layer "F.SilkS")
        (effects (font (size 0.7 0.7) (thickness 0.127)))
    )
    (fp_text value "R_100k_0402" (at 0 1.17) (layer "F.Fab")
        (effects (font (size 1 1) (thickness 0.15)))
    )
    (fp_text user "License: Apache-2.0" (at -0.95 5.169 180) (layer "F.Fab") hide
        (effects (font (size 0.7 0.7) (thickness 0.15)) (justify left bottom))
    )
    (fp_text user "${REFERENCE}" (at 0 0) (layer "F.Fab")
        (effects (font (size 0.25 0.25) (thickness 0.04)))
    )
    (fp_text user "Author: Antmicro" (at -0.95 4.169 180) (layer "F.Fab") hide
        (effects (font (size 0.7 0.7) (thickness 0.15)) (justify left bottom))
    )
    (fp_rect (start -0.925 -0.47) (end 0.925 0.47)
      (stroke (width 0.05) (type default)) (fill none) (layer "F.CrtYd"))
    (fp_rect (start -0.5 -0.25) (end 0.5 0.25)
      (stroke (width 0.15) (type solid)) (fill none) (layer "F.Fab"))
    (pad "1" smd roundrect (at -0.48 0 180) (size 0.59 0.64) (layers "F.Cu" "F.Paste" "F.Mask") (roundrect_rratio 0.25)
      (net 1 "GND") (pintype "passive"))
    (pad "2" smd roundrect (at 0.48 0 180) (size 0.59 0.64) (layers "F.Cu" "F.Paste" "F.Mask") (roundrect_rratio 0.25)
      (net 300 "Net-(U20-FB)") (pintype "passive"))
  )

  (footprint "antmicro-footprints:R_0402_1005Metric" (layer "F.Cu")
    (at 117.524056 86.193104)
    (descr "Resistor SMD 0402")
    (tags "resistor SMD 0402")
    (property "Author" "Antmicro")
    (property "License" "Apache-2.0")
    (property "MPN" "CR0402-FX-1003GLF")
    (property "Manufacturer" "Bourns")
    (property "Public" "False")
    (property "Sheetfile" "power-supply.kicad_sch")
    (property "Sheetname" "Power supply")
    (property "Tolerance" "1%")
    (property "Val" "100k")
    (property "ki_description" "SMD Chip Resistor, 100 kohm, ± 1%, 62.5 mW, 0402 [1005 Metric], Thick Film, General Purpose")
    (property "ki_keywords" "0402, SMT, RESISTOR, PASSIVE")
    (attr smd)
    (fp_text reference "R117" (at -1.235 -0.94) (layer "F.SilkS")
        (effects (font (size 0.7 0.7) (thickness 0.127)))
    )
    (fp_text value "R_100k_0402" (at 0 1.17) (layer "F.Fab")
        (effects (font (size 1 1) (thickness 0.15)))
    )
    (fp_text user "Author: Antmicro" (at -0.95 4.169) (layer "F.Fab") hide
        (effects (font (size 0.7 0.7) (thickness 0.15)) (justify left bottom))
    )
    (fp_text user "License: Apache-2.0" (at -0.95 5.169) (layer "F.Fab") hide
        (effects (font (size 0.7 0.7) (thickness 0.15)) (justify left bottom))
    )
    (fp_text user "${REFERENCE}" (at 0 0) (layer "F.Fab")
        (effects (font (size 0.25 0.25) (thickness 0.04)))
    )
    (fp_rect (start -0.925 -0.47) (end 0.925 0.47)
      (stroke (width 0.05) (type default)) (fill none) (layer "F.CrtYd"))
    (fp_rect (start -0.5 -0.25) (end 0.5 0.25)
      (stroke (width 0.15) (type solid)) (fill none) (layer "F.Fab"))
    (pad "1" smd roundrect (at -0.48 0) (size 0.59 0.64) (layers "F.Cu" "F.Paste" "F.Mask") (roundrect_rratio 0.25)
      (net 292 "Net-(U18-FB)") (pintype "passive"))
    (pad "2" smd roundrect (at 0.48 0) (size 0.59 0.64) (layers "F.Cu" "F.Paste" "F.Mask") (roundrect_rratio 0.25)
      (net 1 "GND") (pintype "passive"))
  )

  (footprint "antmicro-footprints:R_0402_1005Metric" (layer "F.Cu")
    (at 119.589056 86.193104 180)
    (descr "Resistor SMD 0402")
    (tags "resistor SMD 0402")
    (property "Author" "Antmicro")
    (property "License" "Apache-2.0")
    (property "MPN" "CR0402-FX-2003GLF")
    (property "Manufacturer" "Bourns")
    (property "Public" "False")
    (property "Sheetfile" "power-supply.kicad_sch")
    (property "Sheetname" "Power supply")
    (property "Tolerance" "1%")
    (property "Val" "200k")
    (property "ki_description" "SMD Chip Resistor, 200 kohm, ± 1%, 62.5 mW, 0402 [1005 Metric], Thick Film, General Purpose")
    (property "ki_keywords" "0402, SMT, RESISTOR, PASSIVE")
    (attr smd)
    (fp_text reference "R116" (at 0.1 0.94) (layer "F.SilkS")
        (effects (font (size 0.7 0.7) (thickness 0.127)))
    )
    (fp_text value "R_200k_0402" (at 0 1.17) (layer "F.Fab")
        (effects (font (size 1 1) (thickness 0.15)))
    )
    (fp_text user "License: Apache-2.0" (at -0.95 5.169 180) (layer "F.Fab") hide
        (effects (font (size 0.7 0.7) (thickness 0.15)) (justify left bottom))
    )
    (fp_text user "${REFERENCE}" (at 0 0) (layer "F.Fab")
        (effects (font (size 0.25 0.25) (thickness 0.04)))
    )
    (fp_text user "Author: Antmicro" (at -0.95 4.169 180) (layer "F.Fab") hide
        (effects (font (size 0.7 0.7) (thickness 0.15)) (justify left bottom))
    )
    (fp_rect (start -0.925 -0.47) (end 0.925 0.47)
      (stroke (width 0.05) (type default)) (fill none) (layer "F.CrtYd"))
    (fp_rect (start -0.5 -0.25) (end 0.5 0.25)
      (stroke (width 0.15) (type solid)) (fill none) (layer "F.Fab"))
    (pad "1" smd roundrect (at -0.48 0 180) (size 0.59 0.64) (layers "F.Cu" "F.Paste" "F.Mask") (roundrect_rratio 0.25)
      (net 356 "Net-(C119-Pad2)") (pintype "passive"))
    (pad "2" smd roundrect (at 0.48 0 180) (size 0.59 0.64) (layers "F.Cu" "F.Paste" "F.Mask") (roundrect_rratio 0.25)
      (net 292 "Net-(U18-FB)") (pintype "passive"))
  )

  (footprint "antmicro-footprints:R_0402_1005Metric" (layer "F.Cu")
    (at 82.635 88.7)
    (descr "Resistor SMD 0402")
    (tags "resistor SMD 0402")
    (property "Author" "Antmicro")
    (property "License" "Apache-2.0")
    (property "MPN" "CR0402-FX-1003GLF")
    (property "Manufacturer" "Bourns")
    (property "Public" "False")
    (property "Sheetfile" "power-supply.kicad_sch")
    (property "Sheetname" "Power supply")
    (property "Tolerance" "1%")
    (property "Val" "100k")
    (property "ki_description" "SMD Chip Resistor, 100 kohm, ± 1%, 62.5 mW, 0402 [1005 Metric], Thick Film, General Purpose")
    (property "ki_keywords" "0402, SMT, RESISTOR, PASSIVE")
    (attr smd)
    (fp_text reference "R115" (at -0.285 1) (layer "F.SilkS")
        (effects (font (size 0.7 0.7) (thickness 0.127)))
    )
    (fp_text value "R_100k_0402" (at 0 1.17) (layer "F.Fab")
        (effects (font (size 1 1) (thickness 0.15)))
    )
    (fp_text user "${REFERENCE}" (at 0 0) (layer "F.Fab")
        (effects (font (size 0.25 0.25) (thickness 0.04)))
    )
    (fp_text user "License: Apache-2.0" (at -0.95 5.169) (layer "F.Fab") hide
        (effects (font (size 0.7 0.7) (thickness 0.15)) (justify left bottom))
    )
    (fp_text user "Author: Antmicro" (at -0.95 4.169) (layer "F.Fab") hide
        (effects (font (size 0.7 0.7) (thickness 0.15)) (justify left bottom))
    )
    (fp_rect (start -0.925 -0.47) (end 0.925 0.47)
      (stroke (width 0.05) (type default)) (fill none) (layer "F.CrtYd"))
    (fp_rect (start -0.5 -0.25) (end 0.5 0.25)
      (stroke (width 0.15) (type solid)) (fill none) (layer "F.Fab"))
    (pad "1" smd roundrect (at -0.48 0) (size 0.59 0.64) (layers "F.Cu" "F.Paste" "F.Mask") (roundrect_rratio 0.25)
      (net 291 "Net-(U17-FB)") (pintype "passive"))
    (pad "2" smd roundrect (at 0.48 0) (size 0.59 0.64) (layers "F.Cu" "F.Paste" "F.Mask") (roundrect_rratio 0.25)
      (net 1 "GND") (pintype "passive"))
  )

  (footprint "antmicro-footprints:R_0402_1005Metric" (layer "F.Cu")
    (at 84.6 88.7 180)
    (descr "Resistor SMD 0402")
    (tags "resistor SMD 0402")
    (property "Author" "Antmicro")
    (property "License" "Apache-2.0")
    (property "MPN" "CR0402-FX-4533GLF")
    (property "Manufacturer" "Bourns")
    (property "Public" "False")
    (property "Sheetfile" "power-supply.kicad_sch")
    (property "Sheetname" "Power supply")
    (property "Tolerance" "1%")
    (property "Val" "453k")
    (property "ki_description" "SMD Chip Resistor")
    (property "ki_keywords" "0402, SMT, RESISTOR, PASSIVE")
    (attr smd)
    (fp_text reference "R114" (at -0.11 -1.885) (layer "F.SilkS")
        (effects (font (size 0.7 0.7) (thickness 0.127)))
    )
    (fp_text value "R_453k_0402" (at 0 1.17) (layer "F.Fab")
        (effects (font (size 1 1) (thickness 0.15)))
    )
    (fp_text user "${REFERENCE}" (at 0 0) (layer "F.Fab")
        (effects (font (size 0.25 0.25) (thickness 0.04)))
    )
    (fp_text user "Author: Antmicro" (at -0.95 4.169 180) (layer "F.Fab") hide
        (effects (font (size 0.7 0.7) (thickness 0.15)) (justify left bottom))
    )
    (fp_text user "License: Apache-2.0" (at -0.95 5.169 180) (layer "F.Fab") hide
        (effects (font (size 0.7 0.7) (thickness 0.15)) (justify left bottom))
    )
    (fp_rect (start -0.925 -0.47) (end 0.925 0.47)
      (stroke (width 0.05) (type default)) (fill none) (layer "F.CrtYd"))
    (fp_rect (start -0.5 -0.25) (end 0.5 0.25)
      (stroke (width 0.15) (type solid)) (fill none) (layer "F.Fab"))
    (pad "1" smd roundrect (at -0.48 0 180) (size 0.59 0.64) (layers "F.Cu" "F.Paste" "F.Mask") (roundrect_rratio 0.25)
      (net 355 "Net-(C118-Pad2)") (pintype "passive"))
    (pad "2" smd roundrect (at 0.48 0 180) (size 0.59 0.64) (layers "F.Cu" "F.Paste" "F.Mask") (roundrect_rratio 0.25)
      (net 291 "Net-(U17-FB)") (pintype "passive"))
  )

  (footprint "antmicro-footprints:QFN-8_2x1.5mm" (layer "F.Cu")
    (at 83.1 86.15 90)
    (property "Author" "Antmicro")
    (property "License" "Apache-2.0")
    (property "MPN" "TPS62823DLCT")
    (property "Manufacturer" "Texas Instruments")
    (property "Sheetfile" "power-supply.kicad_sch")
    (property "Sheetname" "Power supply")
    (property "ki_description" "DC/DC converter")
    (property "ki_keywords" "SMT, PMIC, IC, SWITCHING, VOLTAGE, REGULATOR, DC-DC")
    (attr smd)
    (fp_text reference "U17" (at 1.515 -1.55 90) (layer "F.SilkS")
        (effects (font (size 0.7 0.7) (thickness 0.127)))
    )
    (fp_text value "TPS62823DLCT" (at 0 2.075 90) (layer "F.Fab")
        (effects (font (size 1 1) (thickness 0.15)))
    )
    (fp_text user "License: Apache-2.0" (at -1.651 6.475 90) (layer "F.Fab") hide
        (effects (font (size 0.7 0.7) (thickness 0.15)) (justify left bottom))
    )
    (fp_text user "${REFERENCE}" (at 0 0 90) (layer "F.Fab")
        (effects (font (size 0.5 0.5) (thickness 0.075)))
    )
    (fp_text user "Author: Antmicro" (at -1.651 5.275 90) (layer "F.Fab") hide
        (effects (font (size 0.7 0.7) (thickness 0.15)) (justify left bottom))
    )
    (fp_line (start -0.9 1.05) (end 0.9 1.05)
      (stroke (width 0.15) (type solid)) (layer "F.SilkS"))
    (fp_line (start -0.25 -1.05) (end 0.9 -1.05)
      (stroke (width 0.15) (type solid)) (layer "F.SilkS"))
    (fp_circle (center -0.9 -1.05) (end -0.849 -1.05)
      (stroke (width 0.15) (type solid)) (fill solid) (layer "F.SilkS"))
    (fp_rect (start -1.1 -1.25) (end 1.1 1.25)
      (stroke (width 0.05) (type solid)) (fill none) (layer "F.CrtYd"))
    (fp_line (start -1 -0.5) (end -0.5 -1)
      (stroke (width 0.15) (type solid)) (layer "F.Fab"))
    (fp_line (start -1 0.998) (end -1 -0.5)
      (stroke (width 0.15) (type solid)) (layer "F.Fab"))
    (fp_line (start -0.5 -1) (end 0.998 -1)
      (stroke (width 0.15) (type solid)) (layer "F.Fab"))
    (fp_line (start 0.998 -1) (end 0.998 0.998)
      (stroke (width 0.15) (type solid)) (layer "F.Fab"))
    (fp_line (start 0.998 0.998) (end -1 0.998)
      (stroke (width 0.15) (type solid)) (layer "F.Fab"))
    (pad "1" smd rect (at -0.677 -0.75 90) (size 0.55 0.25) (layers "F.Cu" "F.Paste" "F.Mask")
      (net 231 "/Power supply/VCCIO_EN") (pinfunction "EN") (pintype "input"))
    (pad "2" smd rect (at -0.677 -0.25 90) (size 0.55 0.25) (layers "F.Cu" "F.Paste" "F.Mask")
      (net 291 "Net-(U17-FB)") (pinfunction "FB") (pintype "bidirectional"))
    (pad "3" smd rect (at -0.677 0.248 90) (size 0.55 0.25) (layers "F.Cu" "F.Paste" "F.Mask")
      (net 1 "GND") (pinfunction "AGND") (pintype "power_in"))
    (pad "4" smd rect (at -0.677 0.748 90) (size 0.55 0.25) (layers "F.Cu" "F.Paste" "F.Mask")
      (net 543 "unconnected-(U17-NC-Pad4)") (pinfunction "NC") (pintype "no_connect"))
    (pad "5" smd rect (at 0.675 0.748 90) (size 0.55 0.25) (layers "F.Cu" "F.Paste" "F.Mask")
      (net 1 "GND") (pinfunction "PGND") (pintype "power_in"))
    (pad "6" smd rect (at 0.675 0.248 90) (size 0.55 0.25) (layers "F.Cu" "F.Paste" "F.Mask")
      (net 389 "Net-(U17-SW)") (pinfunction "SW") (pintype "bidirectional"))
    (pad "7" smd rect (at 0.675 -0.25 90) (size 0.55 0.25) (layers "F.Cu" "F.Paste" "F.Mask")
      (net 11 "VCC5V0") (pinfunction "VIN") (pintype "power_in"))
    (pad "8" smd rect (at 0.675 -0.75 90) (size 0.55 0.25) (layers "F.Cu" "F.Paste" "F.Mask")
      (net 222 "/Power supply/3V3_PG") (pinfunction "PG") (pintype "output"))
  )

  (footprint "antmicro-footprints:R_0603_1608Metric" (layer "F.Cu")
    (at 80.65 87.2 90)
    (descr "Resistor SMD 0603")
    (tags "resistor SMD 0603")
    (property "Author" "Antmicro")
    (property "Current" "1A")
    (property "License" "Apache-2.0")
    (property "MPN" "CR0603-J/-000ELF")
    (property "Manufacturer" "Bourns")
    (property "Public" "False")
    (property "Sheetfile" "power-supply.kicad_sch")
    (property "Sheetname" "Power supply")
    (property "Tolerance" "")
    (property "Val" "0R")
    (property "ki_description" "Zero Ohm Resistor, Jumper, 0603 [1608 Metric], Thick Film, 100 mW, 1 A, Surface Mount Device, CR")
    (property "ki_keywords" "0603, SMT, RESISTOR, PASSIVE")
    (attr smd)
    (fp_text reference "R143" (at -2.425 -0.01 90) (layer "F.SilkS")
        (effects (font (size 0.7 0.7) (thickness 0.127)))
    )
    (fp_text value "R_0R_0603" (at 0 1.9 90) (layer "F.Fab")
        (effects (font (size 1 1) (thickness 0.15)))
    )
    (fp_text user "${REFERENCE}" (at -1.25 3.898 90) (layer "F.Fab") hide
        (effects (font (size 0.7 0.7) (thickness 0.15)) (justify left bottom))
    )
    (fp_text user "Author: Antmicro" (at -1.25 4.9 90) (layer "F.Fab") hide
        (effects (font (size 0.7 0.7) (thickness 0.15)) (justify left bottom))
    )
    (fp_text user "License: Apache-2.0" (at -1.25 5.9 90) (layer "F.Fab") hide
        (effects (font (size 0.7 0.7) (thickness 0.15)) (justify left bottom))
    )
    (fp_line (start -0.15 -0.4) (end 0.15 -0.4)
      (stroke (width 0.15) (type solid)) (layer "F.SilkS"))
    (fp_line (start -0.15 0.4) (end 0.15 0.4)
      (stroke (width 0.15) (type solid)) (layer "F.SilkS"))
    (fp_rect (start -1.25 -0.65) (end 1.25 0.65)
      (stroke (width 0.05) (type solid)) (fill none) (layer "F.CrtYd"))
    (fp_rect (start -0.8 -0.4) (end 0.8 0.4)
      (stroke (width 0.15) (type solid)) (fill none) (layer "F.Fab"))
    (pad "1" smd roundrect (at -0.7 0 90) (size 0.8 1) (layers "F.Cu" "F.Paste" "F.Mask") (roundrect_rratio 0.2)
      (net 3 "VCC1V35") (pintype "passive"))
    (pad "2" smd roundrect (at 0.7 0 90) (size 0.8 1) (layers "F.Cu" "F.Paste" "F.Mask") (roundrect_rratio 0.2)
      (net 357 "Net-(C120-Pad2)") (pintype "passive"))
  )

  (footprint "antmicro-footprints:C_0402_1005Metric" (layer "F.Cu")
    (at 89.35 83.945 180)
    (descr "Capacitor SMD 0402")
    (tags "capacitor SMD 0402")
    (property "Author" "Antmicro")
    (property "Dielectric" "")
    (property "License" "Apache-2.0")
    (property "MPN" "CC0402MRX5R5BB106")
    (property "Manufacturer" "YAGEO")
    (property "Public" "False")
    (property "Sheetfile" "power-supply.kicad_sch")
    (property "Sheetname" "Power supply")
    (property "Val" "10u")
    (property "Voltage" "")
    (property "ki_description" "SMD Multilayer Ceramic Capacitor, 10 µF, 6.3 V, 0402 [1005 Metric], ± 20%, X5R, CC Series")
    (property "ki_keywords" "0402, SMT, CAPACITOR, PASSIVE, MLCC, CERAMIC")
    (attr smd)
    (fp_text reference "C113" (at 1.41 0.43 90) (layer "F.SilkS")
        (effects (font (size 0.7 0.7) (thickness 0.127)))
    )
    (fp_text value "C_10u_0402" (at 0 1.17) (layer "F.Fab")
        (effects (font (size 1 1) (thickness 0.15)))
    )
    (fp_text user "${REFERENCE}" (at 0 0) (layer "F.Fab")
        (effects (font (size 0.25 0.25) (thickness 0.04)))
    )
    (fp_text user "Author: Antmicro" (at -0.939 3.399 180) (layer "F.Fab") hide
        (effects (font (size 0.7 0.7) (thickness 0.15)) (justify left bottom))
    )
    (fp_text user "License: Apache-2.0" (at -0.939 5.799 180) (layer "F.Fab") hide
        (effects (font (size 0.7 0.7) (thickness 0.15)) (justify left bottom))
    )
    (fp_rect (start -0.925 -0.47) (end 0.925 0.47)
      (stroke (width 0.05) (type default)) (fill none) (layer "F.CrtYd"))
    (fp_line (start -0.494 -0.25) (end 0.504 -0.25)
      (stroke (width 0.15) (type solid)) (layer "F.Fab"))
    (fp_line (start -0.494 0.248) (end -0.494 -0.25)
      (stroke (width 0.15) (type solid)) (layer "F.Fab"))
    (fp_line (start 0.504 -0.25) (end 0.504 0.248)
      (stroke (width 0.15) (type solid)) (layer "F.Fab"))
    (fp_line (start 0.504 0.248) (end -0.494 0.248)
      (stroke (width 0.15) (type solid)) (layer "F.Fab"))
    (pad "1" smd roundrect (at -0.48 0 180) (size 0.59 0.64) (layers "F.Cu" "F.Paste" "F.Mask") (roundrect_rratio 0.25)
      (net 1 "GND") (pintype "passive"))
    (pad "2" smd roundrect (at 0.48 0 180) (size 0.59 0.64) (layers "F.Cu" "F.Paste" "F.Mask") (roundrect_rratio 0.25)
      (net 11 "VCC5V0") (pintype "passive"))
  )

  (footprint "antmicro-footprints:C_0402_1005Metric" (layer "F.Cu")
    (at 118.239056 81.415 180)
    (descr "Capacitor SMD 0402")
    (tags "capacitor SMD 0402")
    (property "Author" "Antmicro")
    (property "Dielectric" "")
    (property "License" "Apache-2.0")
    (property "MPN" "CC0402MRX5R5BB106")
    (property "Manufacturer" "YAGEO")
    (property "Public" "False")
    (property "Sheetfile" "power-supply.kicad_sch")
    (property "Sheetname" "Power supply")
    (property "Val" "10u")
    (property "Voltage" "")
    (property "ki_description" "SMD Multilayer Ceramic Capacitor, 10 µF, 6.3 V, 0402 [1005 Metric], ± 20%, X5R, CC Series")
    (property "ki_keywords" "0402, SMT, CAPACITOR, PASSIVE, MLCC, CERAMIC")
    (attr smd)
    (fp_text reference "C115" (at 3.099056 -0.05) (layer "F.SilkS")
        (effects (font (size 0.7 0.7) (thickness 0.127)))
    )
    (fp_text value "C_10u_0402" (at 0 1.17) (layer "F.Fab")
        (effects (font (size 1 1) (thickness 0.15)))
    )
    (fp_text user "License: Apache-2.0" (at -0.939 5.799 180) (layer "F.Fab") hide
        (effects (font (size 0.7 0.7) (thickness 0.15)) (justify left bottom))
    )
    (fp_text user "${REFERENCE}" (at 0 0 90) (layer "F.Fab")
        (effects (font (size 0.25 0.25) (thickness 0.04)))
    )
    (fp_text user "Author: Antmicro" (at -0.939 3.399 180) (layer "F.Fab") hide
        (effects (font (size 0.7 0.7) (thickness 0.15)) (justify left bottom))
    )
    (fp_rect (start -0.925 -0.47) (end 0.925 0.47)
      (stroke (width 0.05) (type default)) (fill none) (layer "F.CrtYd"))
    (fp_line (start -0.494 -0.25) (end 0.504 -0.25)
      (stroke (width 0.15) (type solid)) (layer "F.Fab"))
    (fp_line (start -0.494 0.248) (end -0.494 -0.25)
      (stroke (width 0.15) (type solid)) (layer "F.Fab"))
    (fp_line (start 0.504 -0.25) (end 0.504 0.248)
      (stroke (width 0.15) (type solid)) (layer "F.Fab"))
    (fp_line (start 0.504 0.248) (end -0.494 0.248)
      (stroke (width 0.15) (type solid)) (layer "F.Fab"))
    (pad "1" smd roundrect (at -0.48 0 180) (size 0.59 0.64) (layers "F.Cu" "F.Paste" "F.Mask") (roundrect_rratio 0.25)
      (net 1 "GND") (pintype "passive"))
    (pad "2" smd roundrect (at 0.48 0 180) (size 0.59 0.64) (layers "F.Cu" "F.Paste" "F.Mask") (roundrect_rratio 0.25)
      (net 11 "VCC5V0") (pintype "passive"))
  )

  (footprint "antmicro-footprints:C_0402_1005Metric" (layer "F.Cu")
    (at 80.05 85.1)
    (descr "Capacitor SMD 0402")
    (tags "capacitor SMD 0402")
    (property "Author" "Antmicro")
    (property "Dielectric" "")
    (property "License" "Apache-2.0")
    (property "MPN" "CC0402MRX5R5BB106")
    (property "Manufacturer" "YAGEO")
    (property "Public" "False")
    (property "Sheetfile" "power-supply.kicad_sch")
    (property "Sheetname" "Power supply")
    (property "Val" "10u")
    (property "Voltage" "")
    (property "ki_description" "SMD Multilayer Ceramic Capacitor, 10 µF, 6.3 V, 0402 [1005 Metric], ± 20%, X5R, CC Series")
    (property "ki_keywords" "0402, SMT, CAPACITOR, PASSIVE, MLCC, CERAMIC")
    (attr smd)
    (fp_text reference "C130" (at -0.44 1.865 -90) (layer "F.SilkS")
        (effects (font (size 0.7 0.7) (thickness 0.127)))
    )
    (fp_text value "C_10u_0402" (at 0 1.17) (layer "F.Fab")
        (effects (font (size 1 1) (thickness 0.15)))
    )
    (fp_text user "${REFERENCE}" (at 0 0) (layer "F.Fab")
        (effects (font (size 0.25 0.25) (thickness 0.04)))
    )
    (fp_text user "License: Apache-2.0" (at -0.939 5.799) (layer "F.Fab") hide
        (effects (font (size 0.7 0.7) (thickness 0.15)) (justify left bottom))
    )
    (fp_text user "Author: Antmicro" (at -0.939 3.399) (layer "F.Fab") hide
        (effects (font (size 0.7 0.7) (thickness 0.15)) (justify left bottom))
    )
    (fp_rect (start -0.925 -0.47) (end 0.925 0.47)
      (stroke (width 0.05) (type default)) (fill none) (layer "F.CrtYd"))
    (fp_line (start -0.494 -0.25) (end 0.504 -0.25)
      (stroke (width 0.15) (type solid)) (layer "F.Fab"))
    (fp_line (start -0.494 0.248) (end -0.494 -0.25)
      (stroke (width 0.15) (type solid)) (layer "F.Fab"))
    (fp_line (start 0.504 -0.25) (end 0.504 0.248)
      (stroke (width 0.15) (type solid)) (layer "F.Fab"))
    (fp_line (start 0.504 0.248) (end -0.494 0.248)
      (stroke (width 0.15) (type solid)) (layer "F.Fab"))
    (pad "1" smd roundrect (at -0.48 0) (size 0.59 0.64) (layers "F.Cu" "F.Paste" "F.Mask") (roundrect_rratio 0.25)
      (net 1 "GND") (pintype "passive"))
    (pad "2" smd roundrect (at 0.48 0) (size 0.59 0.64) (layers "F.Cu" "F.Paste" "F.Mask") (roundrect_rratio 0.25)
      (net 357 "Net-(C120-Pad2)") (pintype "passive"))
  )

  (footprint "antmicro-footprints:C_0402_1005Metric" (layer "F.Cu")
    (at 74.05 85.1)
    (descr "Capacitor SMD 0402")
    (tags "capacitor SMD 0402")
    (property "Author" "Antmicro")
    (property "Dielectric" "")
    (property "License" "Apache-2.0")
    (property "MPN" "CC0402MRX5R5BB106")
    (property "Manufacturer" "YAGEO")
    (property "Public" "False")
    (property "Sheetfile" "power-supply.kicad_sch")
    (property "Sheetname" "Power supply")
    (property "Val" "10u")
    (property "Voltage" "")
    (property "ki_description" "SMD Multilayer Ceramic Capacitor, 10 µF, 6.3 V, 0402 [1005 Metric], ± 20%, X5R, CC Series")
    (property "ki_keywords" "0402, SMT, CAPACITOR, PASSIVE, MLCC, CERAMIC")
    (attr smd)
    (fp_text reference "C131" (at 1.48 -0.465 -90) (layer "F.SilkS")
        (effects (font (size 0.7 0.7) (thickness 0.127)))
    )
    (fp_text value "C_10u_0402" (at 0 1.17) (layer "F.Fab")
        (effects (font (size 1 1) (thickness 0.15)))
    )
    (fp_text user "License: Apache-2.0" (at -0.939 5.799) (layer "F.Fab") hide
        (effects (font (size 0.7 0.7) (thickness 0.15)) (justify left bottom))
    )
    (fp_text user "${REFERENCE}" (at 0 0) (layer "F.Fab")
        (effects (font (size 0.25 0.25) (thickness 0.04)))
    )
    (fp_text user "Author: Antmicro" (at -0.939 3.399) (layer "F.Fab") hide
        (effects (font (size 0.7 0.7) (thickness 0.15)) (justify left bottom))
    )
    (fp_rect (start -0.925 -0.47) (end 0.925 0.47)
      (stroke (width 0.05) (type default)) (fill none) (layer "F.CrtYd"))
    (fp_line (start -0.494 -0.25) (end 0.504 -0.25)
      (stroke (width 0.15) (type solid)) (layer "F.Fab"))
    (fp_line (start -0.494 0.248) (end -0.494 -0.25)
      (stroke (width 0.15) (type solid)) (layer "F.Fab"))
    (fp_line (start 0.504 -0.25) (end 0.504 0.248)
      (stroke (width 0.15) (type solid)) (layer "F.Fab"))
    (fp_line (start 0.504 0.248) (end -0.494 0.248)
      (stroke (width 0.15) (type solid)) (layer "F.Fab"))
    (pad "1" smd roundrect (at -0.48 0) (size 0.59 0.64) (layers "F.Cu" "F.Paste" "F.Mask") (roundrect_rratio 0.25)
      (net 1 "GND") (pintype "passive"))
    (pad "2" smd roundrect (at 0.48 0) (size 0.59 0.64) (layers "F.Cu" "F.Paste" "F.Mask") (roundrect_rratio 0.25)
      (net 358 "Net-(C121-Pad2)") (pintype "passive"))
  )

  (footprint "antmicro-footprints:C_0402_1005Metric" (layer "F.Cu")
    (at 86.05 85.1)
    (descr "Capacitor SMD 0402")
    (tags "capacitor SMD 0402")
    (property "Author" "Antmicro")
    (property "Dielectric" "")
    (property "License" "Apache-2.0")
    (property "MPN" "CC0402MRX5R5BB106")
    (property "Manufacturer" "YAGEO")
    (property "Public" "False")
    (property "Sheetfile" "power-supply.kicad_sch")
    (property "Sheetname" "Power supply")
    (property "Val" "10u")
    (property "Voltage" "")
    (property "ki_description" "SMD Multilayer Ceramic Capacitor, 10 µF, 6.3 V, 0402 [1005 Metric], ± 20%, X5R, CC Series")
    (property "ki_keywords" "0402, SMT, CAPACITOR, PASSIVE, MLCC, CERAMIC")
    (attr smd)
    (fp_text reference "C128" (at -1.35 0.1 90) (layer "F.SilkS")
        (effects (font (size 0.7 0.7) (thickness 0.127)))
    )
    (fp_text value "C_10u_0402" (at 0 1.17) (layer "F.Fab")
        (effects (font (size 1 1) (thickness 0.15)))
    )
    (fp_text user "${REFERENCE}" (at 0 0) (layer "F.Fab")
        (effects (font (size 0.25 0.25) (thickness 0.04)))
    )
    (fp_text user "Author: Antmicro" (at -0.939 3.399) (layer "F.Fab") hide
        (effects (font (size 0.7 0.7) (thickness 0.15)) (justify left bottom))
    )
    (fp_text user "License: Apache-2.0" (at -0.939 5.799) (layer "F.Fab") hide
        (effects (font (size 0.7 0.7) (thickness 0.15)) (justify left bottom))
    )
    (fp_rect (start -0.925 -0.47) (end 0.925 0.47)
      (stroke (width 0.05) (type default)) (fill none) (layer "F.CrtYd"))
    (fp_line (start -0.494 -0.25) (end 0.504 -0.25)
      (stroke (width 0.15) (type solid)) (layer "F.Fab"))
    (fp_line (start -0.494 0.248) (end -0.494 -0.25)
      (stroke (width 0.15) (type solid)) (layer "F.Fab"))
    (fp_line (start 0.504 -0.25) (end 0.504 0.248)
      (stroke (width 0.15) (type solid)) (layer "F.Fab"))
    (fp_line (start 0.504 0.248) (end -0.494 0.248)
      (stroke (width 0.15) (type solid)) (layer "F.Fab"))
    (pad "1" smd roundrect (at -0.48 0) (size 0.59 0.64) (layers "F.Cu" "F.Paste" "F.Mask") (roundrect_rratio 0.25)
      (net 1 "GND") (pintype "passive"))
    (pad "2" smd roundrect (at 0.48 0) (size 0.59 0.64) (layers "F.Cu" "F.Paste" "F.Mask") (roundrect_rratio 0.25)
      (net 355 "Net-(C118-Pad2)") (pintype "passive"))
  )

  (footprint "antmicro-footprints:C_0402_1005Metric" (layer "F.Cu")
    (at 80.05 83.925)
    (descr "Capacitor SMD 0402")
    (tags "capacitor SMD 0402")
    (property "Author" "Antmicro")
    (property "Dielectric" "")
    (property "License" "Apache-2.0")
    (property "MPN" "CC0402MRX5R5BB106")
    (property "Manufacturer" "YAGEO")
    (property "Public" "False")
    (property "Sheetfile" "power-supply.kicad_sch")
    (property "Sheetname" "Power supply")
    (property "Val" "10u")
    (property "Voltage" "")
    (property "ki_description" "SMD Multilayer Ceramic Capacitor, 10 µF, 6.3 V, 0402 [1005 Metric], ± 20%, X5R, CC Series")
    (property "ki_keywords" "0402, SMT, CAPACITOR, PASSIVE, MLCC, CERAMIC")
    (attr smd)
    (fp_text reference "C125" (at -0.82 -1.24) (layer "F.SilkS")
        (effects (font (size 0.7 0.7) (thickness 0.127)))
    )
    (fp_text value "C_10u_0402" (at 0 1.17) (layer "F.Fab")
        (effects (font (size 1 1) (thickness 0.15)))
    )
    (fp_text user "License: Apache-2.0" (at -0.939 5.799) (layer "F.Fab") hide
        (effects (font (size 0.7 0.7) (thickness 0.15)) (justify left bottom))
    )
    (fp_text user "Author: Antmicro" (at -0.939 3.399) (layer "F.Fab") hide
        (effects (font (size 0.7 0.7) (thickness 0.15)) (justify left bottom))
    )
    (fp_text user "${REFERENCE}" (at 0 0) (layer "F.Fab")
        (effects (font (size 0.25 0.25) (thickness 0.04)))
    )
    (fp_rect (start -0.925 -0.47) (end 0.925 0.47)
      (stroke (width 0.05) (type default)) (fill none) (layer "F.CrtYd"))
    (fp_line (start -0.494 -0.25) (end 0.504 -0.25)
      (stroke (width 0.15) (type solid)) (layer "F.Fab"))
    (fp_line (start -0.494 0.248) (end -0.494 -0.25)
      (stroke (width 0.15) (type solid)) (layer "F.Fab"))
    (fp_line (start 0.504 -0.25) (end 0.504 0.248)
      (stroke (width 0.15) (type solid)) (layer "F.Fab"))
    (fp_line (start 0.504 0.248) (end -0.494 0.248)
      (stroke (width 0.15) (type solid)) (layer "F.Fab"))
    (pad "1" smd roundrect (at -0.48 0) (size 0.59 0.64) (layers "F.Cu" "F.Paste" "F.Mask") (roundrect_rratio 0.25)
      (net 1 "GND") (pintype "passive"))
    (pad "2" smd roundrect (at 0.48 0) (size 0.59 0.64) (layers "F.Cu" "F.Paste" "F.Mask") (roundrect_rratio 0.25)
      (net 357 "Net-(C120-Pad2)") (pintype "passive"))
  )

  (footprint "antmicro-footprints:C_0402_1005Metric" (layer "F.Cu")
    (at 74.04 83.945)
    (descr "Capacitor SMD 0402")
    (tags "capacitor SMD 0402")
    (property "Author" "Antmicro")
    (property "Dielectric" "")
    (property "License" "Apache-2.0")
    (property "MPN" "CC0402MRX5R5BB106")
    (property "Manufacturer" "YAGEO")
    (property "Public" "False")
    (property "Sheetfile" "power-supply.kicad_sch")
    (property "Sheetname" "Power supply")
    (property "Val" "10u")
    (property "Voltage" "")
    (property "ki_description" "SMD Multilayer Ceramic Capacitor, 10 µF, 6.3 V, 0402 [1005 Metric], ± 20%, X5R, CC Series")
    (property "ki_keywords" "0402, SMT, CAPACITOR, PASSIVE, MLCC, CERAMIC")
    (attr smd)
    (fp_text reference "C126" (at -0.79 -1.28) (layer "F.SilkS")
        (effects (font (size 0.7 0.7) (thickness 0.127)))
    )
    (fp_text value "C_10u_0402" (at 0 1.17) (layer "F.Fab")
        (effects (font (size 1 1) (thickness 0.15)))
    )
    (fp_text user "License: Apache-2.0" (at -0.939 5.799) (layer "F.Fab") hide
        (effects (font (size 0.7 0.7) (thickness 0.15)) (justify left bottom))
    )
    (fp_text user "Author: Antmicro" (at -0.939 3.399) (layer "F.Fab") hide
        (effects (font (size 0.7 0.7) (thickness 0.15)) (justify left bottom))
    )
    (fp_text user "${REFERENCE}" (at 0 0) (layer "F.Fab")
        (effects (font (size 0.25 0.25) (thickness 0.04)))
    )
    (fp_rect (start -0.925 -0.47) (end 0.925 0.47)
      (stroke (width 0.05) (type default)) (fill none) (layer "F.CrtYd"))
    (fp_line (start -0.494 -0.25) (end 0.504 -0.25)
      (stroke (width 0.15) (type solid)) (layer "F.Fab"))
    (fp_line (start -0.494 0.248) (end -0.494 -0.25)
      (stroke (width 0.15) (type solid)) (layer "F.Fab"))
    (fp_line (start 0.504 -0.25) (end 0.504 0.248)
      (stroke (width 0.15) (type solid)) (layer "F.Fab"))
    (fp_line (start 0.504 0.248) (end -0.494 0.248)
      (stroke (width 0.15) (type solid)) (layer "F.Fab"))
    (pad "1" smd roundrect (at -0.48 0) (size 0.59 0.64) (layers "F.Cu" "F.Paste" "F.Mask") (roundrect_rratio 0.25)
      (net 1 "GND") (pintype "passive"))
    (pad "2" smd roundrect (at 0.48 0) (size 0.59 0.64) (layers "F.Cu" "F.Paste" "F.Mask") (roundrect_rratio 0.25)
      (net 358 "Net-(C121-Pad2)") (pintype "passive"))
  )

  (footprint "antmicro-footprints:C_0402_1005Metric" (layer "F.Cu")
    (at 120.539056 81.415)
    (descr "Capacitor SMD 0402")
    (tags "capacitor SMD 0402")
    (property "Author" "Antmicro")
    (property "Dielectric" "")
    (property "License" "Apache-2.0")
    (property "MPN" "CC0402MRX5R5BB106")
    (property "Manufacturer" "YAGEO")
    (property "Public" "False")
    (property "Sheetfile" "power-supply.kicad_sch")
    (property "Sheetname" "Power supply")
    (property "Val" "10u")
    (property "Voltage" "")
    (property "ki_description" "SMD Multilayer Ceramic Capacitor, 10 µF, 6.3 V, 0402 [1005 Metric], ± 20%, X5R, CC Series")
    (property "ki_keywords" "0402, SMT, CAPACITOR, PASSIVE, MLCC, CERAMIC")
    (attr smd)
    (fp_text reference "C124" (at 2.280944 0) (layer "F.SilkS")
        (effects (font (size 0.7 0.7) (thickness 0.127)))
    )
    (fp_text value "C_10u_0402" (at 0 1.17) (layer "F.Fab")
        (effects (font (size 1 1) (thickness 0.15)))
    )
    (fp_text user "Author: Antmicro" (at -0.939 3.399) (layer "F.Fab") hide
        (effects (font (size 0.7 0.7) (thickness 0.15)) (justify left bottom))
    )
    (fp_text user "${REFERENCE}" (at 0 0) (layer "F.Fab")
        (effects (font (size 0.25 0.25) (thickness 0.04)))
    )
    (fp_text user "License: Apache-2.0" (at -0.939 5.799) (layer "F.Fab") hide
        (effects (font (size 0.7 0.7) (thickness 0.15)) (justify left bottom))
    )
    (fp_rect (start -0.925 -0.47) (end 0.925 0.47)
      (stroke (width 0.05) (type default)) (fill none) (layer "F.CrtYd"))
    (fp_line (start -0.494 -0.25) (end 0.504 -0.25)
      (stroke (width 0.15) (type solid)) (layer "F.Fab"))
    (fp_line (start -0.494 0.248) (end -0.494 -0.25)
      (stroke (width 0.15) (type solid)) (layer "F.Fab"))
    (fp_line (start 0.504 -0.25) (end 0.504 0.248)
      (stroke (width 0.15) (type solid)) (layer "F.Fab"))
    (fp_line (start 0.504 0.248) (end -0.494 0.248)
      (stroke (width 0.15) (type solid)) (layer "F.Fab"))
    (pad "1" smd roundrect (at -0.48 0) (size 0.59 0.64) (layers "F.Cu" "F.Paste" "F.Mask") (roundrect_rratio 0.25)
      (net 1 "GND") (pintype "passive"))
    (pad "2" smd roundrect (at 0.48 0) (size 0.59 0.64) (layers "F.Cu" "F.Paste" "F.Mask") (roundrect_rratio 0.25)
      (net 356 "Net-(C119-Pad2)") (pintype "passive"))
  )

  (footprint "antmicro-footprints:C_0402_1005Metric" (layer "F.Cu")
    (at 86.04 83.945)
    (descr "Capacitor SMD 0402")
    (tags "capacitor SMD 0402")
    (property "Author" "Antmicro")
    (property "Dielectric" "")
    (property "License" "Apache-2.0")
    (property "MPN" "CC0402MRX5R5BB106")
    (property "Manufacturer" "YAGEO")
    (property "Public" "False")
    (property "Sheetfile" "power-supply.kicad_sch")
    (property "Sheetname" "Power supply")
    (property "Val" "10u")
    (property "Voltage" "")
    (property "ki_description" "SMD Multilayer Ceramic Capacitor, 10 µF, 6.3 V, 0402 [1005 Metric], ± 20%, X5R, CC Series")
    (property "ki_keywords" "0402, SMT, CAPACITOR, PASSIVE, MLCC, CERAMIC")
    (attr smd)
    (fp_text reference "C123" (at -0.6 -1.27) (layer "F.SilkS")
        (effects (font (size 0.7 0.7) (thickness 0.127)))
    )
    (fp_text value "C_10u_0402" (at 0 1.17) (layer "F.Fab")
        (effects (font (size 1 1) (thickness 0.15)))
    )
    (fp_text user "License: Apache-2.0" (at -0.939 5.799) (layer "F.Fab") hide
        (effects (font (size 0.7 0.7) (thickness 0.15)) (justify left bottom))
    )
    (fp_text user "Author: Antmicro" (at -0.939 3.399) (layer "F.Fab") hide
        (effects (font (size 0.7 0.7) (thickness 0.15)) (justify left bottom))
    )
    (fp_text user "${REFERENCE}" (at 0 0) (layer "F.Fab")
        (effects (font (size 0.25 0.25) (thickness 0.04)))
    )
    (fp_rect (start -0.925 -0.47) (end 0.925 0.47)
      (stroke (width 0.05) (type default)) (fill none) (layer "F.CrtYd"))
    (fp_line (start -0.494 -0.25) (end 0.504 -0.25)
      (stroke (width 0.15) (type solid)) (layer "F.Fab"))
    (fp_line (start -0.494 0.248) (end -0.494 -0.25)
      (stroke (width 0.15) (type solid)) (layer "F.Fab"))
    (fp_line (start 0.504 -0.25) (end 0.504 0.248)
      (stroke (width 0.15) (type solid)) (layer "F.Fab"))
    (fp_line (start 0.504 0.248) (end -0.494 0.248)
      (stroke (width 0.15) (type solid)) (layer "F.Fab"))
    (pad "1" smd roundrect (at -0.48 0) (size 0.59 0.64) (layers "F.Cu" "F.Paste" "F.Mask") (roundrect_rratio 0.25)
      (net 1 "GND") (pintype "passive"))
    (pad "2" smd roundrect (at 0.48 0) (size 0.59 0.64) (layers "F.Cu" "F.Paste" "F.Mask") (roundrect_rratio 0.25)
      (net 355 "Net-(C118-Pad2)") (pintype "passive"))
  )

  (footprint "antmicro-footprints:C_0402_1005Metric" (layer "F.Cu")
    (at 78.75 89.75)
    (descr "Capacitor SMD 0402")
    (tags "capacitor SMD 0402")
    (property "Author" "Antmicro")
    (property "Dielectric" "C0G")
    (property "License" "Apache-2.0")
    (property "MPN" "C0402C121J5GACTU")
    (property "Manufacturer" "KEMET")
    (property "Public" "False")
    (property "Sheetfile" "power-supply.kicad_sch")
    (property "Sheetname" "Power supply")
    (property "Val" "120p")
    (property "Voltage" "100V")
    (property "ki_description" "120 pF ±2% 100V Ceramic Capacitor C0G, NP0 0402 (1005 Metric)")
    (property "ki_keywords" "0402, SMT, CAPACITOR, PASSIVE, CERAMIC, MLCC")
    (attr smd)
    (fp_text reference "C120" (at 1.88 1.915) (layer "F.SilkS")
        (effects (font (size 0.7 0.7) (thickness 0.127)))
    )
    (fp_text value "C_120p_0402" (at 0 1.17) (layer "F.Fab")
        (effects (font (size 1 1) (thickness 0.15)))
    )
    (fp_text user "Author: Antmicro" (at -0.939 3.399) (layer "F.Fab") hide
        (effects (font (size 0.7 0.7) (thickness 0.15)) (justify left bottom))
    )
    (fp_text user "${REFERENCE}" (at 0 0) (layer "F.Fab")
        (effects (font (size 0.25 0.25) (thickness 0.04)))
    )
    (fp_text user "License: Apache-2.0" (at -0.939 5.799) (layer "F.Fab") hide
        (effects (font (size 0.7 0.7) (thickness 0.15)) (justify left bottom))
    )
    (fp_rect (start -0.925 -0.47) (end 0.925 0.47)
      (stroke (width 0.05) (type default)) (fill none) (layer "F.CrtYd"))
    (fp_line (start -0.494 -0.25) (end 0.504 -0.25)
      (stroke (width 0.15) (type solid)) (layer "F.Fab"))
    (fp_line (start -0.494 0.248) (end -0.494 -0.25)
      (stroke (width 0.15) (type solid)) (layer "F.Fab"))
    (fp_line (start 0.504 -0.25) (end 0.504 0.248)
      (stroke (width 0.15) (type solid)) (layer "F.Fab"))
    (fp_line (start 0.504 0.248) (end -0.494 0.248)
      (stroke (width 0.15) (type solid)) (layer "F.Fab"))
    (pad "1" smd roundrect (at -0.48 0) (size 0.59 0.64) (layers "F.Cu" "F.Paste" "F.Mask") (roundrect_rratio 0.25)
      (net 299 "Net-(U19-FB)") (pintype "passive"))
    (pad "2" smd roundrect (at 0.48 0) (size 0.59 0.64) (layers "F.Cu" "F.Paste" "F.Mask") (roundrect_rratio 0.25)
      (net 357 "Net-(C120-Pad2)") (pintype "passive"))
  )

  (footprint "antmicro-footprints:C_0402_1005Metric" (layer "F.Cu")
    (at 72.65 89.75)
    (descr "Capacitor SMD 0402")
    (tags "capacitor SMD 0402")
    (property "Author" "Antmicro")
    (property "Dielectric" "C0G")
    (property "License" "Apache-2.0")
    (property "MPN" "C0402C121J5GACTU")
    (property "Manufacturer" "KEMET")
    (property "Public" "False")
    (property "Sheetfile" "power-supply.kicad_sch")
    (property "Sheetname" "Power supply")
    (property "Val" "120p")
    (property "Voltage" "100V")
    (property "ki_description" "120 pF ±2% 100V Ceramic Capacitor C0G, NP0 0402 (1005 Metric)")
    (property "ki_keywords" "0402, SMT, CAPACITOR, PASSIVE, CERAMIC, MLCC")
    (attr smd)
    (fp_text reference "C121" (at 0.02 1.625) (layer "F.SilkS")
        (effects (font (size 0.7 0.7) (thickness 0.127)))
    )
    (fp_text value "C_120p_0402" (at 0 1.17) (layer "F.Fab")
        (effects (font (size 1 1) (thickness 0.15)))
    )
    (fp_text user "${REFERENCE}" (at 0 0) (layer "F.Fab")
        (effects (font (size 0.25 0.25) (thickness 0.04)))
    )
    (fp_text user "License: Apache-2.0" (at -0.939 5.799) (layer "F.Fab") hide
        (effects (font (size 0.7 0.7) (thickness 0.15)) (justify left bottom))
    )
    (fp_text user "Author: Antmicro" (at -0.939 3.399) (layer "F.Fab") hide
        (effects (font (size 0.7 0.7) (thickness 0.15)) (justify left bottom))
    )
    (fp_rect (start -0.925 -0.47) (end 0.925 0.47)
      (stroke (width 0.05) (type default)) (fill none) (layer "F.CrtYd"))
    (fp_line (start -0.494 -0.25) (end 0.504 -0.25)
      (stroke (width 0.15) (type solid)) (layer "F.Fab"))
    (fp_line (start -0.494 0.248) (end -0.494 -0.25)
      (stroke (width 0.15) (type solid)) (layer "F.Fab"))
    (fp_line (start 0.504 -0.25) (end 0.504 0.248)
      (stroke (width 0.15) (type solid)) (layer "F.Fab"))
    (fp_line (start 0.504 0.248) (end -0.494 0.248)
      (stroke (width 0.15) (type solid)) (layer "F.Fab"))
    (pad "1" smd roundrect (at -0.48 0) (size 0.59 0.64) (layers "F.Cu" "F.Paste" "F.Mask") (roundrect_rratio 0.25)
      (net 300 "Net-(U20-FB)") (pintype "passive"))
    (pad "2" smd roundrect (at 0.48 0) (size 0.59 0.64) (layers "F.Cu" "F.Paste" "F.Mask") (roundrect_rratio 0.25)
      (net 358 "Net-(C121-Pad2)") (pintype "passive"))
  )

  (footprint "antmicro-footprints:C_0402_1005Metric" (layer "F.Cu")
    (at 119.589056 87.243104)
    (descr "Capacitor SMD 0402")
    (tags "capacitor SMD 0402")
    (property "Author" "Antmicro")
    (property "Dielectric" "C0G")
    (property "License" "Apache-2.0")
    (property "MPN" "C0402C121J5GACTU")
    (property "Manufacturer" "KEMET")
    (property "Public" "False")
    (property "Sheetfile" "power-supply.kicad_sch")
    (property "Sheetname" "Power supply")
    (property "Val" "120p")
    (property "Voltage" "100V")
    (property "ki_description" "120 pF ±2% 100V Ceramic Capacitor C0G, NP0 0402 (1005 Metric)")
    (property "ki_keywords" "0402, SMT, CAPACITOR, PASSIVE, CERAMIC, MLCC")
    (attr smd)
    (fp_text reference "C119" (at -0.079056 0.941896) (layer "F.SilkS")
        (effects (font (size 0.7 0.7) (thickness 0.127)))
    )
    (fp_text value "C_120p_0402" (at 0 1.17) (layer "F.Fab")
        (effects (font (size 1 1) (thickness 0.15)))
    )
    (fp_text user "Author: Antmicro" (at -0.939 3.399) (layer "F.Fab") hide
        (effects (font (size 0.7 0.7) (thickness 0.15)) (justify left bottom))
    )
    (fp_text user "${REFERENCE}" (at 0 0) (layer "F.Fab")
        (effects (font (size 0.25 0.25) (thickness 0.04)))
    )
    (fp_text user "License: Apache-2.0" (at -0.939 5.799) (layer "F.Fab") hide
        (effects (font (size 0.7 0.7) (thickness 0.15)) (justify left bottom))
    )
    (fp_rect (start -0.925 -0.47) (end 0.925 0.47)
      (stroke (width 0.05) (type default)) (fill none) (layer "F.CrtYd"))
    (fp_line (start -0.494 -0.25) (end 0.504 -0.25)
      (stroke (width 0.15) (type solid)) (layer "F.Fab"))
    (fp_line (start -0.494 0.248) (end -0.494 -0.25)
      (stroke (width 0.15) (type solid)) (layer "F.Fab"))
    (fp_line (start 0.504 -0.25) (end 0.504 0.248)
      (stroke (width 0.15) (type solid)) (layer "F.Fab"))
    (fp_line (start 0.504 0.248) (end -0.494 0.248)
      (stroke (width 0.15) (type solid)) (layer "F.Fab"))
    (pad "1" smd roundrect (at -0.48 0) (size 0.59 0.64) (layers "F.Cu" "F.Paste" "F.Mask") (roundrect_rratio 0.25)
      (net 292 "Net-(U18-FB)") (pintype "passive"))
    (pad "2" smd roundrect (at 0.48 0) (size 0.59 0.64) (layers "F.Cu" "F.Paste" "F.Mask") (roundrect_rratio 0.25)
      (net 356 "Net-(C119-Pad2)") (pintype "passive"))
  )

  (footprint "antmicro-footprints:C_0402_1005Metric" (layer "F.Cu")
    (at 84.6 89.75)
    (descr "Capacitor SMD 0402")
    (tags "capacitor SMD 0402")
    (property "Author" "Antmicro")
    (property "Dielectric" "C0G")
    (property "License" "Apache-2.0")
    (property "MPN" "C0402C121J5GACTU")
    (property "Manufacturer" "KEMET")
    (property "Public" "False")
    (property "Sheetfile" "power-supply.kicad_sch")
    (property "Sheetname" "Power supply")
    (property "Val" "120p")
    (property "Voltage" "100V")
    (property "ki_description" "120 pF ±2% 100V Ceramic Capacitor C0G, NP0 0402 (1005 Metric)")
    (property "ki_keywords" "0402, SMT, CAPACITOR, PASSIVE, CERAMIC, MLCC")
    (attr smd)
    (fp_text reference "C118" (at -0.1 -1.9) (layer "F.SilkS")
        (effects (font (size 0.7 0.7) (thickness 0.127)))
    )
    (fp_text value "C_120p_0402" (at 0 1.17) (layer "F.Fab")
        (effects (font (size 1 1) (thickness 0.15)))
    )
    (fp_text user "License: Apache-2.0" (at -0.939 5.799) (layer "F.Fab") hide
        (effects (font (size 0.7 0.7) (thickness 0.15)) (justify left bottom))
    )
    (fp_text user "Author: Antmicro" (at -0.939 3.399) (layer "F.Fab") hide
        (effects (font (size 0.7 0.7) (thickness 0.15)) (justify left bottom))
    )
    (fp_text user "${REFERENCE}" (at 0 0) (layer "F.Fab")
        (effects (font (size 0.25 0.25) (thickness 0.04)))
    )
    (fp_rect (start -0.925 -0.47) (end 0.925 0.47)
      (stroke (width 0.05) (type default)) (fill none) (layer "F.CrtYd"))
    (fp_line (start -0.494 -0.25) (end 0.504 -0.25)
      (stroke (width 0.15) (type solid)) (layer "F.Fab"))
    (fp_line (start -0.494 0.248) (end -0.494 -0.25)
      (stroke (width 0.15) (type solid)) (layer "F.Fab"))
    (fp_line (start 0.504 -0.25) (end 0.504 0.248)
      (stroke (width 0.15) (type solid)) (layer "F.Fab"))
    (fp_line (start 0.504 0.248) (end -0.494 0.248)
      (stroke (width 0.15) (type solid)) (layer "F.Fab"))
    (pad "1" smd roundrect (at -0.48 0) (size 0.59 0.64) (layers "F.Cu" "F.Paste" "F.Mask") (roundrect_rratio 0.25)
      (net 291 "Net-(U17-FB)") (pintype "passive"))
    (pad "2" smd roundrect (at 0.48 0) (size 0.59 0.64) (layers "F.Cu" "F.Paste" "F.Mask") (roundrect_rratio 0.25)
      (net 355 "Net-(C118-Pad2)") (pintype "passive"))
  )

  (footprint "antmicro-footprints:C_0402_1005Metric" (layer "F.Cu")
    (at 77.4 83.935 180)
    (descr "Capacitor SMD 0402")
    (tags "capacitor SMD 0402")
    (property "Author" "Antmicro")
    (property "Dielectric" "")
    (property "License" "Apache-2.0")
    (property "MPN" "CC0402MRX5R5BB106")
    (property "Manufacturer" "YAGEO")
    (property "Public" "False")
    (property "Sheetfile" "power-supply.kicad_sch")
    (property "Sheetname" "Power supply")
    (property "Val" "10u")
    (property "Voltage" "")
    (property "ki_description" "SMD Multilayer Ceramic Capacitor, 10 µF, 6.3 V, 0402 [1005 Metric], ± 20%, X5R, CC Series")
    (property "ki_keywords" "0402, SMT, CAPACITOR, PASSIVE, MLCC, CERAMIC")
    (attr smd)
    (fp_text reference "C116" (at 1.18 1.13 180) (layer "F.SilkS")
        (effects (font (size 0.7 0.7) (thickness 0.127)))
    )
    (fp_text value "C_10u_0402" (at 0 1.17) (layer "F.Fab")
        (effects (font (size 1 1) (thickness 0.15)))
    )
    (fp_text user "${REFERENCE}" (at 0 0) (layer "F.Fab")
        (effects (font (size 0.25 0.25) (thickness 0.04)))
    )
    (fp_text user "Author: Antmicro" (at -0.939 3.399 180) (layer "F.Fab") hide
        (effects (font (size 0.7 0.7) (thickness 0.15)) (justify left bottom))
    )
    (fp_text user "License: Apache-2.0" (at -0.939 5.799 180) (layer "F.Fab") hide
        (effects (font (size 0.7 0.7) (thickness 0.15)) (justify left bottom))
    )
    (fp_rect (start -0.925 -0.47) (end 0.925 0.47)
      (stroke (width 0.05) (type default)) (fill none) (layer "F.CrtYd"))
    (fp_line (start -0.494 -0.25) (end 0.504 -0.25)
      (stroke (width 0.15) (type solid)) (layer "F.Fab"))
    (fp_line (start -0.494 0.248) (end -0.494 -0.25)
      (stroke (width 0.15) (type solid)) (layer "F.Fab"))
    (fp_line (start 0.504 -0.25) (end 0.504 0.248)
      (stroke (width 0.15) (type solid)) (layer "F.Fab"))
    (fp_line (start 0.504 0.248) (end -0.494 0.248)
      (stroke (width 0.15) (type solid)) (layer "F.Fab"))
    (pad "1" smd roundrect (at -0.48 0 180) (size 0.59 0.64) (layers "F.Cu" "F.Paste" "F.Mask") (roundrect_rratio 0.25)
      (net 1 "GND") (pintype "passive"))
    (pad "2" smd roundrect (at 0.48 0 180) (size 0.59 0.64) (layers "F.Cu" "F.Paste" "F.Mask") (roundrect_rratio 0.25)
      (net 11 "VCC5V0") (pintype "passive"))
  )

  (footprint "antmicro-footprints:C_0402_1005Metric" (layer "F.Cu")
    (at 71.3 83.945 180)
    (descr "Capacitor SMD 0402")
    (tags "capacitor SMD 0402")
    (property "Author" "Antmicro")
    (property "Dielectric" "")
    (property "License" "Apache-2.0")
    (property "MPN" "CC0402MRX5R5BB106")
    (property "Manufacturer" "YAGEO")
    (property "Public" "False")
    (property "Sheetfile" "power-supply.kicad_sch")
    (property "Sheetname" "Power supply")
    (property "Val" "10u")
    (property "Voltage" "")
    (property "ki_description" "SMD Multilayer Ceramic Capacitor, 10 µF, 6.3 V, 0402 [1005 Metric], ± 20%, X5R, CC Series")
    (property "ki_keywords" "0402, SMT, CAPACITOR, PASSIVE, MLCC, CERAMIC")
    (attr smd)
    (fp_text reference "C117" (at 1.8 0.96 180) (layer "F.SilkS")
        (effects (font (size 0.7 0.7) (thickness 0.127)))
    )
    (fp_text value "C_10u_0402" (at 0 1.17) (layer "F.Fab")
        (effects (font (size 1 1) (thickness 0.15)))
    )
    (fp_text user "License: Apache-2.0" (at -0.939 5.799 180) (layer "F.Fab") hide
        (effects (font (size 0.7 0.7) (thickness 0.15)) (justify left bottom))
    )
    (fp_text user "Author: Antmicro" (at -0.939 3.399 180) (layer "F.Fab") hide
        (effects (font (size 0.7 0.7) (thickness 0.15)) (justify left bottom))
    )
    (fp_text user "${REFERENCE}" (at 0 0) (layer "F.Fab")
        (effects (font (size 0.25 0.25) (thickness 0.04)))
    )
    (fp_rect (start -0.925 -0.47) (end 0.925 0.47)
      (stroke (width 0.05) (type default)) (fill none) (layer "F.CrtYd"))
    (fp_line (start -0.494 -0.25) (end 0.504 -0.25)
      (stroke (width 0.15) (type solid)) (layer "F.Fab"))
    (fp_line (start -0.494 0.248) (end -0.494 -0.25)
      (stroke (width 0.15) (type solid)) (layer "F.Fab"))
    (fp_line (start 0.504 -0.25) (end 0.504 0.248)
      (stroke (width 0.15) (type solid)) (layer "F.Fab"))
    (fp_line (start 0.504 0.248) (end -0.494 0.248)
      (stroke (width 0.15) (type solid)) (layer "F.Fab"))
    (pad "1" smd roundrect (at -0.48 0 180) (size 0.59 0.64) (layers "F.Cu" "F.Paste" "F.Mask") (roundrect_rratio 0.25)
      (net 1 "GND") (pintype "passive"))
    (pad "2" smd roundrect (at 0.48 0 180) (size 0.59 0.64) (layers "F.Cu" "F.Paste" "F.Mask") (roundrect_rratio 0.25)
      (net 11 "VCC5V0") (pintype "passive"))
  )

  (footprint "antmicro-footprints:C_0402_1005Metric" (layer "F.Cu")
    (at 83.34 83.945)
    (descr "Capacitor SMD 0402")
    (tags "capacitor SMD 0402")
    (property "Author" "Antmicro")
    (property "Dielectric" "")
    (property "License" "Apache-2.0")
    (property "MPN" "CC0402MRX5R5BB106")
    (property "Manufacturer" "YAGEO")
    (property "Public" "False")
    (property "Sheetfile" "power-supply.kicad_sch")
    (property "Sheetname" "Power supply")
    (property "Val" "10u")
    (property "Voltage" "")
    (property "ki_description" "SMD Multilayer Ceramic Capacitor, 10 µF, 6.3 V, 0402 [1005 Metric], ± 20%, X5R, CC Series")
    (property "ki_keywords" "0402, SMT, CAPACITOR, PASSIVE, MLCC, CERAMIC")
    (attr smd)
    (fp_text reference "C114" (at -1 -1.84 90) (layer "F.SilkS")
        (effects (font (size 0.7 0.7) (thickness 0.127)))
    )
    (fp_text value "C_10u_0402" (at 0 1.17) (layer "F.Fab")
        (effects (font (size 1 1) (thickness 0.15)))
    )
    (fp_text user "${REFERENCE}" (at 0 0) (layer "F.Fab")
        (effects (font (size 0.25 0.25) (thickness 0.04)))
    )
    (fp_text user "License: Apache-2.0" (at -0.939 5.799) (layer "F.Fab") hide
        (effects (font (size 0.7 0.7) (thickness 0.15)) (justify left bottom))
    )
    (fp_text user "Author: Antmicro" (at -0.939 3.399) (layer "F.Fab") hide
        (effects (font (size 0.7 0.7) (thickness 0.15)) (justify left bottom))
    )
    (fp_rect (start -0.925 -0.47) (end 0.925 0.47)
      (stroke (width 0.05) (type default)) (fill none) (layer "F.CrtYd"))
    (fp_line (start -0.494 -0.25) (end 0.504 -0.25)
      (stroke (width 0.15) (type solid)) (layer "F.Fab"))
    (fp_line (start -0.494 0.248) (end -0.494 -0.25)
      (stroke (width 0.15) (type solid)) (layer "F.Fab"))
    (fp_line (start 0.504 -0.25) (end 0.504 0.248)
      (stroke (width 0.15) (type solid)) (layer "F.Fab"))
    (fp_line (start 0.504 0.248) (end -0.494 0.248)
      (stroke (width 0.15) (type solid)) (layer "F.Fab"))
    (pad "1" smd roundrect (at -0.48 0) (size 0.59 0.64) (layers "F.Cu" "F.Paste" "F.Mask") (roundrect_rratio 0.25)
      (net 11 "VCC5V0") (pintype "passive"))
    (pad "2" smd roundrect (at 0.48 0) (size 0.59 0.64) (layers "F.Cu" "F.Paste" "F.Mask") (roundrect_rratio 0.25)
      (net 1 "GND") (pintype "passive"))
  )

  (footprint "antmicro-footprints:R_0603_1608Metric" (layer "F.Cu")
    (at 92.6 87.2 90)
    (descr "Resistor SMD 0603")
    (tags "resistor SMD 0603")
    (property "Author" "Antmicro")
    (property "Current" "1A")
    (property "License" "Apache-2.0")
    (property "MPN" "CR0603-J/-000ELF")
    (property "Manufacturer" "Bourns")
    (property "Public" "False")
    (property "Sheetfile" "power-supply.kicad_sch")
    (property "Sheetname" "Power supply")
    (property "Tolerance" "")
    (property "Val" "0R")
    (property "ki_description" "Zero Ohm Resistor, Jumper, 0603 [1608 Metric], Thick Film, 100 mW, 1 A, Surface Mount Device, CR")
    (property "ki_keywords" "0603, SMT, RESISTOR, PASSIVE")
    (attr smd)
    (fp_text reference "R145" (at -0.21 1.19 90) (layer "F.SilkS")
        (effects (font (size 0.7 0.7) (thickness 0.127)))
    )
    (fp_text value "R_0R_0603" (at 0 1.9 90) (layer "F.Fab")
        (effects (font (size 1 1) (thickness 0.15)))
    )
    (fp_text user "License: Apache-2.0" (at -1.25 5.9 90) (layer "F.Fab") hide
        (effects (font (size 0.7 0.7) (thickness 0.15)) (justify left bottom))
    )
    (fp_text user "Author: Antmicro" (at -1.25 4.9 90) (layer "F.Fab") hide
        (effects (font (size 0.7 0.7) (thickness 0.15)) (justify left bottom))
    )
    (fp_text user "${REFERENCE}" (at -1.25 3.898 90) (layer "F.Fab") hide
        (effects (font (size 0.7 0.7) (thickness 0.15)) (justify left bottom))
    )
    (fp_line (start -0.15 -0.4) (end 0.15 -0.4)
      (stroke (width 0.15) (type solid)) (layer "F.SilkS"))
    (fp_line (start -0.15 0.4) (end 0.15 0.4)
      (stroke (width 0.15) (type solid)) (layer "F.SilkS"))
    (fp_rect (start -1.25 -0.65) (end 1.25 0.65)
      (stroke (width 0.05) (type solid)) (fill none) (layer "F.CrtYd"))
    (fp_rect (start -0.8 -0.4) (end 0.8 0.4)
      (stroke (width 0.15) (type solid)) (fill none) (layer "F.Fab"))
    (pad "1" smd roundrect (at -0.7 0 90) (size 0.8 1) (layers "F.Cu" "F.Paste" "F.Mask") (roundrect_rratio 0.2)
      (net 225 "VCC2V5") (pintype "passive"))
    (pad "2" smd roundrect (at 0.7 0 90) (size 0.8 1) (layers "F.Cu" "F.Paste" "F.Mask") (roundrect_rratio 0.2)
      (net 359 "Net-(C122-Pad2)") (pintype "passive"))
  )

  (footprint "antmicro-footprints:L_Vishay-IHLP-1212AE" (layer "F.Cu")
    (at 85.25 81.55)
    (property "Author" "Antmicro")
    (property "IMax" "6.7 A")
    (property "ISat" "6.7 A")
    (property "License" "Apache-2.0")
    (property "MPN" "IHLP1212AEERR47M11")
    (property "Manufacturer" "Vishay")
    (property "Public" "False")
    (property "Sheetfile" "power-supply.kicad_sch")
    (property "Sheetname" "Power supply")
    (property "Size" "3.0x3.0")
    (property "Val" "470n/6.7A")
    (property "ki_description" "Power Inductor (SMT), 470 nH, 6.7 A, Shielded, 6.7 A")
    (property "ki_keywords" "SMT, INDUCTOR, PASSIVE")
    (attr smd)
    (fp_text reference "L3" (at -2.35 -1.155) (layer "F.SilkS")
        (effects (font (size 0.7 0.7) (thickness 0.127)))
    )
    (fp_text value "IHLP1212AEERR47M11" (at 0 0 270) (layer "F.SilkS") hide
        (effects (font (size 1.524 1.524) (thickness 0.05)))
    )
    (fp_text user "Author: Antmicro" (at -2.35 6.6) (layer "F.Fab") hide
        (effects (font (size 0.7 0.7) (thickness 0.15)) (justify left bottom))
    )
    (fp_text user "${REFERENCE}" (at -2.35 5.4) (layer "F.Fab") hide
        (effects (font (size 0.7 0.7) (thickness 0.15)) (justify left bottom))
    )
    (fp_text user "License: Apache-2.0" (at -2.35 7.8) (layer "F.Fab") hide
        (effects (font (size 0.7 0.7) (thickness 0.15)) (justify left bottom))
    )
    (fp_line (start -1.647 -1.6) (end 1.653 -1.6)
      (stroke (width 0.15) (type solid)) (layer "F.SilkS"))
    (fp_line (start -1.647 -0.9) (end -1.647 -1.6)
      (stroke (width 0.15) (type solid)) (layer "F.SilkS"))
    (fp_line (start -1.647 1.6) (end -1.647 0.9)
      (stroke (width 0.15) (type solid)) (layer "F.SilkS"))
    (fp_line (start 1.653 -1.6) (end 1.653 -0.9)
      (stroke (width 0.15) (type solid)) (layer "F.SilkS"))
    (fp_line (start 1.653 0.9) (end 1.653 1.601)
      (stroke (width 0.15) (type solid)) (layer "F.SilkS"))
    (fp_line (start 1.653 1.601) (end -1.647 1.6)
      (stroke (width 0.15) (type solid)) (layer "F.SilkS"))
    (fp_rect (start -2.35 -1.85) (end 2.35 1.85)
      (stroke (width 0.05) (type solid)) (fill none) (layer "F.CrtYd"))
    (fp_rect (start -1.803 -1.601) (end 1.803 1.601)
      (stroke (width 0.15) (type solid)) (fill none) (layer "F.Fab"))
    (pad "1" smd roundrect (at -1.35 0) (size 1.5 1.2) (layers "F.Cu" "F.Paste" "F.Mask") (roundrect_rratio 0.1)
      (net 389 "Net-(U17-SW)") (pintype "passive"))
    (pad "2" smd roundrect (at 1.35 0) (size 1.5 1.2) (layers "F.Cu" "F.Paste" "F.Mask") (roundrect_rratio 0.1)
      (net 355 "Net-(C118-Pad2)") (pintype "passive"))
  )

  (footprint "antmicro-footprints:R_0603_1608Metric" (layer "F.Cu")
    (at 86.6 87.2 90)
    (descr "Resistor SMD 0603")
    (tags "resistor SMD 0603")
    (property "Author" "Antmicro")
    (property "Current" "1A")
    (property "License" "Apache-2.0")
    (property "MPN" "CR0603-J/-000ELF")
    (property "Manufacturer" "Bourns")
    (property "Public" "False")
    (property "Sheetfile" "power-supply.kicad_sch")
    (property "Sheetname" "Power supply")
    (property "Tolerance" "")
    (property "Val" "0R")
    (property "ki_description" "Zero Ohm Resistor, Jumper, 0603 [1608 Metric], Thick Film, 100 mW, 1 A, Surface Mount Device, CR")
    (property "ki_keywords" "0603, SMT, RESISTOR, PASSIVE")
    (attr smd)
    (fp_text reference "R141" (at -2.435 0.01 90) (layer "F.SilkS")
        (effects (font (size 0.7 0.7) (thickness 0.127)))
    )
    (fp_text value "R_0R_0603" (at 0 1.9 90) (layer "F.Fab")
        (effects (font (size 1 1) (thickness 0.15)))
    )
    (fp_text user "Author: Antmicro" (at -1.25 4.9 90) (layer "F.Fab") hide
        (effects (font (size 0.7 0.7) (thickness 0.15)) (justify left bottom))
    )
    (fp_text user "${REFERENCE}" (at -1.25 3.898 90) (layer "F.Fab") hide
        (effects (font (size 0.7 0.7) (thickness 0.15)) (justify left bottom))
    )
    (fp_text user "License: Apache-2.0" (at -1.25 5.9 90) (layer "F.Fab") hide
        (effects (font (size 0.7 0.7) (thickness 0.15)) (justify left bottom))
    )
    (fp_line (start -0.15 -0.4) (end 0.15 -0.4)
      (stroke (width 0.15) (type solid)) (layer "F.SilkS"))
    (fp_line (start -0.15 0.4) (end 0.15 0.4)
      (stroke (width 0.15) (type solid)) (layer "F.SilkS"))
    (fp_rect (start -1.25 -0.65) (end 1.25 0.65)
      (stroke (width 0.05) (type solid)) (fill none) (layer "F.CrtYd"))
    (fp_rect (start -0.8 -0.4) (end 0.8 0.4)
      (stroke (width 0.15) (type solid)) (fill none) (layer "F.Fab"))
    (pad "1" smd roundrect (at -0.7 0 90) (size 0.8 1) (layers "F.Cu" "F.Paste" "F.Mask") (roundrect_rratio 0.2)
      (net 2 "VCC3V3") (pintype "passive"))
    (pad "2" smd roundrect (at 0.7 0 90) (size 0.8 1) (layers "F.Cu" "F.Paste" "F.Mask") (roundrect_rratio 0.2)
      (net 355 "Net-(C118-Pad2)") (pintype "passive"))
  )

  (footprint "antmicro-footprints:C_0402_1005Metric" (layer "F.Cu")
    (at 90.65 89.75)
    (descr "Capacitor SMD 0402")
    (tags "capacitor SMD 0402")
    (property "Author" "Antmicro")
    (property "Dielectric" "C0G")
    (property "License" "Apache-2.0")
    (property "MPN" "C0402C121J5GACTU")
    (property "Manufacturer" "KEMET")
    (property "Public" "False")
    (property "Sheetfile" "power-supply.kicad_sch")
    (property "Sheetname" "Power supply")
    (property "Val" "120p")
    (property "Voltage" "100V")
    (property "ki_description" "120 pF ±2% 100V Ceramic Capacitor C0G, NP0 0402 (1005 Metric)")
    (property "ki_keywords" "0402, SMT, CAPACITOR, PASSIVE, CERAMIC, MLCC")
    (attr smd)
    (fp_text reference "C122" (at 0.05 0.825) (layer "F.SilkS")
        (effects (font (size 0.7 0.7) (thickness 0.127)))
    )
    (fp_text value "C_120p_0402" (at 0 1.17) (layer "F.Fab")
        (effects (font (size 1 1) (thickness 0.15)))
    )
    (fp_text user "${REFERENCE}" (at 0 0) (layer "F.Fab")
        (effects (font (size 0.25 0.25) (thickness 0.04)))
    )
    (fp_text user "License: Apache-2.0" (at -0.939 5.799) (layer "F.Fab") hide
        (effects (font (size 0.7 0.7) (thickness 0.15)) (justify left bottom))
    )
    (fp_text user "Author: Antmicro" (at -0.939 3.399) (layer "F.Fab") hide
        (effects (font (size 0.7 0.7) (thickness 0.15)) (justify left bottom))
    )
    (fp_rect (start -0.925 -0.47) (end 0.925 0.47)
      (stroke (width 0.05) (type default)) (fill none) (layer "F.CrtYd"))
    (fp_line (start -0.494 -0.25) (end 0.504 -0.25)
      (stroke (width 0.15) (type solid)) (layer "F.Fab"))
    (fp_line (start -0.494 0.248) (end -0.494 -0.25)
      (stroke (width 0.15) (type solid)) (layer "F.Fab"))
    (fp_line (start 0.504 -0.25) (end 0.504 0.248)
      (stroke (width 0.15) (type solid)) (layer "F.Fab"))
    (fp_line (start 0.504 0.248) (end -0.494 0.248)
      (stroke (width 0.15) (type solid)) (layer "F.Fab"))
    (pad "1" smd roundrect (at -0.48 0) (size 0.59 0.64) (layers "F.Cu" "F.Paste" "F.Mask") (roundrect_rratio 0.25)
      (net 301 "Net-(U16-FB)") (pintype "passive"))
    (pad "2" smd roundrect (at 0.48 0) (size 0.59 0.64) (layers "F.Cu" "F.Paste" "F.Mask") (roundrect_rratio 0.25)
      (net 359 "Net-(C122-Pad2)") (pintype "passive"))
  )

  (footprint "antmicro-footprints:C_0402_1005Metric" (layer "F.Cu")
    (at 92.05 83.965)
    (descr "Capacitor SMD 0402")
    (tags "capacitor SMD 0402")
    (property "Author" "Antmicro")
    (property "Dielectric" "")
    (property "License" "Apache-2.0")
    (property "MPN" "CC0402MRX5R5BB106")
    (property "Manufacturer" "YAGEO")
    (property "Public" "False")
    (property "Sheetfile" "power-supply.kicad_sch")
    (property "Sheetname" "Power supply")
    (property "Val" "10u")
    (property "Voltage" "")
    (property "ki_description" "SMD Multilayer Ceramic Capacitor, 10 µF, 6.3 V, 0402 [1005 Metric], ± 20%, X5R, CC Series")
    (property "ki_keywords" "0402, SMT, CAPACITOR, PASSIVE, MLCC, CERAMIC")
    (attr smd)
    (fp_text reference "C127" (at 2.3 0.69) (layer "F.SilkS")
        (effects (font (size 0.7 0.7) (thickness 0.127)))
    )
    (fp_text value "C_10u_0402" (at 0 1.17) (layer "F.Fab")
        (effects (font (size 1 1) (thickness 0.15)))
    )
    (fp_text user "Author: Antmicro" (at -0.939 3.399) (layer "F.Fab") hide
        (effects (font (size 0.7 0.7) (thickness 0.15)) (justify left bottom))
    )
    (fp_text user "${REFERENCE}" (at 0 0) (layer "F.Fab")
        (effects (font (size 0.25 0.25) (thickness 0.04)))
    )
    (fp_text user "License: Apache-2.0" (at -0.939 5.799) (layer "F.Fab") hide
        (effects (font (size 0.7 0.7) (thickness 0.15)) (justify left bottom))
    )
    (fp_rect (start -0.925 -0.47) (end 0.925 0.47)
      (stroke (width 0.05) (type default)) (fill none) (layer "F.CrtYd"))
    (fp_line (start -0.494 -0.25) (end 0.504 -0.25)
      (stroke (width 0.15) (type solid)) (layer "F.Fab"))
    (fp_line (start -0.494 0.248) (end -0.494 -0.25)
      (stroke (width 0.15) (type solid)) (layer "F.Fab"))
    (fp_line (start 0.504 -0.25) (end 0.504 0.248)
      (stroke (width 0.15) (type solid)) (layer "F.Fab"))
    (fp_line (start 0.504 0.248) (end -0.494 0.248)
      (stroke (width 0.15) (type solid)) (layer "F.Fab"))
    (pad "1" smd roundrect (at -0.48 0) (size 0.59 0.64) (layers "F.Cu" "F.Paste" "F.Mask") (roundrect_rratio 0.25)
      (net 1 "GND") (pintype "passive"))
    (pad "2" smd roundrect (at 0.48 0) (size 0.59 0.64) (layers "F.Cu" "F.Paste" "F.Mask") (roundrect_rratio 0.25)
      (net 359 "Net-(C122-Pad2)") (pintype "passive"))
  )

  (footprint "antmicro-footprints:C_0402_1005Metric" (layer "F.Cu")
    (at 92.05 85.1)
    (descr "Capacitor SMD 0402")
    (tags "capacitor SMD 0402")
    (property "Author" "Antmicro")
    (property "Dielectric" "")
    (property "License" "Apache-2.0")
    (property "MPN" "CC0402MRX5R5BB106")
    (property "Manufacturer" "YAGEO")
    (property "Public" "False")
    (property "Sheetfile" "power-supply.kicad_sch")
    (property "Sheetname" "Power supply")
    (property "Val" "10u")
    (property "Voltage" "")
    (property "ki_description" "SMD Multilayer Ceramic Capacitor, 10 µF, 6.3 V, 0402 [1005 Metric], ± 20%, X5R, CC Series")
    (property "ki_keywords" "0402, SMT, CAPACITOR, PASSIVE, MLCC, CERAMIC")
    (attr smd)
    (fp_text reference "C132" (at 2.32 0.415) (layer "F.SilkS")
        (effects (font (size 0.7 0.7) (thickness 0.127)))
    )
    (fp_text value "C_10u_0402" (at 0 1.17) (layer "F.Fab")
        (effects (font (size 1 1) (thickness 0.15)))
    )
    (fp_text user "${REFERENCE}" (at 0 0) (layer "F.Fab")
        (effects (font (size 0.25 0.25) (thickness 0.04)))
    )
    (fp_text user "Author: Antmicro" (at -0.939 3.399) (layer "F.Fab") hide
        (effects (font (size 0.7 0.7) (thickness 0.15)) (justify left bottom))
    )
    (fp_text user "License: Apache-2.0" (at -0.939 5.799) (layer "F.Fab") hide
        (effects (font (size 0.7 0.7) (thickness 0.15)) (justify left bottom))
    )
    (fp_rect (start -0.925 -0.47) (end 0.925 0.47)
      (stroke (width 0.05) (type default)) (fill none) (layer "F.CrtYd"))
    (fp_line (start -0.494 -0.25) (end 0.504 -0.25)
      (stroke (width 0.15) (type solid)) (layer "F.Fab"))
    (fp_line (start -0.494 0.248) (end -0.494 -0.25)
      (stroke (width 0.15) (type solid)) (layer "F.Fab"))
    (fp_line (start 0.504 -0.25) (end 0.504 0.248)
      (stroke (width 0.15) (type solid)) (layer "F.Fab"))
    (fp_line (start 0.504 0.248) (end -0.494 0.248)
      (stroke (width 0.15) (type solid)) (layer "F.Fab"))
    (pad "1" smd roundrect (at -0.48 0) (size 0.59 0.64) (layers "F.Cu" "F.Paste" "F.Mask") (roundrect_rratio 0.25)
      (net 1 "GND") (pintype "passive"))
    (pad "2" smd roundrect (at 0.48 0) (size 0.59 0.64) (layers "F.Cu" "F.Paste" "F.Mask") (roundrect_rratio 0.25)
      (net 359 "Net-(C122-Pad2)") (pintype "passive"))
  )

  (footprint "antmicro-footprints:R_0402_1005Metric" (layer "F.Cu")
    (at 88.635 88.7)
    (descr "Resistor SMD 0402")
    (tags "resistor SMD 0402")
    (property "Author" "Antmicro")
    (property "License" "Apache-2.0")
    (property "MPN" "CR0402-FX-1003GLF")
    (property "Manufacturer" "Bourns")
    (property "Public" "False")
    (property "Sheetfile" "power-supply.kicad_sch")
    (property "Sheetname" "Power supply")
    (property "Tolerance" "1%")
    (property "Val" "100k")
    (property "ki_description" "SMD Chip Resistor, 100 kohm, ± 1%, 62.5 mW, 0402 [1005 Metric], Thick Film, General Purpose")
    (property "ki_keywords" "0402, SMT, RESISTOR, PASSIVE")
    (attr smd)
    (fp_text reference "R123" (at -0.235 1.05) (layer "F.SilkS")
        (effects (font (size 0.7 0.7) (thickness 0.127)))
    )
    (fp_text value "R_100k_0402" (at 0 1.17) (layer "F.Fab")
        (effects (font (size 1 1) (thickness 0.15)))
    )
    (fp_text user "${REFERENCE}" (at 0 0) (layer "F.Fab")
        (effects (font (size 0.25 0.25) (thickness 0.04)))
    )
    (fp_text user "License: Apache-2.0" (at -0.95 5.169) (layer "F.Fab") hide
        (effects (font (size 0.7 0.7) (thickness 0.15)) (justify left bottom))
    )
    (fp_text user "Author: Antmicro" (at -0.95 4.169) (layer "F.Fab") hide
        (effects (font (size 0.7 0.7) (thickness 0.15)) (justify left bottom))
    )
    (fp_rect (start -0.925 -0.47) (end 0.925 0.47)
      (stroke (width 0.05) (type default)) (fill none) (layer "F.CrtYd"))
    (fp_rect (start -0.5 -0.25) (end 0.5 0.25)
      (stroke (width 0.15) (type solid)) (fill none) (layer "F.Fab"))
    (pad "1" smd roundrect (at -0.48 0) (size 0.59 0.64) (layers "F.Cu" "F.Paste" "F.Mask") (roundrect_rratio 0.25)
      (net 301 "Net-(U16-FB)") (pintype "passive"))
    (pad "2" smd roundrect (at 0.48 0) (size 0.59 0.64) (layers "F.Cu" "F.Paste" "F.Mask") (roundrect_rratio 0.25)
      (net 1 "GND") (pintype "passive"))
  )

  (footprint "antmicro-footprints:L_Vishay-IHLP-1212AE" (layer "F.Cu")
    (at 91.25 81.55)
    (property "Author" "Antmicro")
    (property "IMax" "6.7 A")
    (property "ISat" "6.7 A")
    (property "License" "Apache-2.0")
    (property "MPN" "IHLP1212AEERR47M11")
    (property "Manufacturer" "Vishay")
    (property "Public" "False")
    (property "Sheetfile" "power-supply.kicad_sch")
    (property "Sheetname" "Power supply")
    (property "Size" "3.0x3.0")
    (property "Val" "470n/6.7A")
    (property "ki_description" "Power Inductor (SMT), 470 nH, 6.7 A, Shielded, 6.7 A")
    (property "ki_keywords" "SMT, INDUCTOR, PASSIVE")
    (attr smd)
    (fp_text reference "L7" (at -2.92 0.145) (layer "F.SilkS")
        (effects (font (size 0.7 0.7) (thickness 0.127)))
    )
    (fp_text value "IHLP1212AEERR47M11" (at 0 0 270) (layer "F.SilkS") hide
        (effects (font (size 1.524 1.524) (thickness 0.05)))
    )
    (fp_text user "License: Apache-2.0" (at -2.35 7.8) (layer "F.Fab") hide
        (effects (font (size 0.7 0.7) (thickness 0.15)) (justify left bottom))
    )
    (fp_text user "${REFERENCE}" (at -2.35 5.4) (layer "F.Fab") hide
        (effects (font (size 0.7 0.7) (thickness 0.15)) (justify left bottom))
    )
    (fp_text user "Author: Antmicro" (at -2.35 6.6) (layer "F.Fab") hide
        (effects (font (size 0.7 0.7) (thickness 0.15)) (justify left bottom))
    )
    (fp_line (start -1.647 -1.6) (end 1.653 -1.6)
      (stroke (width 0.15) (type solid)) (layer "F.SilkS"))
    (fp_line (start -1.647 -0.9) (end -1.647 -1.6)
      (stroke (width 0.15) (type solid)) (layer "F.SilkS"))
    (fp_line (start -1.647 1.6) (end -1.647 0.9)
      (stroke (width 0.15) (type solid)) (layer "F.SilkS"))
    (fp_line (start 1.653 -1.6) (end 1.653 -0.9)
      (stroke (width 0.15) (type solid)) (layer "F.SilkS"))
    (fp_line (start 1.653 0.9) (end 1.653 1.601)
      (stroke (width 0.15) (type solid)) (layer "F.SilkS"))
    (fp_line (start 1.653 1.601) (end -1.647 1.6)
      (stroke (width 0.15) (type solid)) (layer "F.SilkS"))
    (fp_rect (start -2.35 -1.85) (end 2.35 1.85)
      (stroke (width 0.05) (type solid)) (fill none) (layer "F.CrtYd"))
    (fp_rect (start -1.803 -1.601) (end 1.803 1.601)
      (stroke (width 0.15) (type solid)) (fill none) (layer "F.Fab"))
    (pad "1" smd roundrect (at -1.35 0) (size 1.5 1.2) (layers "F.Cu" "F.Paste" "F.Mask") (roundrect_rratio 0.1)
      (net 393 "Net-(U16-SW)") (pintype "passive"))
    (pad "2" smd roundrect (at 1.35 0) (size 1.5 1.2) (layers "F.Cu" "F.Paste" "F.Mask") (roundrect_rratio 0.1)
      (net 359 "Net-(C122-Pad2)") (pintype "passive"))
  )

  (footprint "antmicro-footprints:L_Vishay-IHLP-1212AE" (layer "F.Cu")
    (at 120.139056 79.043104)
    (property "Author" "Antmicro")
    (property "IMax" "6.7 A")
    (property "ISat" "6.7 A")
    (property "License" "Apache-2.0")
    (property "MPN" "IHLP1212AEERR47M11")
    (property "Manufacturer" "Vishay")
    (property "Public" "False")
    (property "Sheetfile" "power-supply.kicad_sch")
    (property "Sheetname" "Power supply")
    (property "Size" "3.0x3.0")
    (property "Val" "470n/6.7A")
    (property "ki_description" "Power Inductor (SMT), 470 nH, 6.7 A, Shielded, 6.7 A")
    (property "ki_keywords" "SMT, INDUCTOR, PASSIVE")
    (attr smd)
    (fp_text reference "L4" (at -2.63 -0.975) (layer "F.SilkS")
        (effects (font (size 0.7 0.7) (thickness 0.127)))
    )
    (fp_text value "IHLP1212AEERR47M11" (at 0 0 270) (layer "F.SilkS") hide
        (effects (font (size 1.524 1.524) (thickness 0.05)))
    )
    (fp_text user "${REFERENCE}" (at -2.35 5.4) (layer "F.Fab") hide
        (effects (font (size 0.7 0.7) (thickness 0.15)) (justify left bottom))
    )
    (fp_text user "License: Apache-2.0" (at -2.35 7.8) (layer "F.Fab") hide
        (effects (font (size 0.7 0.7) (thickness 0.15)) (justify left bottom))
    )
    (fp_text user "Author: Antmicro" (at -2.35 6.6) (layer "F.Fab") hide
        (effects (font (size 0.7 0.7) (thickness 0.15)) (justify left bottom))
    )
    (fp_line (start -1.647 -1.6) (end 1.653 -1.6)
      (stroke (width 0.15) (type solid)) (layer "F.SilkS"))
    (fp_line (start -1.647 -0.9) (end -1.647 -1.6)
      (stroke (width 0.15) (type solid)) (layer "F.SilkS"))
    (fp_line (start -1.647 1.6) (end -1.647 0.9)
      (stroke (width 0.15) (type solid)) (layer "F.SilkS"))
    (fp_line (start 1.653 -1.6) (end 1.653 -0.9)
      (stroke (width 0.15) (type solid)) (layer "F.SilkS"))
    (fp_line (start 1.653 0.9) (end 1.653 1.601)
      (stroke (width 0.15) (type solid)) (layer "F.SilkS"))
    (fp_line (start 1.653 1.601) (end -1.647 1.6)
      (stroke (width 0.15) (type solid)) (layer "F.SilkS"))
    (fp_rect (start -2.35 -1.85) (end 2.35 1.85)
      (stroke (width 0.05) (type solid)) (fill none) (layer "F.CrtYd"))
    (fp_rect (start -1.803 -1.601) (end 1.803 1.601)
      (stroke (width 0.15) (type solid)) (fill none) (layer "F.Fab"))
    (pad "1" smd roundrect (at -1.35 0) (size 1.5 1.2) (layers "F.Cu" "F.Paste" "F.Mask") (roundrect_rratio 0.1)
      (net 390 "Net-(U18-SW)") (pintype "passive"))
    (pad "2" smd roundrect (at 1.35 0) (size 1.5 1.2) (layers "F.Cu" "F.Paste" "F.Mask") (roundrect_rratio 0.1)
      (net 356 "Net-(C119-Pad2)") (pintype "passive"))
  )

  (footprint "antmicro-footprints:R_0402_1005Metric" (layer "F.Cu")
    (at 93.75 76.85)
    (descr "Resistor SMD 0402")
    (tags "resistor SMD 0402")
    (property "Author" "Antmicro")
    (property "License" "Apache-2.0")
    (property "MPN" "CR0402-FX-1002GLF")
    (property "Manufacturer" "Bourns")
    (property "Public" "False")
    (property "Sheetfile" "power-supply.kicad_sch")
    (property "Sheetname" "Power supply")
    (property "Tolerance" "1%")
    (property "Val" "10k")
    (property "ki_description" "SMD Chip Resistor, 10 kohm, ± 1%, 62.5 mW, 0402 [1005 Metric], Thick Film, General Purpose")
    (property "ki_keywords" "0402, SMT, RESISTOR, PASSIVE")
    (attr smd)
    (fp_text reference "R100" (at 1.6 2.165 90) (layer "F.SilkS")
        (effects (font (size 0.7 0.7) (thickness 0.127)))
    )
    (fp_text value "R_10k_0402" (at 0 1.17) (layer "F.Fab")
        (effects (font (size 1 1) (thickness 0.15)))
    )
    (fp_text user "License: Apache-2.0" (at -0.95 5.169) (layer "F.Fab") hide
        (effects (font (size 0.7 0.7) (thickness 0.15)) (justify left bottom))
    )
    (fp_text user "Author: Antmicro" (at -0.95 4.169) (layer "F.Fab") hide
        (effects (font (size 0.7 0.7) (thickness 0.15)) (justify left bottom))
    )
    (fp_text user "${REFERENCE}" (at 0 0) (layer "F.Fab")
        (effects (font (size 0.25 0.25) (thickness 0.04)))
    )
    (fp_rect (start -0.925 -0.47) (end 0.925 0.47)
      (stroke (width 0.05) (type default)) (fill none) (layer "F.CrtYd"))
    (fp_rect (start -0.5 -0.25) (end 0.5 0.25)
      (stroke (width 0.15) (type solid)) (fill none) (layer "F.Fab"))
    (pad "1" smd roundrect (at -0.48 0) (size 0.59 0.64) (layers "F.Cu" "F.Paste" "F.Mask") (roundrect_rratio 0.25)
      (net 289 "Net-(U13-FB)") (pintype "passive"))
    (pad "2" smd roundrect (at 0.48 0) (size 0.59 0.64) (layers "F.Cu" "F.Paste" "F.Mask") (roundrect_rratio 0.25)
      (net 1 "GND") (pintype "passive"))
  )

  (footprint "antmicro-footprints:R_0402_1005Metric" (layer "F.Cu")
    (at 92.8 78.9 180)
    (descr "Resistor SMD 0402")
    (tags "resistor SMD 0402")
    (property "Author" "Antmicro")
    (property "License" "Apache-2.0")
    (property "MPN" "CR0402-FX-4701GLF")
    (property "Manufacturer" "Bourns")
    (property "Public" "False")
    (property "Sheetfile" "power-supply.kicad_sch")
    (property "Sheetname" "Power supply")
    (property "Tolerance" "1%")
    (property "Val" "4k7")
    (property "ki_description" "SMD Chip Resistor, 4.7 kohm, ± 1%, 62.5 mW, 0402 [1005 Metric], Thick Film, General Purpose")
    (property "ki_keywords" "0402, SMT, RESISTOR, PASSIVE")
    (attr smd)
    (fp_text reference "R93" (at -2.03 -2.825) (layer "F.SilkS")
        (effects (font (size 0.7 0.7) (thickness 0.127)))
    )
    (fp_text value "R_4k7_0402" (at 0 1.17) (layer "F.Fab")
        (effects (font (size 1 1) (thickness 0.15)))
    )
    (fp_text user "Author: Antmicro" (at -0.95 4.169 180) (layer "F.Fab") hide
        (effects (font (size 0.7 0.7) (thickness 0.15)) (justify left bottom))
    )
    (fp_text user "License: Apache-2.0" (at -0.95 5.169 180) (layer "F.Fab") hide
        (effects (font (size 0.7 0.7) (thickness 0.15)) (justify left bottom))
    )
    (fp_text user "${REFERENCE}" (at 0 0) (layer "F.Fab")
        (effects (font (size 0.25 0.25) (thickness 0.04)))
    )
    (fp_rect (start -0.925 -0.47) (end 0.925 0.47)
      (stroke (width 0.05) (type default)) (fill none) (layer "F.CrtYd"))
    (fp_rect (start -0.5 -0.25) (end 0.5 0.25)
      (stroke (width 0.15) (type solid)) (fill none) (layer "F.Fab"))
    (pad "1" smd roundrect (at -0.48 0 180) (size 0.59 0.64) (layers "F.Cu" "F.Paste" "F.Mask") (roundrect_rratio 0.25)
      (net 352 "Net-(C106-Pad2)") (pintype "passive"))
    (pad "2" smd roundrect (at 0.48 0 180) (size 0.59 0.64) (layers "F.Cu" "F.Paste" "F.Mask") (roundrect_rratio 0.25)
      (net 289 "Net-(U13-FB)") (pintype "passive"))
  )

  (footprint "antmicro-footprints:PinHeader_1x6_P2.54mm_Drill1.1mm" (layer "F.Cu")
    (at 64.531 104.6)
    (descr "WR-PHD 2.54mm Pin Header, 6 Pin")
    (property "Author" "Antmicro")
    (property "License" "Apache-2.0")
    (property "MPN" "61300611121")
    (property "Manufacturer" "Würth Elektronik")
    (property "Sheetfile" "interfaces.kicad_sch")
    (property "Sheetname" "Interfaces")
    (property "ki_description" "Pin Header, Vertical, Board-to-Board, 2.54 mm, 1 Rows, 6 Contacts, Through Hole Straight, WR-PHD")
    (property "ki_keywords" "VERTICAL, THT, HEADER, CONNECTOR, MALE")
    (attr through_hole)
    (fp_text reference "J7" (at 0.059 3.675 90) (layer "F.SilkS")
        (effects (font (size 0.7 0.7) (thickness 0.127)))
    )
    (fp_text value "PinHeader_1x6_P2.54mm_Drill1.1mm" (at 2.320593 2.138773) (layer "F.Fab")
        (effects (font (size 0.641492 0.641492) (thickness 0.015)))
    )
    (fp_text user "Author: Antmicro" (at -1.5 5.337) (layer "F.Fab") hide
        (effects (font (size 0.7 0.7) (thickness 0.15)) (justify left bottom))
    )
    (fp_text user "License: Apache-2.0" (at -1.5 6.538) (layer "F.Fab") hide
        (effects (font (size 0.7 0.7) (thickness 0.15)) (justify left bottom))
    )
    (fp_text user "${REFERENCE}" (at -1.5 4.137) (layer "F.Fab") hide
        (effects (font (size 0.7 0.7) (thickness 0.15)) (justify left bottom))
    )
    (fp_line (start -1.272 -1.27) (end -1.272 1.269)
      (stroke (width 0.15) (type solid)) (layer "F.SilkS"))
    (fp_line (start -1.272 1.269) (end 13.968 1.269)
      (stroke (width 0.15) (type solid)) (layer "F.SilkS"))
    (fp_line (start 13.968 -1.27) (end -1.272 -1.27)
      (stroke (width 0.15) (type solid)) (layer "F.SilkS"))
    (fp_line (start 13.968 1.269) (end 13.968 -1.27)
      (stroke (width 0.15) (type solid)) (layer "F.SilkS"))
    (fp_line (start -1.5 -1.5) (end 14.18 -1.5)
      (stroke (width 0.05) (type solid)) (layer "F.CrtYd"))
    (fp_line (start -1.5 1.48) (end -1.5 -1.5)
      (stroke (width 0.05) (type solid)) (layer "F.CrtYd"))
    (fp_line (start 14.18 -1.5) (end 14.18 1.48)
      (stroke (width 0.05) (type solid)) (layer "F.CrtYd"))
    (fp_line (start 14.18 1.48) (end -1.5 1.48)
      (stroke (width 0.05) (type solid)) (layer "F.CrtYd"))
    (pad "1" thru_hole circle (at 0 0) (size 1.9 1.9) (drill 1.1) (layers "*.Cu" "*.Mask")
      (net 2 "VCC3V3") (pintype "passive"))
    (pad "2" thru_hole circle (at 2.539 0) (size 1.9 1.9) (drill 1.1) (layers "*.Cu" "*.Mask")
      (net 55 "SPI0_MOSI") (pintype "passive"))
    (pad "3" thru_hole circle (at 5.078 0) (size 1.9 1.9) (drill 1.1) (layers "*.Cu" "*.Mask")
      (net 56 "SPI0_MISO") (pintype "passive"))
    (pad "4" thru_hole circle (at 7.618 0) (size 1.9 1.9) (drill 1.1) (layers "*.Cu" "*.Mask")
      (net 54 "SPI0_CLK") (pintype "passive"))
    (pad "5" thru_hole circle (at 10.159 0) (size 1.9 1.9) (drill 1.1) (layers "*.Cu" "*.Mask")
      (net 53 "SPI0_CS_N") (pintype "passive"))
    (pad "6" thru_hole circle (at 12.698 0) (size 1.9 1.9) (drill 1.1) (layers "*.Cu" "*.Mask")
      (net 1 "GND") (pintype "passive"))
  )

  (footprint "antmicro-footprints:R_0402_1005Metric" (layer "F.Cu")
    (at 127.225 130.525 180)
    (descr "Resistor SMD 0402")
    (tags "resistor SMD 0402")
    (property "Author" "Antmicro")
    (property "License" "Apache-2.0")
    (property "MPN" "CR0402-FX-1202GLF")
    (property "Manufacturer" "Bourns")
    (property "Public" "False")
    (property "Sheetfile" "interfaces.kicad_sch")
    (property "Sheetname" "Interfaces")
    (property "Tolerance" "1%")
    (property "Val" "12k")
    (property "ki_description" "SMD Chip Resistor, 12 kohm, ± 1%, 62.5 mW, 0402 [1005 Metric], Thick Film, General Purpose")
    (property "ki_keywords" "0402, SMT, RESISTOR, PASSIVE")
    (attr smd)
    (fp_text reference "R75" (at -2.605 -0.155) (layer "F.SilkS")
        (effects (font (size 0.7 0.7) (thickness 0.127)))
    )
    (fp_text value "R_12k_0402" (at 0 1.17) (layer "F.Fab")
        (effects (font (size 1 1) (thickness 0.15)))
    )
    (fp_text user "${REFERENCE}" (at 0 0) (layer "F.Fab")
        (effects (font (size 0.25 0.25) (thickness 0.04)))
    )
    (fp_text user "Author: Antmicro" (at -0.95 4.169 180) (layer "F.Fab") hide
        (effects (font (size 0.7 0.7) (thickness 0.15)) (justify left bottom))
    )
    (fp_text user "License: Apache-2.0" (at -0.95 5.169 180) (layer "F.Fab") hide
        (effects (font (size 0.7 0.7) (thickness 0.15)) (justify left bottom))
    )
    (fp_rect (start -0.925 -0.47) (end 0.925 0.47)
      (stroke (width 0.05) (type default)) (fill none) (layer "F.CrtYd"))
    (fp_rect (start -0.5 -0.25) (end 0.5 0.25)
      (stroke (width 0.15) (type solid)) (fill none) (layer "F.Fab"))
    (pad "1" smd roundrect (at -0.48 0 180) (size 0.59 0.64) (layers "F.Cu" "F.Paste" "F.Mask") (roundrect_rratio 0.25)
      (net 1 "GND") (pintype "passive"))
    (pad "2" smd roundrect (at 0.48 0 180) (size 0.59 0.64) (layers "F.Cu" "F.Paste" "F.Mask") (roundrect_rratio 0.25)
      (net 405 "Net-(U8-RBIAS)") (pintype "passive"))
  )

  (footprint "antmicro-footprints:C_0402_1005Metric" (layer "F.Cu")
    (at 128.24 133.74 -90)
    (descr "Capacitor SMD 0402")
    (tags "capacitor SMD 0402")
    (property "Author" "Antmicro")
    (property "Dielectric" "X7R")
    (property "License" "Apache-2.0")
    (property "MPN" "GRM155R71H103KA88D")
    (property "Manufacturer" "Murata")
    (property "Public" "False")
    (property "Sheetfile" "interfaces.kicad_sch")
    (property "Sheetname" "Interfaces")
    (property "Val" "10n")
    (property "Voltage" "50V")
    (property "ki_description" "SMD Multilayer Ceramic Capacitor, 10000 pF, 50 V, 0402 [1005 Metric], ± 10%, X7R, GRM Series")
    (property "ki_keywords" "0402, SMT, CAPACITOR, PASSIVE")
    (attr smd)
    (fp_text reference "C56" (at -0.015 -1.01 90) (layer "F.SilkS")
        (effects (font (size 0.7 0.7) (thickness 0.127)))
    )
    (fp_text value "C_10n_0402" (at 0 1.17 90) (layer "F.Fab")
        (effects (font (size 1 1) (thickness 0.15)))
    )
    (fp_text user "License: Apache-2.0" (at -0.939 5.799 -90) (layer "F.Fab") hide
        (effects (font (size 0.7 0.7) (thickness 0.15)) (justify left bottom))
    )
    (fp_text user "Author: Antmicro" (at -0.939 3.399 -90) (layer "F.Fab") hide
        (effects (font (size 0.7 0.7) (thickness 0.15)) (justify left bottom))
    )
    (fp_text user "${REFERENCE}" (at 0 0 90) (layer "F.Fab")
        (effects (font (size 0.25 0.25) (thickness 0.04)))
    )
    (fp_rect (start -0.925 -0.47) (end 0.925 0.47)
      (stroke (width 0.05) (type default)) (fill none) (layer "F.CrtYd"))
    (fp_line (start -0.494 -0.25) (end 0.504 -0.25)
      (stroke (width 0.15) (type solid)) (layer "F.Fab"))
    (fp_line (start -0.494 0.248) (end -0.494 -0.25)
      (stroke (width 0.15) (type solid)) (layer "F.Fab"))
    (fp_line (start 0.504 -0.25) (end 0.504 0.248)
      (stroke (width 0.15) (type solid)) (layer "F.Fab"))
    (fp_line (start 0.504 0.248) (end -0.494 0.248)
      (stroke (width 0.15) (type solid)) (layer "F.Fab"))
    (pad "1" smd roundrect (at -0.48 0 270) (size 0.59 0.64) (layers "F.Cu" "F.Paste" "F.Mask") (roundrect_rratio 0.25)
      (net 1 "GND") (pintype "passive"))
    (pad "2" smd roundrect (at 0.48 0 270) (size 0.59 0.64) (layers "F.Cu" "F.Paste" "F.Mask") (roundrect_rratio 0.25)
      (net 2 "VCC3V3") (pintype "passive"))
  )

  (footprint "antmicro-footprints:QFN-32-1EP_5x5mm" (layer "F.Cu")
    (at 124.955 126.61 180)
    (property "Author" "Antmicro")
    (property "License" "Apache-2.0")
    (property "MPN" "USB3300-EZK-TR")
    (property "Manufacturer" "Microchip Technology")
    (property "Sheetfile" "interfaces.kicad_sch")
    (property "Sheetname" "Interfaces")
    (property "ki_description" "USB Interface, USB Host Controller, USB 2.0 OTG, 3 V, 3.6 V, VQFN, 32 Pins")
    (property "ki_keywords" "SMT, INTERFACE, CONTROLLER, IC, USB")
    (attr smd)
    (fp_text reference "U8" (at -2.445 3.61 180) (layer "F.SilkS")
        (effects (font (size 0.7 0.7) (thickness 0.12051)))
    )
    (fp_text value "USB3300-EZK-TR" (at 3.23987 3.520501 180) (layer "F.Fab")
        (effects (font (size 0.482094 0.482094) (thickness 0.015)))
    )
    (fp_text user "License: Apache-2.0" (at -4.939 5.91 180) (layer "F.Fab") hide
        (effects (font (size 0.7 0.7) (thickness 0.15)) (justify left bottom))
    )
    (fp_text user "Author: Antmicro" (at -4.939 8.31 180) (layer "F.Fab") hide
        (effects (font (size 0.7 0.7) (thickness 0.15)) (justify left bottom))
    )
    (fp_text user "${REFERENCE}" (at -4.939 7.11 180) (layer "F.Fab") hide
        (effects (font (size 0.7 0.7) (thickness 0.15)) (justify left bottom))
    )
    (fp_rect (start -1.446 -0.175) (end -0.246 -1.375)
      (stroke (width 0.2) (type solid)) (fill solid) (layer "F.Paste"))
    (fp_rect (start -1.446 1.474) (end -0.246 0.274)
      (stroke (width 0.2) (type solid)) (fill solid) (layer "F.Paste"))
    (fp_rect (start 0.203 -0.175) (end 1.403 -1.375)
      (stroke (width 0.2) (type solid)) (fill solid) (layer "F.Paste"))
    (fp_rect (start 0.203 1.474) (end 1.403 0.274)
      (stroke (width 0.2) (type solid)) (fill solid) (layer "F.Paste"))
    (fp_line (start -2.62 2.648) (end -2.62 2.249)
      (stroke (width 0.15) (type solid)) (layer "F.SilkS"))
    (fp_line (start -2.221 -2.551) (end -2.62 -2.149)
      (stroke (width 0.15) (type solid)) (layer "F.SilkS"))
    (fp_line (start -2.221 2.648) (end -2.62 2.648)
      (stroke (width 0.15) (type solid)) (layer "F.SilkS"))
    (fp_line (start 2.581 -2.551) (end 2.178 -2.551)
      (stroke (width 0.15) (type solid)) (layer "F.SilkS"))
    (fp_line (start 2.581 -2.551) (end 2.581 -2.149)
      (stroke (width 0.15) (type solid)) (layer "F.SilkS"))
    (fp_line (start 2.581 2.249) (end 2.581 2.648)
      (stroke (width 0.15) (type solid)) (layer "F.SilkS"))
    (fp_line (start 2.581 2.648) (end 2.178 2.648)
      (stroke (width 0.15) (type solid)) (layer "F.SilkS"))
    (fp_circle (center -3.25 -1.702) (end -3.2 -1.702)
      (stroke (width 0.15) (type solid)) (fill solid) (layer "F.SilkS"))
    (fp_rect (start -2.74 -2.75) (end 2.75 2.74)
      (stroke (width 0.05) (type solid)) (fill none) (layer "F.CrtYd"))
    (fp_line (start -2.499 -2.299) (end -2.298 -2.5)
      (stroke (width 0.15) (type solid)) (layer "F.Fab"))
    (fp_rect (start -2.499 -2.5) (end 2.5 2.499)
      (stroke (width 0.15) (type solid)) (fill none) (layer "F.Fab"))
    (pad "1" smd rect (at -2.495 -1.702 90) (size 0.28 0.85) (layers "F.Cu" "F.Paste" "F.Mask")
      (net 1 "GND") (pinfunction "GND") (pintype "power_in") (solder_mask_margin 0.07))
    (pad "2" smd rect (at -2.495 -1.2 90) (size 0.28 0.85) (layers "F.Cu" "F.Paste" "F.Mask")
      (net 1 "GND") (pinfunction "GND") (pintype "passive") (solder_mask_margin 0.07))
    (pad "3" smd rect (at -2.495 -0.701 90) (size 0.28 0.85) (layers "F.Cu" "F.Paste" "F.Mask")
      (net 496 "unconnected-(U8-CPEN-Pad3)") (pinfunction "CPEN") (pintype "output+no_connect") (solder_mask_margin 0.07))
    (pad "4" smd rect (at -2.495 -0.201 90) (size 0.28 0.85) (layers "F.Cu" "F.Paste" "F.Mask")
      (net 404 "Net-(U8-VBUS)") (pinfunction "VBUS") (pintype "bidirectional") (solder_mask_margin 0.07))
    (pad "5" smd rect (at -2.495 0.296 90) (size 0.28 0.85) (layers "F.Cu" "F.Paste" "F.Mask")
      (net 497 "unconnected-(U8-ID-Pad5)") (pinfunction "ID") (pintype "input+no_connect") (solder_mask_margin 0.07))
    (pad "6" smd rect (at -2.495 0.8 90) (size 0.28 0.85) (layers "F.Cu" "F.Paste" "F.Mask")
      (net 2 "VCC3V3") (pinfunction "VDD3.3") (pintype "power_in") (solder_mask_margin 0.07))
    (pad "7" smd rect (at -2.495 1.3 90) (size 0.28 0.85) (layers "F.Cu" "F.Paste" "F.Mask")
      (net 98 "USB2_DP") (pinfunction "DP") (pintype "bidirectional") (solder_mask_margin 0.07))
    (pad "8" smd rect (at -2.495 1.8 90) (size 0.28 0.85) (layers "F.Cu" "F.Paste" "F.Mask")
      (net 99 "USB2_DN") (pinfunction "DM") (pintype "bidirectional") (solder_mask_margin 0.07))
    (pad "9" smd rect (at -1.768 2.523 90) (size 0.85 0.28) (layers "F.Cu" "F.Paste" "F.Mask")
      (net 317 "ULPI2_RESET") (pinfunction "RESET") (pintype "input") (solder_mask_margin 0.07))
    (pad "10" smd rect (at -1.269 2.523 90) (size 0.85 0.28) (layers "F.Cu" "F.Paste" "F.Mask")
      (net 498 "unconnected-(U8-EXTVBUS-Pad10)") (pinfunction "EXTVBUS") (pintype "input+no_connect") (solder_mask_margin 0.07))
    (pad "11" smd rect (at -0.772 2.523 90) (size 0.85 0.28) (layers "F.Cu" "F.Paste" "F.Mask")
      (net 318 "ULPI2_NXT") (pinfunction "NXT") (pintype "output") (solder_mask_margin 0.07))
    (pad "12" smd rect (at -0.272 2.523 90) (size 0.85 0.28) (layers "F.Cu" "F.Paste" "F.Mask")
      (net 319 "ULPI_DIR") (pinfunction "DIR") (pintype "output") (solder_mask_margin 0.07))
    (pad "13" smd rect (at 0.229 2.523 90) (size 0.85 0.28) (layers "F.Cu" "F.Paste" "F.Mask")
      (net 320 "ULPI2_STP") (pinfunction "STP") (pintype "input") (solder_mask_margin 0.07))
    (pad "14" smd rect (at 0.728 2.523 90) (size 0.85 0.28) (layers "F.Cu" "F.Paste" "F.Mask")
      (net 321 "ULPI2_CLKO") (pinfunction "CLKOUT") (pintype "output") (solder_mask_margin 0.07))
    (pad "15" smd rect (at 1.23 2.523 90) (size 0.85 0.28) (layers "F.Cu" "F.Paste" "F.Mask")
      (net 227 "Net-(C71-Pad1)") (pinfunction "VDD1.8") (pintype "power_in") (solder_mask_margin 0.07))
    (pad "16" smd rect (at 1.73 2.523 90) (size 0.85 0.28) (layers "F.Cu" "F.Paste" "F.Mask")
      (net 2 "VCC3V3") (pinfunction "VDD3.3") (pintype "passive") (solder_mask_margin 0.07))
    (pad "17" smd rect (at 2.456 1.8 90) (size 0.28 0.85) (layers "F.Cu" "F.Paste" "F.Mask")
      (net 322 "ULPI2_D7") (pinfunction "DATA[7]") (pintype "bidirectional") (solder_mask_margin 0.07))
    (pad "18" smd rect (at 2.456 1.3 90) (size 0.28 0.85) (layers "F.Cu" "F.Paste" "F.Mask")
      (net 323 "ULPI2_D6") (pinfunction "DATA[6]") (pintype "bidirectional") (solder_mask_margin 0.07))
    (pad "19" smd rect (at 2.456 0.8 90) (size 0.28 0.85) (layers "F.Cu" "F.Paste" "F.Mask")
      (net 324 "ULPI2_D5") (pinfunction "DATA[5]") (pintype "bidirectional") (solder_mask_margin 0.07))
    (pad "20" smd rect (at 2.456 0.296 90) (size 0.28 0.85) (layers "F.Cu" "F.Paste" "F.Mask")
      (net 325 "ULPI2_D4") (pinfunction "DATA[4]") (pintype "bidirectional") (solder_mask_margin 0.07))
    (pad "21" smd rect (at 2.456 -0.201 90) (size 0.28 0.85) (layers "F.Cu" "F.Paste" "F.Mask")
      (net 326 "ULPI2_D3") (pinfunction "DATA[3]") (pintype "bidirectional") (solder_mask_margin 0.07))
    (pad "22" smd rect (at 2.456 -0.701 90) (size 0.28 0.85) (layers "F.Cu" "F.Paste" "F.Mask")
      (net 327 "ULPI2_D2") (pinfunction "DATA[2]") (pintype "bidirectional") (solder_mask_margin 0.07))
    (pad "23" smd rect (at 2.456 -1.2 90) (size 0.28 0.85) (layers "F.Cu" "F.Paste" "F.Mask")
      (net 328 "ULPI2_D1") (pinfunction "DATA[1]") (pintype "bidirectional") (solder_mask_margin 0.07))
    (pad "24" smd rect (at 2.456 -1.702 90) (size 0.28 0.85) (layers "F.Cu" "F.Paste" "F.Mask")
      (net 329 "ULPI2_D0") (pinfunction "DATA[0]") (pintype "bidirectional") (solder_mask_margin 0.07))
    (pad "25" smd rect (at 1.73 -2.426 90) (size 0.85 0.28) (layers "F.Cu" "F.Paste" "F.Mask")
      (net 2 "VCC3V3") (pinfunction "VDD3.3") (pintype "passive") (solder_mask_margin 0.07))
    (pad "26" smd rect (at 1.23 -2.426 90) (size 0.85 0.28) (layers "F.Cu" "F.Paste" "F.Mask")
      (net 227 "Net-(C71-Pad1)") (pinfunction "VDD1.8") (pintype "passive") (solder_mask_margin 0.07))
    (pad "27" smd rect (at 0.728 -2.426 90) (size 0.85 0.28) (layers "F.Cu" "F.Paste" "F.Mask")
      (net 499 "unconnected-(U8-XO-Pad27)") (pinfunction "XO") (pintype "output+no_connect") (solder_mask_margin 0.07))
    (pad "28" smd rect (at 0.229 -2.426 90) (size 0.85 0.28) (layers "F.Cu" "F.Paste" "F.Mask")
      (net 678 "/Interfaces/USB2_CLK") (pinfunction "XI") (pintype "input") (solder_mask_margin 0.07))
    (pad "29" smd rect (at -0.272 -2.426 90) (size 0.85 0.28) (layers "F.Cu" "F.Paste" "F.Mask")
      (net 221 "Net-(U8-VDDA1.8)") (pinfunction "VDDA1.8") (pintype "power_in") (solder_mask_margin 0.07))
    (pad "30" smd rect (at -0.772 -2.426 90) (size 0.85 0.28) (layers "F.Cu" "F.Paste" "F.Mask")
      (net 2 "VCC3V3") (pinfunction "VDD3.3") (pintype "passive") (solder_mask_margin 0.07))
    (pad "31" smd rect (at -1.269 -2.426 90) (size 0.85 0.28) (layers "F.Cu" "F.Paste" "F.Mask")
      (net 2 "VCC3V3") (pinfunction "REG_EN") (pintype "bidirectional") (solder_mask_margin 0.07))
    (pad "32" smd rect (at -1.768 -2.426 90) (size 0.85 0.28) (layers "F.Cu" "F.Paste" "F.Mask")
      (net 405 "Net-(U8-RBIAS)") (pinfunction "RBIAS") (pintype "bidirectional") (solder_mask_margin 0.07))
    (pad "33" smd rect (at -0.02 0.048 90) (size 3.45 3.45) (layers "F.Cu" "F.Mask")
      (net 1 "GND") (pinfunction "EP") (pintype "passive"))
  )

  (footprint "antmicro-footprints:TP_SMD_1mm" (layer "F.Cu")
    (at 115.270001 158.864201 180)
    (property "Author" "Antmicro")
    (property "License" "Apache-2.0")
    (property "MPN" "")
    (property "Manufacturer" "")
    (property "Sheetfile" "pcie-conn.kicad_sch")
    (property "Sheetname" "PCIe-connector")
    (property "exclude_from_bom" "")
    (property "ki_description" "Test point 1mm SMD")
    (property "ki_keywords" "TESTPOINT")
    (attr exclude_from_pos_files exclude_from_bom)
    (fp_text reference "TP2" (at 2.640001 -0.4158 180) (layer "F.SilkS")
        (effects (font (size 0.7 0.7) (thickness 0.15)) (justify left bottom))
    )
    (fp_text value "TP_1mm_SMD" (at 0 1.4 180) (layer "F.Fab")
        (effects (font (size 0.7 0.7) (thickness 0.15)) (justify left bottom))
    )
    (fp_text user "Author: Antmicro" (at -0.5 4 180) (layer "F.Fab") hide
        (effects (font (size 0.7 0.7) (thickness 0.15)) (justify left bottom))
    )
    (fp_text user "${REFERENCE}" (at -0.5 2.8 180) (layer "F.Fab") hide
        (effects (font (size 0.7 0.7) (thickness 0.15)) (justify left bottom))
    )
    (fp_text user "License: Apache-2.0" (at -0.5 5.2 180) (layer "F.Fab") hide
        (effects (font (size 0.7 0.7) (thickness 0.15)) (justify left bottom))
    )
    (fp_circle (center 0 0) (end 0.6 0)
      (stroke (width 0.05) (type default)) (fill none) (layer "F.CrtYd"))
    (pad "1" smd circle (at 0 0 180) (size 1 1) (layers "F.Cu" "F.Mask")
      (net 380 "Net-(J2-~{CLKREQ})") (pinfunction "1") (pintype "passive"))
  )

  (footprint "antmicro-footprints:TP_SMD_1mm" (layer "F.Cu")
    (at 115.270001 160.806701 180)
    (property "Author" "Antmicro")
    (property "License" "Apache-2.0")
    (property "MPN" "")
    (property "Manufacturer" "")
    (property "Sheetfile" "pcie-conn.kicad_sch")
    (property "Sheetname" "PCIe-connector")
    (property "exclude_from_bom" "")
    (property "ki_description" "Test point 1mm SMD")
    (property "ki_keywords" "TESTPOINT")
    (attr exclude_from_pos_files exclude_from_bom)
    (fp_text reference "TP3" (at 2.640001 -0.4158 180) (layer "F.SilkS")
        (effects (font (size 0.7 0.7) (thickness 0.15)) (justify left bottom))
    )
    (fp_text value "TP_1mm_SMD" (at 0 1.4 180) (layer "F.Fab")
        (effects (font (size 0.7 0.7) (thickness 0.15)) (justify left bottom))
    )
    (fp_text user "License: Apache-2.0" (at -0.5 5.2 180) (layer "F.Fab") hide
        (effects (font (size 0.7 0.7) (thickness 0.15)) (justify left bottom))
    )
    (fp_text user "${REFERENCE}" (at -0.5 2.8 180) (layer "F.Fab") hide
        (effects (font (size 0.7 0.7) (thickness 0.15)) (justify left bottom))
    )
    (fp_text user "Author: Antmicro" (at -0.5 4 180) (layer "F.Fab") hide
        (effects (font (size 0.7 0.7) (thickness 0.15)) (justify left bottom))
    )
    (fp_circle (center 0 0) (end 0.6 0)
      (stroke (width 0.05) (type default)) (fill none) (layer "F.CrtYd"))
    (pad "1" smd circle (at 0 0 180) (size 1 1) (layers "F.Cu" "F.Mask")
      (net 58 "PRSNT0_N") (pinfunction "1") (pintype "passive"))
  )

  (footprint "antmicro-footprints:TP_SMD_1mm" (layer "F.Cu")
    (at 86.1 69.6008)
    (property "Author" "Antmicro")
    (property "License" "Apache-2.0")
    (property "MPN" "")
    (property "Manufacturer" "")
    (property "Sheetfile" "power-supply.kicad_sch")
    (property "Sheetname" "Power supply")
    (property "exclude_from_bom" "")
    (property "ki_description" "Test point 1mm SMD")
    (property "ki_keywords" "TESTPOINT")
    (attr exclude_from_pos_files exclude_from_bom)
    (fp_text reference "TP6" (at -0.91 1.7742 180) (layer "F.SilkS")
        (effects (font (size 0.7 0.7) (thickness 0.15)) (justify left bottom))
    )
    (fp_text value "TP_1mm_SMD" (at 0 1.4) (layer "F.Fab")
        (effects (font (size 0.7 0.7) (thickness 0.15)) (justify left bottom))
    )
    (fp_text user "Author: Antmicro" (at -0.5 4) (layer "F.Fab") hide
        (effects (font (size 0.7 0.7) (thickness 0.15)) (justify left bottom))
    )
    (fp_text user "${REFERENCE}" (at -0.5 2.8) (layer "F.Fab") hide
        (effects (font (size 0.7 0.7) (thickness 0.15)) (justify left bottom))
    )
    (fp_text user "License: Apache-2.0" (at -0.5 5.2) (layer "F.Fab") hide
        (effects (font (size 0.7 0.7) (thickness 0.15)) (justify left bottom))
    )
    (fp_circle (center 0 0) (end 0.6 0)
      (stroke (width 0.05) (type default)) (fill none) (layer "F.CrtYd"))
    (pad "1" smd circle (at 0 0) (size 1 1) (layers "F.Cu" "F.Mask")
      (net 785 "Net-(U15-EN)") (pinfunction "1") (pintype "passive"))
  )

  (footprint "antmicro-footprints:TP_SMD_1mm" (layer "F.Cu")
    (at 83.95 69.6)
    (property "Author" "Antmicro")
    (property "License" "Apache-2.0")
    (property "MPN" "")
    (property "Manufacturer" "")
    (property "Sheetfile" "power-supply.kicad_sch")
    (property "Sheetname" "Power supply")
    (property "exclude_from_bom" "")
    (property "ki_description" "Test point 1mm SMD")
    (property "ki_keywords" "TESTPOINT")
    (attr exclude_from_pos_files exclude_from_bom)
    (fp_text reference "TP12" (at -1.63 1.735) (layer "F.SilkS")
        (effects (font (size 0.7 0.7) (thickness 0.15)) (justify left bottom))
    )
    (fp_text value "TP_1mm_SMD" (at 0 1.4) (layer "F.Fab")
        (effects (font (size 0.7 0.7) (thickness 0.15)) (justify left bottom))
    )
    (fp_text user "Author: Antmicro" (at -0.5 4) (layer "F.Fab") hide
        (effects (font (size 0.7 0.7) (thickness 0.15)) (justify left bottom))
    )
    (fp_text user "${REFERENCE}" (at -0.5 2.8) (layer "F.Fab") hide
        (effects (font (size 0.7 0.7) (thickness 0.15)) (justify left bottom))
    )
    (fp_text user "License: Apache-2.0" (at -0.5 5.2) (layer "F.Fab") hide
        (effects (font (size 0.7 0.7) (thickness 0.15)) (justify left bottom))
    )
    (fp_circle (center 0 0) (end 0.6 0)
      (stroke (width 0.05) (type default)) (fill none) (layer "F.CrtYd"))
    (pad "1" smd circle (at 0 0) (size 1 1) (layers "F.Cu" "F.Mask")
      (net 270 "/Power supply/5V0_PG") (pinfunction "1") (pintype "passive"))
  )

  (footprint "antmicro-footprints:C_0402_1005Metric" (layer "F.Cu")
    (at 93.15 61.735 -90)
    (descr "Capacitor SMD 0402")
    (tags "capacitor SMD 0402")
    (property "Author" "Antmicro")
    (property "Dielectric" "X5R")
    (property "License" "Apache-2.0")
    (property "MPN" "GRM155R61H104KE14D")
    (property "Manufacturer" "Murata")
    (property "Public" "False")
    (property "Sheetfile" "power-supply.kicad_sch")
    (property "Sheetname" "Power supply")
    (property "Val" "100n")
    (property "Voltage" "50V")
    (property "ki_description" "SMD Multilayer Ceramic Capacitor, 0.1 µF, 50 V, 0402 [1005 Metric], ± 10%, X5R, GRM Series")
    (property "ki_keywords" "0402, SMT, CAPACITOR, PASSIVE, CERAMIC, MLCC")
    (attr smd)
    (fp_text reference "C100" (at -0.48 -1.94 -90) (layer "F.SilkS")
        (effects (font (size 0.7 0.7) (thickness 0.127)))
    )
    (fp_text value "C_100n_0402" (at 0 1.17 90) (layer "F.Fab")
        (effects (font (size 1 1) (thickness 0.15)))
    )
    (fp_text user "${REFERENCE}" (at 0 0 90) (layer "F.Fab")
        (effects (font (size 0.25 0.25) (thickness 0.04)))
    )
    (fp_text user "Author: Antmicro" (at -0.939 3.399 -90) (layer "F.Fab") hide
        (effects (font (size 0.7 0.7) (thickness 0.15)) (justify left bottom))
    )
    (fp_text user "License: Apache-2.0" (at -0.939 5.799 -90) (layer "F.Fab") hide
        (effects (font (size 0.7 0.7) (thickness 0.15)) (justify left bottom))
    )
    (fp_rect (start -0.925 -0.47) (end 0.925 0.47)
      (stroke (width 0.05) (type default)) (fill none) (layer "F.CrtYd"))
    (fp_line (start -0.494 -0.25) (end 0.504 -0.25)
      (stroke (width 0.15) (type solid)) (layer "F.Fab"))
    (fp_line (start -0.494 0.248) (end -0.494 -0.25)
      (stroke (width 0.15) (type solid)) (layer "F.Fab"))
    (fp_line (start 0.504 -0.25) (end 0.504 0.248)
      (stroke (width 0.15) (type solid)) (layer "F.Fab"))
    (fp_line (start 0.504 0.248) (end -0.494 0.248)
      (stroke (width 0.15) (type solid)) (layer "F.Fab"))
    (pad "1" smd roundrect (at -0.48 0 270) (size 0.59 0.64) (layers "F.Cu" "F.Paste" "F.Mask") (roundrect_rratio 0.25)
      (net 1 "GND") (pintype "passive"))
    (pad "2" smd roundrect (at 0.48 0 270) (size 0.59 0.64) (layers "F.Cu" "F.Paste" "F.Mask") (roundrect_rratio 0.25)
      (net 232 "Net-(U13-AVIN)") (pintype "passive"))
  )

  (footprint "antmicro-footprints:R_0603_1608Metric" (layer "F.Cu")
    (at 91.95 61.55 -90)
    (descr "Resistor SMD 0603")
    (tags "resistor SMD 0603")
    (property "Author" "Antmicro")
    (property "License" "Apache-2.0")
    (property "MPN" "CR0603-FX-10R0ELF")
    (property "Manufacturer" "Bourns")
    (property "Public" "False")
    (property "Sheetfile" "power-supply.kicad_sch")
    (property "Sheetname" "Power supply")
    (property "Tolerance" "1%")
    (property "Val" "10R")
    (property "ki_description" "SMD Chip Resistor, 10 ohm, ± 1%, 100 mW, 0603 [1608 Metric], Thick Film, General Purpose")
    (property "ki_keywords" "0603, SMT, RESISTOR, PASSIVE")
    (attr smd)
    (fp_text reference "R88" (at 1.995 -3.2 -90) (layer "F.SilkS")
        (effects (font (size 0.7 0.7) (thickness 0.127)))
    )
    (fp_text value "R_10R_0603" (at 0 1.9 90) (layer "F.Fab")
        (effects (font (size 1 1) (thickness 0.15)))
    )
    (fp_text user "License: Apache-2.0" (at -1.25 5.9 -90) (layer "F.Fab") hide
        (effects (font (size 0.7 0.7) (thickness 0.15)) (justify left bottom))
    )
    (fp_text user "${REFERENCE}" (at -1.25 3.898 -90) (layer "F.Fab") hide
        (effects (font (size 0.7 0.7) (thickness 0.15)) (justify left bottom))
    )
    (fp_text user "Author: Antmicro" (at -1.25 4.9 -90) (layer "F.Fab") hide
        (effects (font (size 0.7 0.7) (thickness 0.15)) (justify left bottom))
    )
    (fp_line (start -0.15 -0.4) (end 0.15 -0.4)
      (stroke (width 0.15) (type solid)) (layer "F.SilkS"))
    (fp_line (start -0.15 0.4) (end 0.15 0.4)
      (stroke (width 0.15) (type solid)) (layer "F.SilkS"))
    (fp_rect (start -1.25 -0.65) (end 1.25 0.65)
      (stroke (width 0.05) (type solid)) (fill none) (layer "F.CrtYd"))
    (fp_rect (start -0.8 -0.4) (end 0.8 0.4)
      (stroke (width 0.15) (type solid)) (fill none) (layer "F.Fab"))
    (pad "1" smd roundrect (at -0.7 0 270) (size 0.8 1) (layers "F.Cu" "F.Paste" "F.Mask") (roundrect_rratio 0.2)
      (net 11 "VCC5V0") (pintype "passive"))
    (pad "2" smd roundrect (at 0.7 0 270) (size 0.8 1) (layers "F.Cu" "F.Paste" "F.Mask") (roundrect_rratio 0.2)
      (net 232 "Net-(U13-AVIN)") (pintype "passive"))
  )

  (footprint "antmicro-footprints:C_0805_2012Metric" (layer "F.Cu")
    (at 89.31 62.295)
    (descr "Capacitor SMD 0805")
    (tags "capacitor SMD 0805")
    (property "Author" "Antmicro")
    (property "Dielectric" "")
    (property "License" "Apache-2.0")
    (property "MPN" "160R15X106KV4E")
    (property "Manufacturer" "Johanson Technology")
    (property "Public" "False")
    (property "Sheetfile" "power-supply.kicad_sch")
    (property "Sheetname" "Power supply")
    (property "Val" "10u")
    (property "Voltage" "")
    (property "ki_description" "SMD Multilayer Ceramic Capacitor, TANCERAM®, 10 µF, 16 V, 0805 [2012 Metric], ± 10%, X5R")
    (property "ki_keywords" "0805, SMT, CAPACITOR, PASSIVE")
    (attr smd)
    (fp_text reference "C96" (at 2.94 0.985 180) (layer "F.SilkS")
        (effects (font (size 0.7 0.7) (thickness 0.127)))
    )
    (fp_text value "C_10u_0805" (at 0 1.95) (layer "F.Fab")
        (effects (font (size 1 1) (thickness 0.15)))
    )
    (fp_text user "Author: Antmicro" (at -1.9 5.947) (layer "F.Fab") hide
        (effects (font (size 0.7 0.7) (thickness 0.15)) (justify left bottom))
    )
    (fp_text user "${REFERENCE}" (at -1.9 3.947) (layer "F.Fab") hide
        (effects (font (size 0.7 0.7) (thickness 0.15)) (justify left bottom))
    )
    (fp_text user "License: Apache-2.0" (at -1.9 4.947) (layer "F.Fab") hide
        (effects (font (size 0.7 0.7) (thickness 0.15)) (justify left bottom))
    )
    (fp_line (start -0.3 -0.7) (end 0.3 -0.7)
      (stroke (width 0.15) (type solid)) (layer "F.SilkS"))
    (fp_line (start -0.3 0.7) (end 0.3 0.7)
      (stroke (width 0.15) (type solid)) (layer "F.SilkS"))
    (fp_rect (start 1.95 -0.9) (end -1.95 0.9)
      (stroke (width 0.05) (type default)) (fill none) (layer "F.CrtYd"))
    (fp_rect (start -0.95 -0.675) (end 0.95 0.675)
      (stroke (width 0.15) (type solid)) (fill none) (layer "F.Fab"))
    (pad "1" smd roundrect (at -1.1 0) (size 1.2 1.3) (layers "F.Cu" "F.Paste" "F.Mask") (roundrect_rratio 0.25)
      (net 1 "GND") (pintype "passive"))
    (pad "2" smd roundrect (at 1.1 0) (size 1.2 1.3) (layers "F.Cu" "F.Paste" "F.Mask") (roundrect_rratio 0.25)
      (net 11 "VCC5V0") (pintype "passive"))
  )

  (footprint "antmicro-footprints:C_0805_2012Metric" (layer "F.Cu")
    (at 89.31 60.245)
    (descr "Capacitor SMD 0805")
    (tags "capacitor SMD 0805")
    (property "Author" "Antmicro")
    (property "Dielectric" "")
    (property "License" "Apache-2.0")
    (property "MPN" "160R15X106KV4E")
    (property "Manufacturer" "Johanson Technology")
    (property "Public" "False")
    (property "Sheetfile" "power-supply.kicad_sch")
    (property "Sheetname" "Power supply")
    (property "Val" "10u")
    (property "Voltage" "")
    (property "ki_description" "SMD Multilayer Ceramic Capacitor, TANCERAM®, 10 µF, 16 V, 0805 [2012 Metric], ± 10%, X5R")
    (property "ki_keywords" "0805, SMT, CAPACITOR, PASSIVE")
    (attr smd)
    (fp_text reference "C97" (at 2.72 -0.695 180) (layer "F.SilkS")
        (effects (font (size 0.7 0.7) (thickness 0.127)))
    )
    (fp_text value "C_10u_0805" (at 0 1.95) (layer "F.Fab")
        (effects (font (size 1 1) (thickness 0.15)))
    )
    (fp_text user "License: Apache-2.0" (at -1.9 4.947) (layer "F.Fab") hide
        (effects (font (size 0.7 0.7) (thickness 0.15)) (justify left bottom))
    )
    (fp_text user "${REFERENCE}" (at -1.9 3.947) (layer "F.Fab") hide
        (effects (font (size 0.7 0.7) (thickness 0.15)) (justify left bottom))
    )
    (fp_text user "Author: Antmicro" (at -1.9 5.947) (layer "F.Fab") hide
        (effects (font (size 0.7 0.7) (thickness 0.15)) (justify left bottom))
    )
    (fp_line (start -0.3 -0.7) (end 0.3 -0.7)
      (stroke (width 0.15) (type solid)) (layer "F.SilkS"))
    (fp_line (start -0.3 0.7) (end 0.3 0.7)
      (stroke (width 0.15) (type solid)) (layer "F.SilkS"))
    (fp_rect (start 1.95 -0.9) (end -1.95 0.9)
      (stroke (width 0.05) (type default)) (fill none) (layer "F.CrtYd"))
    (fp_rect (start -0.95 -0.675) (end 0.95 0.675)
      (stroke (width 0.15) (type solid)) (fill none) (layer "F.Fab"))
    (pad "1" smd roundrect (at -1.1 0) (size 1.2 1.3) (layers "F.Cu" "F.Paste" "F.Mask") (roundrect_rratio 0.25)
      (net 1 "GND") (pintype "passive"))
    (pad "2" smd roundrect (at 1.1 0) (size 1.2 1.3) (layers "F.Cu" "F.Paste" "F.Mask") (roundrect_rratio 0.25)
      (net 11 "VCC5V0") (pintype "passive"))
  )

  (footprint "antmicro-footprints:C_0402_1005Metric" (layer "F.Cu")
    (at 87.4 143.05 -90)
    (descr "Capacitor SMD 0402")
    (tags "capacitor SMD 0402")
    (property "Author" "Antmicro")
    (property "Dielectric" "X5R")
    (property "License" "Apache-2.0")
    (property "MPN" "GRM155R61H104KE14D")
    (property "Manufacturer" "Murata")
    (property "Public" "False")
    (property "Sheetfile" "interfaces.kicad_sch")
    (property "Sheetname" "Interfaces")
    (property "Val" "100n")
    (property "Voltage" "50V")
    (property "ki_description" "SMD Multilayer Ceramic Capacitor, 0.1 µF, 50 V, 0402 [1005 Metric], ± 10%, X5R, GRM Series")
    (property "ki_keywords" "0402, SMT, CAPACITOR, PASSIVE, CERAMIC, MLCC")
    (attr smd)
    (fp_text reference "C248" (at -2.31 -0.1 90) (layer "F.SilkS")
        (effects (font (size 0.7 0.7) (thickness 0.127)))
    )
    (fp_text value "C_100n_0402" (at 0 1.17 90) (layer "F.Fab")
        (effects (font (size 1 1) (thickness 0.15)))
    )
    (fp_text user "License: Apache-2.0" (at -0.939 5.799 -90) (layer "F.Fab") hide
        (effects (font (size 0.7 0.7) (thickness 0.15)) (justify left bottom))
    )
    (fp_text user "Author: Antmicro" (at -0.939 3.399 -90) (layer "F.Fab") hide
        (effects (font (size 0.7 0.7) (thickness 0.15)) (justify left bottom))
    )
    (fp_text user "${REFERENCE}" (at 0 0 90) (layer "F.Fab")
        (effects (font (size 0.25 0.25) (thickness 0.04)))
    )
    (fp_rect (start -0.925 -0.47) (end 0.925 0.47)
      (stroke (width 0.05) (type default)) (fill none) (layer "F.CrtYd"))
    (fp_line (start -0.494 -0.25) (end 0.504 -0.25)
      (stroke (width 0.15) (type solid)) (layer "F.Fab"))
    (fp_line (start -0.494 0.248) (end -0.494 -0.25)
      (stroke (width 0.15) (type solid)) (layer "F.Fab"))
    (fp_line (start 0.504 -0.25) (end 0.504 0.248)
      (stroke (width 0.15) (type solid)) (layer "F.Fab"))
    (fp_line (start 0.504 0.248) (end -0.494 0.248)
      (stroke (width 0.15) (type solid)) (layer "F.Fab"))
    (pad "1" smd roundrect (at -0.48 0 270) (size 0.59 0.64) (layers "F.Cu" "F.Paste" "F.Mask") (roundrect_rratio 0.25)
      (net 1 "GND") (pintype "passive"))
    (pad "2" smd roundrect (at 0.48 0 270) (size 0.59 0.64) (layers "F.Cu" "F.Paste" "F.Mask") (roundrect_rratio 0.25)
      (net 12 "VCC1V0") (pintype "passive"))
  )

  (footprint "antmicro-footprints:SW_B3U-1000P_SMD" (layer "F.Cu")
    (at 71.65 94.75)
    (property "Author" "Antmicro")
    (property "License" "Apache-2.0")
    (property "MPN" "B3U-1000P")
    (property "Manufacturer" "Omron")
    (property "Sheetfile" "fpga-banks.kicad_sch")
    (property "Sheetname" "FPGA banks")
    (property "ki_description" "Tactile Switch, B3U, Top Actuated, Surface Mount, Round Button, 153 gf, 50mA at 12VDC")
    (property "ki_keywords" "VERTICAL, SMT, SWITCH, MECHANICAL, TACTILE")
    (attr smd)
    (fp_text reference "SW1" (at -3.125 1.3) (layer "F.SilkS")
        (effects (font (size 0.7 0.7) (thickness 0.127)))
    )
    (fp_text value "SW_B3U-1000P_SMD" (at 0 2.63) (layer "F.Fab")
        (effects (font (size 1 1) (thickness 0.15)))
    )
    (fp_text user "Author: Antmicro" (at -2.249 5.7) (layer "F.Fab") hide
        (effects (font (size 0.7 0.7) (thickness 0.15)) (justify left bottom))
    )
    (fp_text user "${REFERENCE}" (at 0 0) (layer "F.Fab")
        (effects (font (size 0.5 0.5) (thickness 0.05)))
    )
    (fp_text user "License: Apache-2.0" (at -2.249 6.9) (layer "F.Fab") hide
        (effects (font (size 0.7 0.7) (thickness 0.15)) (justify left bottom))
    )
    (fp_line (start -1.601 -0.95) (end -2 -0.95)
      (stroke (width 0.15) (type solid)) (layer "F.SilkS"))
    (fp_line (start -1.6 -1.4) (end -1.601 -0.95)
      (stroke (width 0.15) (type solid)) (layer "F.SilkS"))
    (fp_line (start -1.6 -1.4) (end -1.1 -1.4)
      (stroke (width 0.15) (type solid)) (layer "F.SilkS"))
    (fp_line (start -1.6 1.4) (end -1.6 0.95)
      (stroke (width 0.15) (type solid)) (layer "F.SilkS"))
    (fp_line (start -1.6 1.4) (end -1.1 1.4)
      (stroke (width 0.15) (type solid)) (layer "F.SilkS"))
    (fp_line (start 1.6 -1.4) (end 1.1 -1.4)
      (stroke (width 0.15) (type solid)) (layer "F.SilkS"))
    (fp_line (start 1.6 -1.4) (end 1.6 -0.95)
      (stroke (width 0.15) (type solid)) (layer "F.SilkS"))
    (fp_line (start 1.6 1.4) (end 1.1 1.4)
      (stroke (width 0.15) (type solid)) (layer "F.SilkS"))
    (fp_line (start 1.6 1.4) (end 1.6 0.95)
      (stroke (width 0.15) (type solid)) (layer "F.SilkS"))
    (fp_rect (start -2.249 -1.55) (end 2.25 1.549)
      (stroke (width 0.05) (type solid)) (fill none) (layer "F.CrtYd"))
    (fp_rect (start -1.5 -1.29) (end 1.499 1.289)
      (stroke (width 0.15) (type solid)) (fill none) (layer "F.Fab"))
    (pad "1" smd rect (at -1.7 0) (size 0.8 1.7) (layers "F.Cu" "F.Paste" "F.Mask")
      (net 268 "PROGRAM_N") (pinfunction "1") (pintype "passive"))
    (pad "2" smd rect (at 1.699 0) (size 0.8 1.7) (layers "F.Cu" "F.Paste" "F.Mask")
      (net 1 "GND") (pinfunction "2") (pintype "passive"))
  )

  (footprint "antmicro-footprints:R_0402_1005Metric" (layer "F.Cu")
    (at 78.24 73.64 -90)
    (descr "Resistor SMD 0402")
    (tags "resistor SMD 0402")
    (property "Author" "Antmicro")
    (property "License" "Apache-2.0")
    (property "MPN" "CR0402-FX-1003GLF")
    (property "Manufacturer" "Bourns")
    (property "Public" "False")
    (property "Sheetfile" "power-supply.kicad_sch")
    (property "Sheetname" "Power supply")
    (property "Tolerance" "1%")
    (property "Val" "100k")
    (property "ki_description" "SMD Chip Resistor, 100 kohm, ± 1%, 62.5 mW, 0402 [1005 Metric], Thick Film, General Purpose")
    (property "ki_keywords" "0402, SMT, RESISTOR, PASSIVE")
    (attr smd)
    (fp_text reference "R86" (at -2.45 4.9 -90) (layer "F.SilkS")
        (effects (font (size 0.7 0.7) (thickness 0.127)))
    )
    (fp_text value "R_100k_0402" (at 0 1.17 -90) (layer "F.Fab")
        (effects (font (size 1 1) (thickness 0.15)))
    )
    (fp_text user "License: Apache-2.0" (at -0.95 5.169 -90) (layer "F.Fab") hide
        (effects (font (size 0.7 0.7) (thickness 0.15)) (justify left bottom))
    )
    (fp_text user "Author: Antmicro" (at -0.95 4.169 -90) (layer "F.Fab") hide
        (effects (font (size 0.7 0.7) (thickness 0.15)) (justify left bottom))
    )
    (fp_text user "${REFERENCE}" (at 0 0 -90) (layer "F.Fab")
        (effects (font (size 0.25 0.25) (thickness 0.04)))
    )
    (fp_rect (start -0.925 -0.47) (end 0.925 0.47)
      (stroke (width 0.05) (type default)) (fill none) (layer "F.CrtYd"))
    (fp_rect (start -0.5 -0.25) (end 0.5 0.25)
      (stroke (width 0.15) (type solid)) (fill none) (layer "F.Fab"))
    (pad "1" smd roundrect (at -0.48 0 270) (size 0.59 0.64) (layers "F.Cu" "F.Paste" "F.Mask") (roundrect_rratio 0.25)
      (net 11 "VCC5V0") (pintype "passive"))
    (pad "2" smd roundrect (at 0.48 0 270) (size 0.59 0.64) (layers "F.Cu" "F.Paste" "F.Mask") (roundrect_rratio 0.25)
      (net 420 "Net-(U12-FLAG2)") (pintype "passive"))
  )

  (footprint "antmicro-footprints:R_0402_1005Metric" (layer "F.Cu")
    (at 77.24 73.64 -90)
    (descr "Resistor SMD 0402")
    (tags "resistor SMD 0402")
    (property "Author" "Antmicro")
    (property "License" "Apache-2.0")
    (property "MPN" "CR0402-FX-1003GLF")
    (property "Manufacturer" "Bourns")
    (property "Public" "False")
    (property "Sheetfile" "power-supply.kicad_sch")
    (property "Sheetname" "Power supply")
    (property "Tolerance" "1%")
    (property "Val" "100k")
    (property "ki_description" "SMD Chip Resistor, 100 kohm, ± 1%, 62.5 mW, 0402 [1005 Metric], Thick Film, General Purpose")
    (property "ki_keywords" "0402, SMT, RESISTOR, PASSIVE")
    (attr smd)
    (fp_text reference "R87" (at -2.45 4.9 -90) (layer "F.SilkS")
        (effects (font (size 0.7 0.7) (thickness 0.127)))
    )
    (fp_text value "R_100k_0402" (at 0 1.17 -90) (layer "F.Fab")
        (effects (font (size 1 1) (thickness 0.15)))
    )
    (fp_text user "${REFERENCE}" (at 0 0 -90) (layer "F.Fab")
        (effects (font (size 0.25 0.25) (thickness 0.04)))
    )
    (fp_text user "License: Apache-2.0" (at -0.95 5.169 -90) (layer "F.Fab") hide
        (effects (font (size 0.7 0.7) (thickness 0.15)) (justify left bottom))
    )
    (fp_text user "Author: Antmicro" (at -0.95 4.169 -90) (layer "F.Fab") hide
        (effects (font (size 0.7 0.7) (thickness 0.15)) (justify left bottom))
    )
    (fp_rect (start -0.925 -0.47) (end 0.925 0.47)
      (stroke (width 0.05) (type default)) (fill none) (layer "F.CrtYd"))
    (fp_rect (start -0.5 -0.25) (end 0.5 0.25)
      (stroke (width 0.15) (type solid)) (fill none) (layer "F.Fab"))
    (pad "1" smd roundrect (at -0.48 0 270) (size 0.59 0.64) (layers "F.Cu" "F.Paste" "F.Mask") (roundrect_rratio 0.25)
      (net 11 "VCC5V0") (pintype "passive"))
    (pad "2" smd roundrect (at 0.48 0 270) (size 0.59 0.64) (layers "F.Cu" "F.Paste" "F.Mask") (roundrect_rratio 0.25)
      (net 422 "Net-(U12-FLAG3)") (pintype "passive"))
  )

  (footprint "antmicro-footprints:L_WE-PDF-1064" (layer "F.Cu")
    (at 70.75 69.5 -90)
    (property "Author" "Antmicro")
    (property "IMax" "7.9 A")
    (property "ISat" "6 A")
    (property "License" "Apache-2.0")
    (property "MPN" "7447798720")
    (property "Manufacturer" "Würth Elektronik")
    (property "Public" "False")
    (property "Sheetfile" "power-supply.kicad_sch")
    (property "Sheetname" "Power supply")
    (property "Size" "10.2x10.2")
    (property "Val" "7u2/7.9A")
    (property "ki_description" "Power Inductor (SMD), 7.2 µH, 7.9 A, Shielded, 6 A, WE-PDF")
    (property "ki_keywords" "INDUCTOR, PASSIVE, SMT")
    (attr smd)
    (fp_text reference "L2" (at -5.745 4.38) (layer "F.SilkS")
        (effects (font (size 0.7 0.7) (thickness 0.127)))
    )
    (fp_text value "WE_7447798720" (at 0 0) (layer "F.SilkS") hide
        (effects (font (size 1.524 1.524) (thickness 0.05)))
    )
    (fp_text user "WE_7447798720" (at 0 0) (layer "F.SilkS") hide
        (effects (font (size 1.524 1.524) (thickness 0.05)))
    )
    (fp_text user "${REFERENCE}" (at -5.6 11 -90) (layer "F.Fab") hide
        (effects (font (size 0.7 0.7) (thickness 0.15)) (justify left bottom))
    )
    (fp_text user "Author: Antmicro" (at -5.6 9.8 -90) (layer "F.Fab") hide
        (effects (font (size 0.7 0.7) (thickness 0.15)) (justify left bottom))
    )
    (fp_text user "License: Apache-2.0" (at -5.6 8.6 -90) (layer "F.Fab") hide
        (effects (font (size 0.7 0.7) (thickness 0.15)) (justify left bottom))
    )
    (fp_line (start -5.225 -5.225) (end 4.125 -5.225)
      (stroke (width 0.15) (type solid)) (layer "F.SilkS"))
    (fp_line (start -5.225 -1.925) (end -5.225 -5.225)
      (stroke (width 0.15) (type solid)) (layer "F.SilkS"))
    (fp_line (start -5.225 5.225) (end -5.225 1.925)
      (stroke (width 0.15) (type solid)) (layer "F.SilkS"))
    (fp_line (start 4.125 -5.225) (end 5.225 -4.125)
      (stroke (width 0.15) (type solid)) (layer "F.SilkS"))
    (fp_line (start 5.225 -4.125) (end 5.225 -1.925)
      (stroke (width 0.15) (type solid)) (layer "F.SilkS"))
    (fp_line (start 5.225 1.925) (end 5.225 5.225)
      (stroke (width 0.15) (type solid)) (layer "F.SilkS"))
    (fp_line (start 5.225 5.225) (end -5.225 5.225)
      (stroke (width 0.15) (type solid)) (layer "F.SilkS"))
    (fp_line (start -5.55 -1.95) (end -5.55 1.95)
      (stroke (width 0.05) (type solid)) (layer "F.CrtYd"))
    (fp_line (start -5.55 1.95) (end -5.35 1.95)
      (stroke (width 0.05) (type solid)) (layer "F.CrtYd"))
    (fp_line (start -5.35 -5.35) (end -5.35 -1.95)
      (stroke (width 0.05) (type solid)) (layer "F.CrtYd"))
    (fp_line (start -5.35 -1.95) (end -5.55 -1.95)
      (stroke (width 0.05) (type solid)) (layer "F.CrtYd"))
    (fp_line (start -5.35 1.95) (end -5.35 5.35)
      (stroke (width 0.05) (type solid)) (layer "F.CrtYd"))
    (fp_line (start -5.35 5.35) (end 5.35 5.35)
      (stroke (width 0.05) (type solid)) (layer "F.CrtYd"))
    (fp_line (start 5.35 -5.35) (end -5.35 -5.35)
      (stroke (width 0.05) (type solid)) (layer "F.CrtYd"))
    (fp_line (start 5.35 -1.95) (end 5.35 -5.35)
      (stroke (width 0.05) (type solid)) (layer "F.CrtYd"))
    (fp_line (start 5.35 1.95) (end 5.55 1.95)
      (stroke (width 0.05) (type solid)) (layer "F.CrtYd"))
    (fp_line (start 5.35 5.35) (end 5.35 1.95)
      (stroke (width 0.05) (type solid)) (layer "F.CrtYd"))
    (fp_line (start 5.55 -1.95) (end 5.35 -1.95)
      (stroke (width 0.05) (type solid)) (layer "F.CrtYd"))
    (fp_line (start 5.55 -1.95) (end 5.55 1.95)
      (stroke (width 0.05) (type solid)) (layer "F.CrtYd"))
    (fp_rect (start -5.101 -5.101) (end 5.099 5.099)
      (stroke (width 0.15) (type solid)) (fill none) (layer "F.Fab"))
    (pad "1" smd roundrect (at -4.1 0) (size 3.4 2.4) (layers "F.Cu" "F.Paste" "F.Mask") (roundrect_rratio 0.1)
      (net 265 "Net-(D6-C)") (pintype "passive"))
    (pad "2" smd roundrect (at 4.1 0) (size 3.4 2.4) (layers "F.Cu" "F.Paste" "F.Mask") (roundrect_rratio 0.1)
      (net 290 "Net-(C110-Pad2)") (pintype "passive"))
  )

  (footprint "antmicro-footprints:C_0402_1005Metric" (layer "F.Cu")
    (at 120.539056 82.593104)
    (descr "Capacitor SMD 0402")
    (tags "capacitor SMD 0402")
    (property "Author" "Antmicro")
    (property "Dielectric" "")
    (property "License" "Apache-2.0")
    (property "MPN" "CC0402MRX5R5BB106")
    (property "Manufacturer" "YAGEO")
    (property "Public" "False")
    (property "Sheetfile" "power-supply.kicad_sch")
    (property "Sheetname" "Power supply")
    (property "Val" "10u")
    (property "Voltage" "")
    (property "ki_description" "SMD Multilayer Ceramic Capacitor, 10 µF, 6.3 V, 0402 [1005 Metric], ± 20%, X5R, CC Series")
    (property "ki_keywords" "0402, SMT, CAPACITOR, PASSIVE, MLCC, CERAMIC")
    (attr smd)
    (fp_text reference "C129" (at 2.300944 -0.008104) (layer "F.SilkS")
        (effects (font (size 0.7 0.7) (thickness 0.127)))
    )
    (fp_text value "C_10u_0402" (at 0 1.17) (layer "F.Fab")
        (effects (font (size 1 1) (thickness 0.15)))
    )
    (fp_text user "License: Apache-2.0" (at -0.939 5.799) (layer "F.Fab") hide
        (effects (font (size 0.7 0.7) (thickness 0.15)) (justify left bottom))
    )
    (fp_text user "Author: Antmicro" (at -0.939 3.399) (layer "F.Fab") hide
        (effects (font (size 0.7 0.7) (thickness 0.15)) (justify left bottom))
    )
    (fp_text user "${REFERENCE}" (at 0 0) (layer "F.Fab")
        (effects (font (size 0.25 0.25) (thickness 0.04)))
    )
    (fp_rect (start -0.925 -0.47) (end 0.925 0.47)
      (stroke (width 0.05) (type default)) (fill none) (layer "F.CrtYd"))
    (fp_line (start -0.494 -0.25) (end 0.504 -0.25)
      (stroke (width 0.15) (type solid)) (layer "F.Fab"))
    (fp_line (start -0.494 0.248) (end -0.494 -0.25)
      (stroke (width 0.15) (type solid)) (layer "F.Fab"))
    (fp_line (start 0.504 -0.25) (end 0.504 0.248)
      (stroke (width 0.15) (type solid)) (layer "F.Fab"))
    (fp_line (start 0.504 0.248) (end -0.494 0.248)
      (stroke (width 0.15) (type solid)) (layer "F.Fab"))
    (pad "1" smd roundrect (at -0.48 0) (size 0.59 0.64) (layers "F.Cu" "F.Paste" "F.Mask") (roundrect_rratio 0.25)
      (net 1 "GND") (pintype "passive"))
    (pad "2" smd roundrect (at 0.48 0) (size 0.59 0.64) (layers "F.Cu" "F.Paste" "F.Mask") (roundrect_rratio 0.25)
      (net 356 "Net-(C119-Pad2)") (pintype "passive"))
  )

  (footprint "antmicro-footprints:C_0603_1608Metric" (layer "F.Cu")
    (at 84.85 66.58 90)
    (descr "Capacitor SMD 0603")
    (tags "capacitor 0603")
    (property "Author" "Antmicro")
    (property "Dielectric" "")
    (property "License" "Apache-2.0")
    (property "MPN" "C1608X5R1E106M080AC")
    (property "Manufacturer" "TDK")
    (property "Public" "False")
    (property "Sheetfile" "power-supply.kicad_sch")
    (property "Sheetname" "Power supply")
    (property "Val" "10u")
    (property "Voltage" "25V")
    (property "ki_description" "SMD Multilayer Ceramic Capacitor, 10 µF, 25 V, 0603 [1608 Metric], ± 20%, X5R, C")
    (property "ki_keywords" "0603, SMT, CAPACITOR, PASSIVE, CERAMIC, MLCC")
    (attr smd)
    (fp_text reference "C101" (at -2.555 0.14 90) (layer "F.SilkS")
        (effects (font (size 0.7 0.7) (thickness 0.127)))
    )
    (fp_text value "C_10u_25V_0603" (at 0 1.9 90) (layer "F.Fab")
        (effects (font (size 1 1) (thickness 0.15)))
    )
    (fp_text user "License: Apache-2.0" (at -1.682 5.895 90) (layer "F.Fab") hide
        (effects (font (size 0.7 0.7) (thickness 0.15)) (justify left bottom))
    )
    (fp_text user "${REFERENCE}" (at -1.682 3.895 90) (layer "F.Fab") hide
        (effects (font (size 0.7 0.7) (thickness 0.15)) (justify left bottom))
    )
    (fp_text user "Author: Antmicro" (at -1.682 4.894 90) (layer "F.Fab") hide
        (effects (font (size 0.7 0.7) (thickness 0.15)) (justify left bottom))
    )
    (fp_line (start -0.15 -0.4) (end 0.15 -0.4)
      (stroke (width 0.15) (type solid)) (layer "F.SilkS"))
    (fp_line (start -0.15 0.4) (end 0.15 0.4)
      (stroke (width 0.15) (type solid)) (layer "F.SilkS"))
    (fp_rect (start -1.25 -0.65) (end 1.25 0.65)
      (stroke (width 0.05) (type solid)) (fill none) (layer "F.CrtYd"))
    (fp_rect (start -0.8 -0.4) (end 0.8 0.4)
      (stroke (width 0.15) (type solid)) (fill none) (layer "F.Fab"))
    (pad "1" smd roundrect (at -0.7 0 90) (size 0.8 1) (layers "F.Cu" "F.Paste" "F.Mask") (roundrect_rratio 0.2)
      (net 1 "GND") (pintype "passive"))
    (pad "2" smd roundrect (at 0.7 0 90) (size 0.8 1) (layers "F.Cu" "F.Paste" "F.Mask") (roundrect_rratio 0.2)
      (net 15 "VCC12V") (pintype "passive"))
  )

  (footprint "antmicro-footprints:C_0603_1608Metric" (layer "F.Cu")
    (at 83.35 66.58 90)
    (descr "Capacitor SMD 0603")
    (tags "capacitor 0603")
    (property "Author" "Antmicro")
    (property "Dielectric" "")
    (property "License" "Apache-2.0")
    (property "MPN" "C1608X5R1E106M080AC")
    (property "Manufacturer" "TDK")
    (property "Public" "False")
    (property "Sheetfile" "power-supply.kicad_sch")
    (property "Sheetname" "Power supply")
    (property "Val" "10u")
    (property "Voltage" "25V")
    (property "ki_description" "SMD Multilayer Ceramic Capacitor, 10 µF, 25 V, 0603 [1608 Metric], ± 20%, X5R, C")
    (property "ki_keywords" "0603, SMT, CAPACITOR, PASSIVE, CERAMIC, MLCC")
    (attr smd)
    (fp_text reference "C260" (at -2.485 -0.72 90) (layer "F.SilkS")
        (effects (font (size 0.7 0.7) (thickness 0.127)))
    )
    (fp_text value "C_10u_25V_0603" (at 0 1.9 90) (layer "F.Fab")
        (effects (font (size 1 1) (thickness 0.15)))
    )
    (fp_text user "Author: Antmicro" (at -1.682 4.894 90) (layer "F.Fab") hide
        (effects (font (size 0.7 0.7) (thickness 0.15)) (justify left bottom))
    )
    (fp_text user "${REFERENCE}" (at -1.682 3.895 90) (layer "F.Fab") hide
        (effects (font (size 0.7 0.7) (thickness 0.15)) (justify left bottom))
    )
    (fp_text user "License: Apache-2.0" (at -1.682 5.895 90) (layer "F.Fab") hide
        (effects (font (size 0.7 0.7) (thickness 0.15)) (justify left bottom))
    )
    (fp_line (start -0.15 -0.4) (end 0.15 -0.4)
      (stroke (width 0.15) (type solid)) (layer "F.SilkS"))
    (fp_line (start -0.15 0.4) (end 0.15 0.4)
      (stroke (width 0.15) (type solid)) (layer "F.SilkS"))
    (fp_rect (start -1.25 -0.65) (end 1.25 0.65)
      (stroke (width 0.05) (type solid)) (fill none) (layer "F.CrtYd"))
    (fp_rect (start -0.8 -0.4) (end 0.8 0.4)
      (stroke (width 0.15) (type solid)) (fill none) (layer "F.Fab"))
    (pad "1" smd roundrect (at -0.7 0 90) (size 0.8 1) (layers "F.Cu" "F.Paste" "F.Mask") (roundrect_rratio 0.2)
      (net 1 "GND") (pintype "passive"))
    (pad "2" smd roundrect (at 0.7 0 90) (size 0.8 1) (layers "F.Cu" "F.Paste" "F.Mask") (roundrect_rratio 0.2)
      (net 15 "VCC12V") (pintype "passive"))
  )

  (footprint "antmicro-footprints:C_0603_1608Metric" (layer "F.Cu")
    (at 86.35 66.58 90)
    (descr "Capacitor SMD 0603")
    (tags "capacitor 0603")
    (property "Author" "Antmicro")
    (property "Dielectric" "")
    (property "License" "Apache-2.0")
    (property "MPN" "C1608X5R1E106M080AC")
    (property "Manufacturer" "TDK")
    (property "Public" "False")
    (property "Sheetfile" "power-supply.kicad_sch")
    (property "Sheetname" "Power supply")
    (property "Val" "10u")
    (property "Voltage" "25V")
    (property "ki_description" "SMD Multilayer Ceramic Capacitor, 10 µF, 25 V, 0603 [1608 Metric], ± 20%, X5R, C")
    (property "ki_keywords" "0603, SMT, CAPACITOR, PASSIVE, CERAMIC, MLCC")
    (attr smd)
    (fp_text reference "C261" (at -2.465 0.7 90) (layer "F.SilkS")
        (effects (font (size 0.7 0.7) (thickness 0.127)))
    )
    (fp_text value "C_10u_25V_0603" (at 0 1.9 90) (layer "F.Fab")
        (effects (font (size 1 1) (thickness 0.15)))
    )
    (fp_text user "Author: Antmicro" (at -1.682 4.894 90) (layer "F.Fab") hide
        (effects (font (size 0.7 0.7) (thickness 0.15)) (justify left bottom))
    )
    (fp_text user "${REFERENCE}" (at -1.682 3.895 90) (layer "F.Fab") hide
        (effects (font (size 0.7 0.7) (thickness 0.15)) (justify left bottom))
    )
    (fp_text user "License: Apache-2.0" (at -1.682 5.895 90) (layer "F.Fab") hide
        (effects (font (size 0.7 0.7) (thickness 0.15)) (justify left bottom))
    )
    (fp_line (start -0.15 -0.4) (end 0.15 -0.4)
      (stroke (width 0.15) (type solid)) (layer "F.SilkS"))
    (fp_line (start -0.15 0.4) (end 0.15 0.4)
      (stroke (width 0.15) (type solid)) (layer "F.SilkS"))
    (fp_rect (start -1.25 -0.65) (end 1.25 0.65)
      (stroke (width 0.05) (type solid)) (fill none) (layer "F.CrtYd"))
    (fp_rect (start -0.8 -0.4) (end 0.8 0.4)
      (stroke (width 0.15) (type solid)) (fill none) (layer "F.Fab"))
    (pad "1" smd roundrect (at -0.7 0 90) (size 0.8 1) (layers "F.Cu" "F.Paste" "F.Mask") (roundrect_rratio 0.2)
      (net 1 "GND") (pintype "passive"))
    (pad "2" smd roundrect (at 0.7 0 90) (size 0.8 1) (layers "F.Cu" "F.Paste" "F.Mask") (roundrect_rratio 0.2)
      (net 15 "VCC12V") (pintype "passive"))
  )

  (footprint "antmicro-footprints:C_0402_1005Metric" (layer "F.Cu")
    (at 81.89 63.9 -90)
    (descr "Capacitor SMD 0402")
    (tags "capacitor SMD 0402")
    (property "Author" "Antmicro")
    (property "Dielectric" "X7R")
    (property "License" "Apache-2.0")
    (property "MPN" "GRM155R71H103KA88D")
    (property "Manufacturer" "Murata")
    (property "Public" "False")
    (property "Sheetfile" "power-supply.kicad_sch")
    (property "Sheetname" "Power supply")
    (property "Val" "10n")
    (property "Voltage" "50V")
    (property "ki_description" "SMD Multilayer Ceramic Capacitor, 10000 pF, 50 V, 0402 [1005 Metric], ± 10%, X7R, GRM Series")
    (property "ki_keywords" "0402, SMT, CAPACITOR, PASSIVE")
    (attr smd)
    (fp_text reference "C59" (at -1.85 -0.04 90) (layer "F.SilkS")
        (effects (font (size 0.7 0.7) (thickness 0.127)))
    )
    (fp_text value "C_10n_0402" (at 0 1.17 90) (layer "F.Fab")
        (effects (font (size 1 1) (thickness 0.15)))
    )
    (fp_text user "${REFERENCE}" (at 0 0 90) (layer "F.Fab")
        (effects (font (size 0.25 0.25) (thickness 0.04)))
    )
    (fp_text user "Author: Antmicro" (at -0.939 3.399 90) (layer "F.Fab") hide
        (effects (font (size 0.7 0.7) (thickness 0.15)) (justify right bottom))
    )
    (fp_text user "License: Apache-2.0" (at -0.939 5.799 90) (layer "F.Fab") hide
        (effects (font (size 0.7 0.7) (thickness 0.15)) (justify right bottom))
    )
    (fp_rect (start -0.925 -0.47) (end 0.925 0.47)
      (stroke (width 0.05) (type default)) (fill none) (layer "F.CrtYd"))
    (fp_line (start -0.494 -0.25) (end 0.504 -0.25)
      (stroke (width 0.15) (type solid)) (layer "F.Fab"))
    (fp_line (start -0.494 0.248) (end -0.494 -0.25)
      (stroke (width 0.15) (type solid)) (layer "F.Fab"))
    (fp_line (start 0.504 -0.25) (end 0.504 0.248)
      (stroke (width 0.15) (type solid)) (layer "F.Fab"))
    (fp_line (start 0.504 0.248) (end -0.494 0.248)
      (stroke (width 0.15) (type solid)) (layer "F.Fab"))
    (pad "1" smd roundrect (at -0.48 0 270) (size 0.59 0.64) (layers "F.Cu" "F.Paste" "F.Mask") (roundrect_rratio 0.25)
      (net 1 "GND") (pintype "passive"))
    (pad "2" smd roundrect (at 0.48 0 270) (size 0.59 0.64) (layers "F.Cu" "F.Paste" "F.Mask") (roundrect_rratio 0.25)
      (net 780 "Net-(U15-SS{slash}TR)") (pintype "passive"))
  )

  (footprint "antmicro-footprints:C_0603_1608Metric" (layer "F.Cu")
    (at 79.9 68.65 -90)
    (descr "Capacitor SMD 0603")
    (tags "capacitor 0603")
    (property "Author" "Antmicro")
    (property "Dielectric" "")
    (property "License" "Apache-2.0")
    (property "MPN" "GRM188R60J476ME15D")
    (property "Manufacturer" "Murata")
    (property "Public" "False")
    (property "Sheetfile" "power-supply.kicad_sch")
    (property "Sheetname" "Power supply")
    (property "Val" "47u")
    (property "Voltage" "")
    (property "ki_description" "SMD Multilayer Ceramic Capacitor, 47 µF, 6.3 V, 0603 [1608 Metric], ± 20%, X5R, GRM Series")
    (property "ki_keywords" "0603, SMT, CAPACITOR, PASSIVE, CERAMIC, MLCC")
    (attr smd)
    (fp_text reference "C112" (at 0.505 -1.05 90) (layer "F.SilkS")
        (effects (font (size 0.7 0.7) (thickness 0.127)))
    )
    (fp_text value "C_47u_0603" (at 0 1.9 90) (layer "F.Fab")
        (effects (font (size 1 1) (thickness 0.15)))
    )
    (fp_text user "${REFERENCE}" (at -1.682 3.895 -90) (layer "F.Fab") hide
        (effects (font (size 0.7 0.7) (thickness 0.15)) (justify left bottom))
    )
    (fp_text user "Author: Antmicro" (at -1.682 4.894 -90) (layer "F.Fab") hide
        (effects (font (size 0.7 0.7) (thickness 0.15)) (justify left bottom))
    )
    (fp_text user "License: Apache-2.0" (at -1.682 5.895 -90) (layer "F.Fab") hide
        (effects (font (size 0.7 0.7) (thickness 0.15)) (justify left bottom))
    )
    (fp_line (start -0.15 -0.4) (end 0.15 -0.4)
      (stroke (width 0.15) (type solid)) (layer "F.SilkS"))
    (fp_line (start -0.15 0.4) (end 0.15 0.4)
      (stroke (width 0.15) (type solid)) (layer "F.SilkS"))
    (fp_rect (start -1.25 -0.65) (end 1.25 0.65)
      (stroke (width 0.05) (type solid)) (fill none) (layer "F.CrtYd"))
    (fp_rect (start -0.8 -0.4) (end 0.8 0.4)
      (stroke (width 0.15) (type solid)) (fill none) (layer "F.Fab"))
    (pad "1" smd roundrect (at -0.7 0 270) (size 0.8 1) (layers "F.Cu" "F.Paste" "F.Mask") (roundrect_rratio 0.2)
      (net 1 "GND") (pintype "passive"))
    (pad "2" smd roundrect (at 0.7 0 270) (size 0.8 1) (layers "F.Cu" "F.Paste" "F.Mask") (roundrect_rratio 0.2)
      (net 290 "Net-(C110-Pad2)") (pintype "passive"))
  )

  (footprint "antmicro-footprints:Oscillator_SMD_Abracon_ASFLMB_5x3.2x0.85mm" (layer "F.Cu")
    (at 144.631 87.455 180)
    (property "Author" "Antmicro")
    (property "License" "Apache-2.0")
    (property "MPN" "ASFLMB-12.000MHZ-LC-T")
    (property "Manufacturer" "Abracon")
    (property "Sheetfile" "interfaces.kicad_sch")
    (property "Sheetname" "Interfaces")
    (property "Val" "12 MHz")
    (property "ki_description" "MEMS Oscillator, 12 MHz, SMD, 5mm x 3.2mm, 50 ppm, 3.3 V, ASFLMB, LVCMOS")
    (property "ki_keywords" "OSCILLATOR, MEMS")
    (attr smd)
    (fp_text reference "Y4" (at 0.211 3.41) (layer "F.SilkS")
        (effects (font (size 0.7 0.7) (thickness 0.127)))
    )
    (fp_text value "Oscillator_12MHz_ASFLMB" (at -0.05 2.925) (layer "F.Fab")
        (effects (font (size 1 1) (thickness 0.15)))
    )
    (fp_text user "Author: Antmicro" (at -2.8 6.259 180) (layer "F.Fab") hide
        (effects (font (size 0.7 0.7) (thickness 0.15)) (justify left bottom))
    )
    (fp_text user "License: Apache-2.0" (at -2.8 7.459 180) (layer "F.Fab") hide
        (effects (font (size 0.7 0.7) (thickness 0.15)) (justify left bottom))
    )
    (fp_text user "${REFERENCE}" (at -2 0) (layer "F.Fab")
        (effects (font (size 0.3 0.3) (thickness 0.05)))
    )
    (fp_line (start -1.6 -2.5) (end -1.6 -1.9)
      (stroke (width 0.15) (type solid)) (layer "F.SilkS"))
    (fp_line (start -1.6 -0.4) (end -1.6 0.6)
      (stroke (width 0.15) (type solid)) (layer "F.SilkS"))
    (fp_line (start -1.6 2.1) (end -1.6 2.7)
      (stroke (width 0.15) (type solid)) (layer "F.SilkS"))
    (fp_line (start -1.6 2.7) (end 1.8 2.7)
      (stroke (width 0.15) (type solid)) (layer "F.SilkS"))
    (fp_line (start 1.8 -2.5) (end -1.6 -2.5)
      (stroke (width 0.15) (type solid)) (layer "F.SilkS"))
    (fp_line (start 1.8 -1.9) (end 1.8 -2.5)
      (stroke (width 0.15) (type solid)) (layer "F.SilkS"))
    (fp_line (start 1.8 0.6) (end 1.8 -0.4)
      (stroke (width 0.15) (type solid)) (layer "F.SilkS"))
    (fp_line (start 1.8 2.7) (end 1.8 2.1)
      (stroke (width 0.15) (type solid)) (layer "F.SilkS"))
    (fp_circle (center -1.9 -2.1) (end -1.9 -2.05)
      (stroke (width 0.15) (type solid)) (fill solid) (layer "F.SilkS"))
    (fp_rect (start 2 -2.7) (end -1.8 2.9)
      (stroke (width 0.05) (type solid)) (fill none) (layer "F.CrtYd"))
    (pad "1" smd rect (at -1.049 -1.17) (size 1.1 1.2) (layers "F.Cu" "F.Paste" "F.Mask")
      (net 2 "VCC3V3") (pinfunction "EN") (pintype "input"))
    (pad "2" smd rect (at -1.049 1.369 90) (size 1.2 1.1) (layers "F.Cu" "F.Paste" "F.Mask")
      (net 1 "GND") (pinfunction "GND") (pintype "power_in"))
    (pad "3" smd rect (at 1.252 1.369 90) (size 1.2 1.1) (layers "F.Cu" "F.Paste" "F.Mask")
      (net 511 "/Interfaces/FTDI_CLK") (pinfunction "OUT") (pintype "output"))
    (pad "4" smd rect (at 1.252 -1.17 90) (size 1.2 1.1) (layers "F.Cu" "F.Paste" "F.Mask")
      (net 2 "VCC3V3") (pinfunction "VDD") (pintype "power_in"))
  )

  (footprint "antmicro-footprints:TP_SMD_1mm" (layer "F.Cu")
    (at 137.75 96.35 -90)
    (property "Author" "Antmicro")
    (property "License" "Apache-2.0")
    (property "MPN" "")
    (property "Manufacturer" "")
    (property "Sheetfile" "interfaces.kicad_sch")
    (property "Sheetname" "Interfaces")
    (property "exclude_from_bom" "")
    (property "ki_description" "Test point 1mm SMD")
    (property "ki_keywords" "TESTPOINT")
    (attr exclude_from_pos_files exclude_from_bom)
    (fp_text reference "TP15" (at 0.435 -0.66) (layer "F.SilkS")
        (effects (font (size 0.7 0.7) (thickness 0.15)) (justify left bottom))
    )
    (fp_text value "TP_1mm_SMD" (at 0 1.4 -90) (layer "F.Fab")
        (effects (font (size 0.7 0.7) (thickness 0.15)) (justify left bottom))
    )
    (fp_text user "Author: Antmicro" (at -0.5 4 -90) (layer "F.Fab") hide
        (effects (font (size 0.7 0.7) (thickness 0.15)) (justify left bottom))
    )
    (fp_text user "${REFERENCE}" (at -0.5 2.8 -90) (layer "F.Fab") hide
        (effects (font (size 0.7 0.7) (thickness 0.15)) (justify left bottom))
    )
    (fp_text user "License: Apache-2.0" (at -0.5 5.2 -90) (layer "F.Fab") hide
        (effects (font (size 0.7 0.7) (thickness 0.15)) (justify left bottom))
    )
    (fp_circle (center 0 0) (end 0.6 0)
      (stroke (width 0.05) (type default)) (fill none) (layer "F.CrtYd"))
    (pad "1" smd circle (at 0 0 270) (size 1 1) (layers "F.Cu" "F.Mask")
      (net 436 "Net-(U14-~{SUSPEND})") (pinfunction "1") (pintype "passive"))
  )

  (footprint "antmicro-footprints:TP_SMD_1mm" (layer "F.Cu")
    (at 140.9492 84.675 -90)
    (property "Author" "Antmicro")
    (property "License" "Apache-2.0")
    (property "MPN" "")
    (property "Manufacturer" "")
    (property "Sheetfile" "interfaces.kicad_sch")
    (property "Sheetname" "Interfaces")
    (property "exclude_from_bom" "")
    (property "ki_description" "Test point 1mm SMD")
    (property "ki_keywords" "TESTPOINT")
    (attr exclude_from_pos_files exclude_from_bom)
    (fp_text reference "TP14" (at -0.69 1.1392) (layer "F.SilkS")
        (effects (font (size 0.7 0.7) (thickness 0.15)) (justify left bottom))
    )
    (fp_text value "TP_1mm_SMD" (at 0 1.4 -90) (layer "F.Fab")
        (effects (font (size 0.7 0.7) (thickness 0.15)) (justify left bottom))
    )
    (fp_text user "License: Apache-2.0" (at -0.5 5.2 -90) (layer "F.Fab") hide
        (effects (font (size 0.7 0.7) (thickness 0.15)) (justify left bottom))
    )
    (fp_text user "Author: Antmicro" (at -0.5 4 -90) (layer "F.Fab") hide
        (effects (font (size 0.7 0.7) (thickness 0.15)) (justify left bottom))
    )
    (fp_text user "${REFERENCE}" (at -0.5 2.8 -90) (layer "F.Fab") hide
        (effects (font (size 0.7 0.7) (thickness 0.15)) (justify left bottom))
    )
    (fp_circle (center 0 0) (end 0.6 0)
      (stroke (width 0.05) (type default)) (fill none) (layer "F.CrtYd"))
    (pad "1" smd circle (at 0 0 270) (size 1 1) (layers "F.Cu" "F.Mask")
      (net 435 "Net-(U14-~{PWR_{EN}})") (pinfunction "1") (pintype "passive"))
  )

  (footprint "antmicro-footprints:TP_SMD_1mm" (layer "F.Cu")
    (at 124.95 66.8508)
    (property "Author" "Antmicro")
    (property "License" "Apache-2.0")
    (property "MPN" "")
    (property "Manufacturer" "")
    (property "Sheetfile" "interfaces.kicad_sch")
    (property "Sheetname" "Interfaces")
    (property "exclude_from_bom" "")
    (property "ki_description" "Test point 1mm SMD")
    (property "ki_keywords" "TESTPOINT")
    (attr exclude_from_pos_files exclude_from_bom)
    (fp_text reference "TP13" (at -3.34 0.4342) (layer "F.SilkS")
        (effects (font (size 0.7 0.7) (thickness 0.15)) (justify left bottom))
    )
    (fp_text value "TP_1mm_SMD" (at 0 1.4) (layer "F.Fab")
        (effects (font (size 0.7 0.7) (thickness 0.15)) (justify left bottom))
    )
    (fp_text user "${REFERENCE}" (at -0.5 2.8) (layer "F.Fab") hide
        (effects (font (size 0.7 0.7) (thickness 0.15)) (justify left bottom))
    )
    (fp_text user "License: Apache-2.0" (at -0.5 5.2) (layer "F.Fab") hide
        (effects (font (size 0.7 0.7) (thickness 0.15)) (justify left bottom))
    )
    (fp_text user "Author: Antmicro" (at -0.5 4) (layer "F.Fab") hide
        (effects (font (size 0.7 0.7) (thickness 0.15)) (justify left bottom))
    )
    (fp_circle (center 0 0) (end 0.6 0)
      (stroke (width 0.05) (type default)) (fill none) (layer "F.CrtYd"))
    (pad "1" smd circle (at 0 0) (size 1 1) (layers "F.Cu" "F.Mask")
      (net 388 "Net-(J6-ID)") (pinfunction "1") (pintype "passive"))
  )

  (footprint "antmicro-footprints:SFF-TA-1002-4C+" (layer "F.Cu")
    (at 104.89 177.345)
    (property "Author" "Antmicro")
    (property "DNP" "DNP")
    (property "License" "Apache-2.0")
    (property "MPN" "SFF-TA-1002-4C+")
    (property "Manufacturer" "Amphenol")
    (property "Sheetfile" "edge-connector.kicad_sch")
    (property "Sheetname" "Edge connector")
    (property "ki_description" "PCI connector")
    (property "ki_keywords" "CONNECTOR")
    (attr exclude_from_pos_files)
    (fp_text reference "J5" (at -0.83 -8.9) (layer "F.SilkS")
        (effects (font (size 0.7 0.7) (thickness 0.127)))
    )
    (fp_text value "SFF-TA-1002-4C+" (at -24.2 4.8) (layer "F.Fab")
        (effects (font (size 1 1) (thickness 0.15)))
    )
    (fp_text user "${REFERENCE}" (at 0 5.4) (layer "F.Fab") hide
        (effects (font (size 0.7 0.7) (thickness 0.15)) (justify left bottom))
    )
    (fp_text user "License: Apache-2.0" (at 0 7.8) (layer "F.Fab") hide
        (effects (font (size 0.7 0.7) (thickness 0.15)) (justify left bottom))
    )
    (fp_text user "Author: Antmicro" (at 0 6.6) (layer "F.Fab") hide
        (effects (font (size 0.7 0.7) (thickness 0.15)) (justify left bottom))
    )
    (fp_line (start -35 -4.6) (end -31.98 -4.6)
      (stroke (width 0.12) (type solid)) (layer "B.Fab"))
    (fp_line (start -31.48 1.19) (end -31.48 -4.1)
      (stroke (width 0.12) (type solid)) (layer "B.Fab"))
    (fp_line (start -30.73 1.94) (end -31.48 1.19)
      (stroke (width 0.12) (type solid)) (layer "B.Fab"))
    (fp_line (start -30.73 1.94) (end -22.275 1.94)
      (stroke (width 0.12) (type solid)) (layer "B.Fab"))
    (fp_line (start -21.525 1.19) (end -22.275 1.94)
      (stroke (width 0.12) (type solid)) (layer "B.Fab"))
    (fp_line (start -21.525 1.19) (end -21.525 -4.06)
      (stroke (width 0.12) (type solid)) (layer "B.Fab"))
    (fp_line (start -19.275 1.19) (end -19.275 -4.06)
      (stroke (width 0.12) (type solid)) (layer "B.Fab"))
    (fp_line (start -19.275 1.19) (end -18.525 1.94)
      (stroke (width 0.12) (type solid)) (layer "B.Fab"))
    (fp_line (start -18.525 1.94) (end -1.67 1.94)
      (stroke (width 0.12) (type solid)) (layer "B.Fab"))
    (fp_line (start -0.92 1.19) (end -1.67 1.94)
      (stroke (width 0.12) (type solid)) (layer "B.Fab"))
    (fp_line (start -0.92 1.19) (end -0.92 -4.26)
      (stroke (width 0.12) (type solid)) (layer "B.Fab"))
    (fp_line (start 0.93 1.19) (end 0.93 -4.34)
      (stroke (width 0.12) (type solid)) (layer "B.Fab"))
    (fp_line (start 0.93 1.19) (end 1.68 1.94)
      (stroke (width 0.12) (type solid)) (layer "B.Fab"))
    (fp_line (start 1.68 1.94) (end 10.135 1.94)
      (stroke (width 0.12) (type solid)) (layer "B.Fab"))
    (fp_line (start 10.135 1.94) (end 10.885 1.19)
      (stroke (width 0.12) (type solid)) (layer "B.Fab"))
    (fp_line (start 10.885 1.19) (end 10.885 -3.81)
      (stroke (width 0.12) (type solid)) (layer "B.Fab"))
    (fp_line (start 13.635 1.19) (end 13.635 -3.89)
      (stroke (width 0.12) (type solid)) (layer "B.Fab"))
    (fp_line (start 14.385 1.94) (end 13.635 1.19)
      (stroke (width 0.12) (type solid)) (layer "B.Fab"))
    (fp_line (start 14.385 1.94) (end 31.2451 1.94)
      (stroke (width 0.12) (type solid)) (layer "B.Fab"))
    (fp_line (start 32 1.19) (end 31.2451 1.94)
      (stroke (width 0.12) (type solid)) (layer "B.Fab"))
    (fp_line (start 32 1.19) (end 32 -4.1)
      (stroke (width 0.12) (type solid)) (layer "B.Fab"))
    (fp_arc (start -31.98 -4.6) (mid -31.626447 -4.453553) (end -31.48 -4.1)
      (stroke (width 0.12) (type solid)) (layer "B.Fab"))
    (fp_arc (start -21.525 -4.06) (mid -20.4 -5.225711) (end -19.275 -4.06)
      (stroke (width 0.12) (type solid)) (layer "B.Fab"))
    (fp_arc (start -0.92 -4.26) (mid -0.015005 -5.225648) (end 0.930864 -4.3)
      (stroke (width 0.12) (type solid)) (layer "B.Fab"))
    (fp_arc (start 10.885 -3.81) (mid 12.264997 -5.225573) (end 13.634673 -3.800012)
      (stroke (width 0.12) (type solid)) (layer "B.Fab"))
    (fp_arc (start 32 -4.1) (mid 32.146447 -4.453553) (end 32.5 -4.6)
      (stroke (width 0.12) (type solid)) (layer "B.Fab"))
    (pad "A1" smd rect (at -18.205 -0.2) (size 0.38 1.72) (layers "B.Cu" "B.Mask")
      (net 37 "I2C[0]_SCL") (pinfunction "A1") (pintype "passive"))
    (pad "A2" smd rect (at -17.6 -0.2) (size 0.38 1.72) (layers "B.Cu" "B.Mask")
      (net 38 "I2C[0]_SDA") (pinfunction "A2") (pintype "passive"))
    (pad "A3" smd rect (at -17 -0.2) (size 0.38 1.72) (layers "B.Cu" "B.Mask")
      (net 28 "I2C[1]_SCL") (pinfunction "A3") (pintype "passive"))
    (pad "A4" smd rect (at -16.4 -0.2) (size 0.38 1.72) (layers "B.Cu" "B.Mask")
      (net 29 "I2C[1]_SDA") (pinfunction "A4") (pintype "passive"))
    (pad "A5" smd rect (at -15.8 -0.2) (size 0.38 1.72) (layers "B.Cu" "B.Mask")
      (net 32 "I2C[2]_SCL") (pinfunction "A5") (pintype "passive"))
    (pad "A6" smd rect (at -15.2 -0.2) (size 0.38 1.72) (layers "B.Cu" "B.Mask")
      (net 31 "I2C[2]_SDA") (pinfunction "A6") (pintype "passive"))
    (pad "A7" smd rect (at -14.6 -0.2) (size 0.38 1.72) (layers "B.Cu" "B.Mask")
      (net 25 "I2C[3]_SCL") (pinfunction "A7") (pintype "passive"))
    (pad "A8" smd rect (at -14 -0.2) (size 0.38 1.72) (layers "B.Cu" "B.Mask")
      (net 27 "I2C[3]_SDA") (pinfunction "A8") (pintype "passive"))
    (pad "A9" smd rect (at -13.4 -0.2) (size 0.38 1.72) (layers "B.Cu" "B.Mask")
      (net 36 "I2C[4]_SCL") (pinfunction "A9") (pintype "passive"))
    (pad "A10" smd rect (at -12.8 -0.2) (size 0.38 1.72) (layers "B.Cu" "B.Mask")
      (net 33 "I2C[4]_SDA") (pinfunction "A10") (pintype "passive"))
    (pad "A11" smd rect (at -12.2 0) (size 0.38 2.12) (layers "B.Cu" "B.Mask")
      (net 24 "I2C[5]_SCL") (pinfunction "A11") (pintype "passive"))
    (pad "A12" smd rect (at -11.6 -0.2) (size 0.38 1.72) (layers "B.Cu" "B.Mask")
      (net 23 "I2C[5]_SDA") (pinfunction "A12") (pintype "passive"))
    (pad "A13" smd rect (at -11 -0.2) (size 0.38 1.72) (layers "B.Cu" "B.Mask")
      (net 1 "GND") (pinfunction "A13") (pintype "passive"))
    (pad "A14" smd rect (at -10.4 0) (size 0.38 2.12) (layers "B.Cu" "B.Mask")
      (net 103 "CLK_100M_PCIE_DP") (pinfunction "A14") (pintype "passive"))
    (pad "A15" smd rect (at -9.8 -0.2) (size 0.38 1.72) (layers "B.Cu" "B.Mask")
      (net 104 "CLK_100M_PCIE_DN") (pinfunction "A15") (pintype "passive"))
    (pad "A16" smd rect (at -9.2 -0.2) (size 0.38 1.72) (layers "B.Cu" "B.Mask")
      (net 1 "GND") (pinfunction "A16") (pintype "passive"))
    (pad "A17" smd rect (at -8.6 0) (size 0.38 2.12) (layers "B.Cu" "B.Mask")
      (net 105 "PCIE_BMC_TX_DP") (pinfunction "A17") (pintype "passive"))
    (pad "A18" smd rect (at -8 -0.2) (size 0.38 1.72) (layers "B.Cu" "B.Mask")
      (net 106 "PCIE_BMC_TX_DN") (pinfunction "A18") (pintype "passive"))
    (pad "A19" smd rect (at -7.4 -0.2) (size 0.38 1.72) (layers "B.Cu" "B.Mask")
      (net 1 "GND") (pinfunction "A19") (pintype "passive"))
    (pad "A20" smd rect (at -6.8 0) (size 0.38 2.12) (layers "B.Cu" "B.Mask")
      (net 107 "PCIE_BMC_RX_DP") (pinfunction "A20") (pintype "passive"))
    (pad "A21" smd rect (at -6.2 -0.2) (size 0.38 1.72) (layers "B.Cu" "B.Mask")
      (net 108 "PCIE_BMC_RX_DN") (pinfunction "A21") (pintype "passive"))
    (pad "A22" smd rect (at -5.6 -0.2) (size 0.38 1.72) (layers "B.Cu" "B.Mask")
      (net 1 "GND") (pinfunction "A22") (pintype "passive"))
    (pad "A23" smd rect (at -5 -0.2) (size 0.38 1.72) (layers "B.Cu" "B.Mask")
      (net 34 "I2C[6]_SCL") (pinfunction "A23") (pintype "passive"))
    (pad "A24" smd rect (at -4.4 -0.2) (size 0.38 1.72) (layers "B.Cu" "B.Mask")
      (net 35 "I2C[6]_SDA") (pinfunction "A24") (pintype "passive"))
    (pad "A25" smd rect (at -3.8 -0.2) (size 0.38 1.72) (layers "B.Cu" "B.Mask")
      (net 26 "I2C[7]_SCL") (pinfunction "A25") (pintype "passive"))
    (pad "A26" smd rect (at -3.2 -0.2) (size 0.38 1.72) (layers "B.Cu" "B.Mask")
      (net 30 "I2C[7]_SDA") (pinfunction "A26") (pintype "passive"))
    (pad "A27" smd rect (at -2.6 -0.2) (size 0.38 1.72) (layers "B.Cu" "B.Mask")
      (net 51 "I2C[8]_SCL") (pinfunction "A27") (pintype "passive"))
    (pad "A28" smd rect (at -2 -0.2) (size 0.38 1.72) (layers "B.Cu" "B.Mask")
      (net 52 "I2C[8]_SDA") (pinfunction "A28") (pintype "passive"))
    (pad "A29" smd rect (at 2.01 -0.2) (size 0.38 1.72) (layers "B.Cu" "B.Mask")
      (net 43 "I2C[9]_SCL") (pinfunction "A29") (pintype "passive"))
    (pad "A30" smd rect (at 2.6 -0.2) (size 0.38 1.72) (layers "B.Cu" "B.Mask")
      (net 44 "I2C[9]_SDA") (pinfunction "A30") (pintype "passive"))
    (pad "A31" smd rect (at 3.2 -0.2) (size 0.38 1.72) (layers "B.Cu" "B.Mask")
      (net 48 "I2C[10]_SCL") (pinfunction "A31") (pintype "passive"))
    (pad "A32" smd rect (at 3.8 -0.2) (size 0.38 1.72) (layers "B.Cu" "B.Mask")
      (net 47 "I2C[10]_SDA") (pinfunction "A32") (pintype "passive"))
    (pad "A33" smd rect (at 4.4 0) (size 0.38 2.12) (layers "B.Cu" "B.Mask")
      (net 1 "GND") (pinfunction "A33") (pintype "passive"))
    (pad "A34" smd rect (at 5 -0.2) (size 0.38 1.72) (layers "B.Cu" "B.Mask")
      (net 21 "JTAG_TCK") (pinfunction "A34") (pintype "passive"))
    (pad "A35" smd rect (at 5.6 -0.2) (size 0.38 1.72) (layers "B.Cu" "B.Mask")
      (net 22 "JTAG_TMS") (pinfunction "A35") (pintype "passive"))
    (pad "A36" smd rect (at 6.2 -0.2) (size 0.38 1.72) (layers "B.Cu" "B.Mask")
      (net 19 "JTAG_TDI") (pinfunction "A36") (pintype "passive"))
    (pad "A37" smd rect (at 6.8 -0.2) (size 0.38 1.72) (layers "B.Cu" "B.Mask")
      (net 20 "JTAG_TDO") (pinfunction "A37") (pintype "passive"))
    (pad "A38" smd rect (at 7.4 -0.2) (size 0.38 1.72) (layers "B.Cu" "B.Mask")
      (net 40 "I2C[11]_SCL") (pinfunction "A38") (pintype "passive"))
    (pad "A39" smd rect (at 8 -0.2) (size 0.38 1.72) (layers "B.Cu" "B.Mask")
      (net 42 "I2C[11]_SDA") (pinfunction "A39") (pintype "passive"))
    (pad "A40" smd rect (at 8.6 -0.2) (size 0.38 1.72) (layers "B.Cu" "B.Mask")
      (net 50 "I2C[12]_SCL") (pinfunction "A40") (pintype "passive"))
    (pad "A41" smd rect (at 9.2 -0.2) (size 0.38 1.72) (layers "B.Cu" "B.Mask")
      (net 49 "I2C[12]_SDA") (pinfunction "A41") (pintype "passive"))
    (pad "A42" smd rect (at 9.8 0) (size 0.38 2.12) (layers "B.Cu" "B.Mask")
      (net 1 "GND") (pinfunction "A42") (pintype "passive"))
    (pad "A43" smd rect (at 14.715 -0.2) (size 0.38 1.72) (layers "B.Cu" "B.Mask")
      (net 109 "HPM_FW_RECOVERY") (pinfunction "A43") (pintype "passive"))
    (pad "A44" smd rect (at 15.3 -0.2) (size 0.38 1.72) (layers "B.Cu" "B.Mask")
      (net 110 "HPM_STBY_RDY") (pinfunction "A44") (pintype "passive"))
    (pad "A45" smd rect (at 15.9 -0.2) (size 0.38 1.72) (layers "B.Cu" "B.Mask")
      (net 111 "HPM_STBY_EN") (pinfunction "A45") (pintype "passive"))
    (pad "A46" smd rect (at 16.5 -0.2) (size 0.38 1.72) (layers "B.Cu" "B.Mask")
      (net 112 "HPM_STBY_RST_N") (pinfunction "A46") (pintype "passive"))
    (pad "A47" smd rect (at 17.1 -0.2) (size 0.38 1.72) (layers "B.Cu" "B.Mask")
      (net 113 "SYS_PWRBTN_N") (pinfunction "A47") (pintype "passive"))
    (pad "A48" smd rect (at 17.7 -0.2) (size 0.38 1.72) (layers "B.Cu" "B.Mask")
      (net 114 "SYS_PWROK") (pinfunction "A48") (pintype "passive"))
    (pad "A49" smd rect (at 18.3 -0.2) (size 0.38 1.72) (layers "B.Cu" "B.Mask")
      (net 115 "DBP_PREQ_N") (pinfunction "A49") (pintype "passive"))
    (pad "A50" smd rect (at 18.9 -0.2) (size 0.38 1.72) (layers "B.Cu" "B.Mask")
      (net 116 "DBP_PRDY_N") (pinfunction "A50") (pintype "passive"))
    (pad "A51" smd rect (at 19.5 -0.2) (size 0.38 1.72) (layers "B.Cu" "B.Mask")
      (net 117 "RST_PLTRST_BUF_N") (pinfunction "A51") (pintype "passive"))
    (pad "A52" smd rect (at 20.1 -0.2) (size 0.38 1.72) (layers "B.Cu" "B.Mask")
      (net 118 "SPARE1") (pinfunction "A52") (pintype "passive"))
    (pad "A53" smd rect (at 20.7 -0.2) (size 0.38 1.72) (layers "B.Cu" "B.Mask")
      (net 119 "RoT_CPU_RST_N") (pinfunction "A53") (pintype "passive"))
    (pad "A54" smd rect (at 21.3 -0.2) (size 0.38 1.72) (layers "B.Cu" "B.Mask")
      (net 120 "CHASI#") (pinfunction "A54") (pintype "passive"))
    (pad "A55" smd rect (at 21.9 -0.2) (size 0.38 1.72) (layers "B.Cu" "B.Mask")
      (net 121 "SPARE0") (pinfunction "A55") (pintype "passive"))
    (pad "A56" smd rect (at 22.5 -0.2) (size 0.38 1.72) (layers "B.Cu" "B.Mask")
      (net 122 "IRQ_N") (pinfunction "A56") (pintype "passive"))
    (pad "A57" smd rect (at 23.1 -0.2) (size 0.38 1.72) (layers "B.Cu" "B.Mask")
      (net 123 "PRSNT1_N") (pinfunction "A57") (pintype "passive"))
    (pad "A58" smd rect (at 23.7 0) (size 0.38 2.12) (layers "B.Cu" "B.Mask")
      (net 1 "GND") (pinfunction "A58") (pintype "passive"))
    (pad "A59" smd rect (at 24.3 -0.2) (size 0.38 1.72) (layers "B.Cu" "B.Mask")
      (net 702 "PCIE_HPM_RX0_P") (pinfunction "A59") (pintype "passive"))
    (pad "A60" smd rect (at 24.9 -0.2) (size 0.38 1.72) (layers "B.Cu" "B.Mask")
      (net 703 "PCIE_HPM_RX0_N") (pinfunction "A60") (pintype "passive"))
    (pad "A61" smd rect (at 25.5 0) (size 0.38 2.12) (layers "B.Cu" "B.Mask")
      (net 1 "GND") (pinfunction "A61") (pintype "passive"))
    (pad "A62" smd rect (at 26.1 -0.2) (size 0.38 1.72) (layers "B.Cu" "B.Mask")
      (net 701 "PCIE_HPM_RX1_P") (pinfunction "A62") (pintype "passive"))
    (pad "A63" smd rect (at 26.7 -0.2) (size 0.38 1.72) (layers "B.Cu" "B.Mask")
      (net 700 "PCIE_HPM_RX1_N") (pinfunction "A63") (pintype "passive"))
    (pad "A64" smd rect (at 27.3 0) (size 0.38 2.12) (layers "B.Cu" "B.Mask")
      (net 1 "GND") (pinfunction "A64") (pintype "passive"))
    (pad "A65" smd rect (at 27.9 -0.2) (size 0.38 1.72) (layers "B.Cu" "B.Mask")
      (net 699 "PCIE_HPM_RX2_P") (pinfunction "A65") (pintype "passive"))
    (pad "A66" smd rect (at 28.5 -0.2) (size 0.38 1.72) (layers "B.Cu" "B.Mask")
      (net 698 "PCIE_HPM_RX2_N") (pinfunction "A66") (pintype "passive"))
    (pad "A67" smd rect (at 29.1 0) (size 0.38 2.12) (layers "B.Cu" "B.Mask")
      (net 1 "GND") (pinfunction "A67") (pintype "passive"))
    (pad "A68" smd rect (at 29.7 -0.2) (size 0.38 1.72) (layers "B.Cu" "B.Mask")
      (net 697 "PCIE_HPM_RX3_P") (pinfunction "A68") (pintype "passive"))
    (pad "A69" smd rect (at 30.3 -0.2) (size 0.38 1.72) (layers "B.Cu" "B.Mask")
      (net 696 "PCIE_HPM_RX3_N") (pinfunction "A69") (pintype "passive"))
    (pad "A70" smd rect (at 30.9 0) (size 0.38 2.12) (layers "B.Cu" "B.Mask")
      (net 1 "GND") (pinfunction "A70") (pintype "passive"))
    (pad "B1" smd rect (at -18.205 -0.2) (size 0.38 1.72) (layers "F.Cu" "F.Mask")
      (net 59 "ESPI_CLK") (pinfunction "B1") (pintype "passive"))
    (pad "B2" smd rect (at -17.6 -0.2) (size 0.38 1.72) (layers "F.Cu" "F.Mask")
      (net 60 "ESPI_CS0_N") (pinfunction "B2") (pintype "passive"))
    (pad "B3" smd rect (at -17 -0.2) (size 0.38 1.72) (layers "F.Cu" "F.Mask")
      (net 61 "ESPI_ALERT_N") (pinfunction "B3") (pintype "passive"))
    (pad "B4" smd rect (at -16.4 -0.2) (size 0.38 1.72) (layers "F.Cu" "F.Mask")
      (net 62 "ESPI_RESET_N") (pinfunction "B4") (pintype "passive"))
    (pad "B5" smd rect (at -15.8 -0.2) (size 0.38 1.72) (layers "F.Cu" "F.Mask")
      (net 63 "ESPI_IO0") (pinfunction "B5") (pintype "passive"))
    (pad "B6" smd rect (at -15.2 -0.2) (size 0.38 1.72) (layers "F.Cu" "F.Mask")
      (net 64 "ESPI_IO1") (pinfunction "B6") (pintype "passive"))
    (pad "B7" smd rect (at -14.6 -0.2) (size 0.38 1.72) (layers "F.Cu" "F.Mask")
      (net 65 "ESPI_IO2") (pinfunction "B7") (pintype "passive"))
    (pad "B8" smd rect (at -14 -0.2) (size 0.38 1.72) (layers "F.Cu" "F.Mask")
      (net 66 "ESPI_IO3") (pinfunction "B8") (pintype "passive"))
    (pad "B9" smd rect (at -13.4 -0.2) (size 0.38 1.72) (layers "F.Cu" "F.Mask")
      (net 67 "ESPI_CS1_N") (pinfunction "B9") (pintype "passive"))
    (pad "B10" smd rect (at -12.8 0) (size 0.38 2.12) (layers "F.Cu" "F.Mask")
      (net 1 "GND") (pinfunction "B10") (pintype "passive"))
    (pad "B11" smd rect (at -12.2 -0.2) (size 0.38 1.72) (layers "F.Cu" "F.Mask")
      (net 68 "QSPI0_CLK") (pinfunction "B11") (pintype "passive"))
    (pad "B12" smd rect (at -11.6 -0.2) (size 0.38 1.72) (layers "F.Cu" "F.Mask")
      (net 69 "QSPI0_CS0_N") (pinfunction "B12") (pintype "passive"))
    (pad "B13" smd rect (at -11 -0.2) (size 0.38 1.72) (layers "F.Cu" "F.Mask")
      (net 70 "QSPI0_D0") (pinfunction "B13") (pintype "passive"))
    (pad "B14" smd rect (at -10.4 -0.2) (size 0.38 1.72) (layers "F.Cu" "F.Mask")
      (net 71 "QSPI0_D1") (pinfunction "B14") (pintype "passive"))
    (pad "B15" smd rect (at -9.8 -0.2) (size 0.38 1.72) (layers "F.Cu" "F.Mask")
      (net 72 "QSPI0_D2") (pinfunction "B15") (pintype "passive"))
    (pad "B16" smd rect (at -9.2 -0.2) (size 0.38 1.72) (layers "F.Cu" "F.Mask")
      (net 73 "QSPI0_D3") (pinfunction "B16") (pintype "passive"))
    (pad "B17" smd rect (at -8.6 0) (size 0.38 2.12) (layers "F.Cu" "F.Mask")
      (net 1 "GND") (pinfunction "B17") (pintype "passive"))
    (pad "B18" smd rect (at -8 -0.2) (size 0.38 1.72) (layers "F.Cu" "F.Mask")
      (net 74 "NCSI_CLK") (pinfunction "B18") (pintype "passive"))
    (pad "B19" smd rect (at -7.4 -0.2) (size 0.38 1.72) (layers "F.Cu" "F.Mask")
      (net 75 "NCSI_CRS_DV") (pinfunction "B19") (pintype "passive"))
    (pad "B20" smd rect (at -6.8 -0.2) (size 0.38 1.72) (layers "F.Cu" "F.Mask")
      (net 76 "NCSI_TXEN") (pinfunction "B20") (pintype "passive"))
    (pad "B21" smd rect (at -6.2 -0.2) (size 0.38 1.72) (layers "F.Cu" "F.Mask")
      (net 77 "NCSI_TXD0") (pinfunction "B21") (pintype "passive"))
    (pad "B22" smd rect (at -5.6 -0.2) (size 0.38 1.72) (layers "F.Cu" "F.Mask")
      (net 78 "NCSI_TXD1") (pinfunction "B22") (pintype "passive"))
    (pad "B23" smd rect (at -5 -0.2) (size 0.38 1.72) (layers "F.Cu" "F.Mask")
      (net 79 "NCSI_RXER") (pinfunction "B23") (pintype "passive"))
    (pad "B24" smd rect (at -4.4 -0.2) (size 0.38 1.72) (layers "F.Cu" "F.Mask")
      (net 80 "NCSI_RXD0") (pinfunction "B24") (pintype "passive"))
    (pad "B25" smd rect (at -3.8 -0.2) (size 0.38 1.72) (layers "F.Cu" "F.Mask")
      (net 81 "NCSI_RXD1") (pinfunction "B25") (pintype "passive"))
    (pad "B26" smd rect (at -3.2 0) (size 0.38 2.12) (layers "F.Cu" "F.Mask")
      (net 1 "GND") (pinfunction "B26") (pintype "passive"))
    (pad "B27" smd rect (at -2.6 -0.2) (size 0.38 1.72) (layers "F.Cu" "F.Mask")
      (net 421 "unconnected-(J5-PadB27)") (pinfunction "B27") (pintype "passive+no_connect"))
    (pad "B28" smd rect (at -2 -0.2) (size 0.38 1.72) (layers "F.Cu" "F.Mask")
      (net 424 "unconnected-(J5-PadB28)") (pinfunction "B28") (pintype "passive+no_connect"))
    (pad "B29" smd rect (at 2.01 -0.2) (size 0.38 1.72) (layers "F.Cu" "F.Mask")
      (net 82 "SGPIO0_DO") (pinfunction "B29") (pintype "passive"))
    (pad "B30" smd rect (at 2.6 -0.2) (size 0.38 1.72) (layers "F.Cu" "F.Mask")
      (net 83 "SGPIO0_CLK") (pinfunction "B30") (pintype "passive"))
    (pad "B31" smd rect (at 3.2 -0.2) (size 0.38 1.72) (layers "F.Cu" "F.Mask")
      (net 84 "SGPIO0_DI") (pinfunction "B31") (pintype "passive"))
    (pad "B32" smd rect (at 3.8 -0.2) (size 0.38 1.72) (layers "F.Cu" "F.Mask")
      (net 85 "SGPIO0_LD") (pinfunction "B32") (pintype "passive"))
    (pad "B33" smd rect (at 4.4 0) (size 0.38 2.12) (layers "F.Cu" "F.Mask")
      (net 1 "GND") (pinfunction "B33") (pintype "passive"))
    (pad "B34" smd rect (at 5 -0.2) (size 0.38 1.72) (layers "F.Cu" "F.Mask")
      (net 86 "SGPIO1_DO") (pinfunction "B34") (pintype "passive"))
    (pad "B35" smd rect (at 5.6 -0.2) (size 0.38 1.72) (layers "F.Cu" "F.Mask")
      (net 277 "SGPIO1_CLK") (pinfunction "B35") (pintype "passive"))
    (pad "B36" smd rect (at 6.2 -0.2) (size 0.38 1.72) (layers "F.Cu" "F.Mask")
      (net 87 "SGPIO1_DI") (pinfunction "B36") (pintype "passive"))
    (pad "B37" smd rect (at 6.8 -0.2) (size 0.38 1.72) (layers "F.Cu" "F.Mask")
      (net 88 "SGPIO1_LD") (pinfunction "B37") (pintype "passive"))
    (pad "B38" smd rect (at 7.4 0) (size 0.38 2.12) (layers "F.Cu" "F.Mask")
      (net 1 "GND") (pinfunction "B38") (pintype "passive"))
    (pad "B39" smd rect (at 8 -0.2) (size 0.38 1.72) (layers "F.Cu" "F.Mask")
      (net 89 "SGPIO_RESET_N") (pinfunction "B39") (pintype "passive"))
    (pad "B40" smd rect (at 8.6 -0.2) (size 0.38 1.72) (layers "F.Cu" "F.Mask")
      (net 90 "SGPIO_INTR_N") (pinfunction "B40") (pintype "passive"))
    (pad "B41" smd rect (at 9.2 -0.2) (size 0.38 1.72) (layers "F.Cu" "F.Mask")
      (net 414 "3V0_BAT") (pinfunction "B41") (pintype "passive"))
    (pad "B42" smd rect (at 9.8 -0.2) (size 0.38 1.72) (layers "F.Cu" "F.Mask")
      (net 91 "QSPI0_CS1_N") (pinfunction "B42") (pintype "passive"))
    (pad "B43" smd rect (at 14.715 -0.2) (size 0.38 1.72) (layers "F.Cu" "F.Mask")
      (net 92 "QSPI1_CLK") (pinfunction "B43") (pintype "passive"))
    (pad "B44" smd rect (at 15.3 -0.2) (size 0.38 1.72) (layers "F.Cu" "F.Mask")
      (net 93 "QSPI1_CS0_N") (pinfunction "B44") (pintype "passive"))
    (pad "B45" smd rect (at 15.9 -0.2) (size 0.38 1.72) (layers "F.Cu" "F.Mask")
      (net 94 "QSPI1_D0") (pinfunction "B45") (pintype "passive"))
    (pad "B46" smd rect (at 16.5 -0.2) (size 0.38 1.72) (layers "F.Cu" "F.Mask")
      (net 95 "QSPI1_D1") (pinfunction "B46") (pintype "passive"))
    (pad "B47" smd rect (at 17.1 -0.2) (size 0.38 1.72) (layers "F.Cu" "F.Mask")
      (net 96 "QSPI1_D2") (pinfunction "B47") (pintype "passive"))
    (pad "B48" smd rect (at 17.7 -0.2) (size 0.38 1.72) (layers "F.Cu" "F.Mask")
      (net 97 "QSPI1_D3") (pinfunction "B48") (pintype "passive"))
    (pad "B49" smd rect (at 18.3 0) (size 0.38 2.12) (layers "F.Cu" "F.Mask")
      (net 1 "GND") (pinfunction "B49") (pintype "passive"))
    (pad "B50" smd rect (at 18.9 -0.2) (size 0.38 1.72) (layers "F.Cu" "F.Mask")
      (net 98 "USB2_DP") (pinfunction "B50") (pintype "passive"))
    (pad "B51" smd rect (at 19.5 -0.2) (size 0.38 1.72) (layers "F.Cu" "F.Mask")
      (net 99 "USB2_DN") (pinfunction "B51") (pintype "passive"))
    (pad "B52" smd rect (at 20.1 0) (size 0.38 2.12) (layers "F.Cu" "F.Mask")
      (net 1 "GND") (pinfunction "B52") (pintype "passive"))
    (pad "B53" smd rect (at 20.7 -0.2) (size 0.38 1.72) (layers "F.Cu" "F.Mask")
      (net 100 "USB1_DP") (pinfunction "B53") (pintype "passive"))
    (pad "B54" smd rect (at 21.3 -0.2) (size 0.38 1.72) (layers "F.Cu" "F.Mask")
      (net 101 "USB1_DN") (pinfunction "B54") (pintype "passive"))
    (pad "B55" smd rect (at 21.9 0) (size 0.38 2.12) (layers "F.Cu" "F.Mask")
      (net 1 "GND") (pinfunction "B55") (pintype "passive"))
    (pad "B56" smd rect (at 22.5 -0.2) (size 0.38 1.72) (layers "F.Cu" "F.Mask")
      (net 264 "CLK_PCIE_x4_DP") (pinfunction "B56") (pintype "passive"))
    (pad "B57" smd rect (at 23.1 -0.2) (size 0.38 1.72) (layers "F.Cu" "F.Mask")
      (net 266 "CLK_PCIE_x4_DN") (pinfunction "B57") (pintype "passive"))
    (pad "B58" smd rect (at 23.7 0) (size 0.38 2.12) (layers "F.Cu" "F.Mask")
      (net 1 "GND") (pinfunction "B58") (pintype "passive"))
    (pad "B59" smd rect (at 24.3 -0.2) (size 0.38 1.72) (layers "F.Cu" "F.Mask")
      (net 688 "PCIE_HPM_TX0_P") (pinfunction "B59") (pintype "passive"))
    (pad "B60" smd rect (at 24.9 -0.2) (size 0.38 1.72) (layers "F.Cu" "F.Mask")
      (net 692 "PCIE_HPM_TX0_N") (pinfunction "B60") (pintype "passive"))
    (pad "B61" smd rect (at 25.5 0) (size 0.38 2.12) (layers "F.Cu" "F.Mask")
      (net 1 "GND") (pinfunction "B61") (pintype "passive"))
    (pad "B62" smd rect (at 26.1 -0.2) (size 0.38 1.72) (layers "F.Cu" "F.Mask")
      (net 689 "PCIE_HPM_TX1_P") (pinfunction "B62") (pintype "passive"))
    (pad "B63" smd rect (at 26.7 -0.2) (size 0.38 1.72) (layers "F.Cu" "F.Mask")
      (net 693 "PCIE_HPM_TX1_N") (pinfunction "B63") (pintype "passive"))
    (pad "B64" smd rect (at 27.3 0) (size 0.38 2.12) (layers "F.Cu" "F.Mask")
      (net 1 "GND") (pinfunction "B64") (pintype "passive"))
    (pad "B65" smd rect (at 27.9 -0.2) (size 0.38 1.72) (layers "F.Cu" "F.Mask")
      (net 690 "PCIE_HPM_TX2_P") (pinfunction "B65") (pintype "passive"))
    (pad "B66" smd rect (at 28.5 -0.2) (size 0.38 1.72) (layers "F.Cu" "F.Mask")
      (net 694 "PCIE_HPM_TX2_N") (pinfunction "B66") (pintype "passive"))
    (pad "B67" smd rect (at 29.1 0) (size 0.38 2.12) (layers "F.Cu" "F.Mask")
      (net 1 "GND") (pinfunction "B67") (pintype "passive"))
    (pad "B68" smd rect (at 29.7 -0.2) (size 0.38 1.72) (layers "F.Cu" "F.Mask")
      (net 691 "PCIE_HPM_TX3_P") (pinfunction "B68") (pintype "passive"))
    (pad "B69" smd rect (at 30.3 -0.2) (size 0.38 1.72) (layers "F.Cu" "F.Mask")
      (net 695 "PCIE_HPM_TX3_N") (pinfunction "B69") (pintype "passive"))
    (pad "B70" smd rect (at 30.9 0) (size 0.38 2.12) (layers "F.Cu" "F.Mask")
      (net 1 "GND") (pinfunction "B70") (pintype "passive"))
    (pad "OA1" smd rect (at -30.4 -0.2) (size 0.38 1.72) (layers "B.Cu" "B.Mask")
      (net 57 "P12V_AUX") (pinfunction "OA1") (pintype "passive"))
    (pad "OA2" smd rect (at -29.8 -0.2) (size 0.38 1.72) (layers "B.Cu" "B.Mask")
      (net 57 "P12V_AUX") (pinfunction "OA2") (pintype "passive"))
    (pad "OA3" smd rect (at -29.2 0) (size 0.38 2.12) (layers "B.Cu" "B.Mask")
      (net 1 "GND") (pinfunction "OA3") (pintype "passive"))
    (pad "OA4" smd rect (at -28.6 0) (size 0.38 2.12) (layers "B.Cu" "B.Mask")
      (net 1 "GND") (pinfunction "OA4") (pintype "passive"))
    (pad "OA5" smd rect (at -28 -0.2) (size 0.38 1.72) (layers "B.Cu" "B.Mask")
      (net 206 "I3C[0]_SCL_1V0") (pinfunction "OA5") (pintype "passive"))
    (pad "OA6" smd rect (at -27.4 -0.2) (size 0.38 1.72) (layers "B.Cu" "B.Mask")
      (net 205 "I3C[0]_SDA_1V0") (pinfunction "OA6") (pintype "passive"))
    (pad "OA7" smd rect (at -26.8 -0.2) (size 0.38 1.72) (layers "B.Cu" "B.Mask")
      (net 208 "I3C[1]_SCL_1V0") (pinfunction "OA7") (pintype "passive"))
    (pad "OA8" smd rect (at -26.2 -0.2) (size 0.38 1.72) (layers "B.Cu" "B.Mask")
      (net 207 "I3C[1]_SDA_1V0") (pinfunction "OA8") (pintype "passive"))
    (pad "OA9" smd rect (at -25.6 -0.2) (size 0.38 1.72) (layers "B.Cu" "B.Mask")
      (net 210 "I3C[2]_SCL_1V0") (pinfunction "OA9") (pintype "passive"))
    (pad "OA10" smd rect (at -25 -0.2) (size 0.38 1.72) (layers "B.Cu" "B.Mask")
      (net 209 "I3C[2]_SDA_1V0") (pinfunction "OA10") (pintype "passive"))
    (pad "OA11" smd rect (at -24.4 -0.2) (size 0.38 1.72) (layers "B.Cu" "B.Mask")
      (net 204 "I3C[3]_SCL_1V0") (pinfunction "OA11") (pintype "passive"))
    (pad "OA12" smd rect (at -23.8 -0.2) (size 0.38 1.72) (layers "B.Cu" "B.Mask")
      (net 203 "I3C[3]_SDA_1V0") (pinfunction "OA12") (pintype "passive"))
    (pad "OA13" smd rect (at -23.2 0) (size 0.38 2.12) (layers "B.Cu" "B.Mask")
      (net 1 "GND") (pinfunction "OA13") (pintype "passive"))
    (pad "OA14" smd rect (at -22.6 -0.2) (size 0.38 1.72) (layers "B.Cu" "B.Mask")
      (net 102 "VIRTUAL_RESEAT") (pinfunction "OA14") (pintype "passive"))
    (pad "OB1" smd rect (at -30.4 -0.2) (size 0.38 1.72) (layers "F.Cu" "F.Mask")
      (net 57 "P12V_AUX") (pinfunction "OB1") (pintype "passive"))
    (pad "OB2" smd rect (at -29.8 -0.2) (size 0.38 1.72) (layers "F.Cu" "F.Mask")
      (net 57 "P12V_AUX") (pinfunction "OB2") (pintype "passive"))
    (pad "OB3" smd rect (at -29.2 -0.2) (size 0.38 1.72) (layers "F.Cu" "F.Mask")
      (net 58 "PRSNT0_N") (pinfunction "OB3") (pintype "passive"))
    (pad "OB4" smd rect (at -28.6 0) (size 0.38 2.12) (layers "F.Cu" "F.Mask")
      (net 1 "GND") (pinfunction "OB4") (pintype "passive"))
    (pad "OB5" smd rect (at -28 -0.2) (size 0.38 1.72) (layers "F.Cu" "F.Mask")
      (net 46 "UART1_SCM_TX") (pinfunction "OB5") (pintype "passive"))
    (pad "OB6" smd rect (at -27.4 -0.2) (size 0.38 1.72) (layers "F.Cu" "F.Mask")
      (net 39 "UART1_SCM_RX") (pinfunction "OB6") (pintype "passive"))
    (pad "OB7" smd rect (at -26.8 0) (size 0.38 2.12) (layers "F.Cu" "F.Mask")
      (net 1 "GND") (pinfunction "OB7") (pintype "passive"))
    (pad "OB8" smd rect (at -26.2 -0.2) (size 0.38 1.72) (layers "F.Cu" "F.Mask")
      (net 41 "UART0_SCM_TX") (pinfunction "OB8") (pintype "passive"))
    (pad "OB9" smd rect (at -25.6 -0.2) (size 0.38 1.72) (layers "F.Cu" "F.Mask")
      (net 45 "UART0_SCM_RX") (pinfunction "OB9") (pintype "passive"))
    (pad "OB10" smd rect (at -25 0) (size 0.38 2.12) (layers "F.Cu" "F.Mask")
      (net 1 "GND") (pinfunction "OB10") (pintype "passive"))
    (pad "OB11" smd rect (at -24.4 -0.2) (size 0.38 1.72) (layers "F.Cu" "F.Mask")
      (net 54 "SPI0_CLK") (pinfunction "OB11") (pintype "passive"))
    (pad "OB12" smd rect (at -23.8 -0.2) (size 0.38 1.72) (layers "F.Cu" "F.Mask")
      (net 53 "SPI0_CS_N") (pinfunction "OB12") (pintype "passive"))
    (pad "OB13" smd rect (at -23.2 -0.2) (size 0.38 1.72) (layers "F.Cu" "F.Mask")
      (net 55 "SPI0_MOSI") (pinfunction "OB13") (pintype "passive"))
    (pad "OB14" smd rect (at -22.6 -0.2) (size 0.38 1.72) (layers "F.Cu" "F.Mask")
      (net 56 "SPI0_MISO") (pinfunction "OB14") (pintype "passive"))
  )

  (footprint "antmicro-footprints:USB-Micro-B_Receptacle_Amphenol_10118192" (layer "F.Cu")
    (at 126.24 62.069 180)
    (property "Author" "Antmicro")
    (property "License" "Apache-2.0")
    (property "MPN" "10118192-0001LF")
    (property "Manufacturer" "Amphenol")
    (property "Sheetfile" "interfaces.kicad_sch")
    (property "Sheetname" "Interfaces")
    (property "ki_description" "USB - micro B USB 2.0 Receptacle Connector 5 Position Surface Mount, Right Angle")
    (property "ki_keywords" "USB, MICRO, CONNECTOR, SMT, HORIZONTAL")
    (attr smd)
    (fp_text reference "J6" (at 5.925 -3.175) (layer "F.SilkS")
        (effects (font (size 0.7 0.7) (thickness 0.127)))
    )
    (fp_text value "USB-Micro-B_Amphenol_10118192-0001LF" (at 0 4.25) (layer "F.Fab")
        (effects (font (size 1 1) (thickness 0.15)))
    )
    (fp_text user "${REFERENCE}" (at 0 0) (layer "F.Fab")
        (effects (font (size 1 1) (thickness 0.15)))
    )
    (fp_text user "Author: Antmicro" (at -5 7.9 180) (layer "F.Fab") hide
        (effects (font (size 0.7 0.7) (thickness 0.15)) (justify left bottom))
    )
    (fp_text user "License: Apache-2.0" (at -5 9.099 180) (layer "F.Fab") hide
        (effects (font (size 0.7 0.7) (thickness 0.15)) (justify left bottom))
    )
    (fp_line (start -4.05 -1.151) (end -4.05 -0.701)
      (stroke (width 0.15) (type solid)) (layer "F.SilkS"))
    (fp_line (start -1.901 -2.902) (end -1.601 -2.902)
      (stroke (width 0.15) (type solid)) (layer "F.SilkS"))
    (fp_line (start 1.65 -2.902) (end 1.949 -2.902)
      (stroke (width 0.15) (type solid)) (layer "F.SilkS"))
    (fp_line (start 4.049 -1.151) (end 4.049 -0.652)
      (stroke (width 0.15) (type solid)) (layer "F.SilkS"))
    (fp_circle (center -1.75 -3.15) (end -1.7 -3.15)
      (stroke (width 0.15) (type solid)) (fill none) (layer "F.SilkS"))
    (fp_rect (start -4.758 -3.051) (end 4.755 3.048)
      (stroke (width 0.05) (type solid)) (fill none) (layer "F.CrtYd"))
    (fp_line (start -3.951 -2.351) (end -3.951 2.749)
      (stroke (width 0.15) (type solid)) (layer "F.Fab"))
    (fp_line (start -3.951 -2.351) (end -3.5 -2.801)
      (stroke (width 0.15) (type solid)) (layer "F.Fab"))
    (fp_line (start -3.951 2.769) (end 3.95 2.769)
      (stroke (width 0.15) (type solid)) (layer "F.Fab"))
    (fp_line (start 3.95 -2.801) (end -3.5 -2.801)
      (stroke (width 0.15) (type solid)) (layer "F.Fab"))
    (fp_line (start 3.95 2.769) (end 3.95 -2.801)
      (stroke (width 0.15) (type solid)) (layer "F.Fab"))
    (pad "1" smd rect (at -1.301 -2.226 180) (size 0.4 1.35) (layers "F.Cu" "F.Paste" "F.Mask")
      (net 415 "VBUS") (pinfunction "VBUS") (pintype "passive"))
    (pad "2" smd rect (at -0.651 -2.226 180) (size 0.4 1.35) (layers "F.Cu" "F.Paste" "F.Mask")
      (net 416 "DBG_USB_D_N") (pinfunction "D-") (pintype "bidirectional"))
    (pad "3" smd rect (at 0 -2.226 180) (size 0.4 1.35) (layers "F.Cu" "F.Paste" "F.Mask")
      (net 417 "DBG_USB_D_P") (pinfunction "D+") (pintype "bidirectional"))
    (pad "4" smd rect (at 0.65 -2.226 180) (size 0.4 1.35) (layers "F.Cu" "F.Paste" "F.Mask")
      (net 388 "Net-(J6-ID)") (pinfunction "ID") (pintype "bidirectional"))
    (pad "5" smd rect (at 1.3 -2.226 180) (size 0.4 1.35) (layers "F.Cu" "F.Paste" "F.Mask")
      (net 1 "GND") (pinfunction "GND") (pintype "power_in"))
    (pad "SH" smd roundrect (at -3.801 0.449 180) (size 1.8 1.9) (layers "F.Cu" "F.Paste" "F.Mask") (roundrect_rratio 0.1)
      (net 1 "GND") (pinfunction "SHIELD") (pintype "passive"))
    (pad "SH" smd roundrect (at -3.101 -2.101 180) (size 2.1 1.6) (layers "F.Cu" "F.Paste" "F.Mask") (roundrect_rratio 0.1)
      (net 1 "GND") (pinfunction "SHIELD") (pintype "passive"))
    (pad "SH" smd roundrect (at -1.2 0.449 180) (size 1.9 1.9) (layers "F.Cu" "F.Paste" "F.Mask") (roundrect_rratio 0.1)
      (net 1 "GND") (pinfunction "SHIELD") (pintype "passive"))
    (pad "SH" smd roundrect (at 1.199 0.449 180) (size 1.9 1.9) (layers "F.Cu" "F.Paste" "F.Mask") (roundrect_rratio 0.1)
      (net 1 "GND") (pinfunction "SHIELD") (pintype "passive"))
    (pad "SH" smd roundrect (at 3.1 -2.101 180) (size 2.1 1.6) (layers "F.Cu" "F.Paste" "F.Mask") (roundrect_rratio 0.1)
      (net 1 "GND") (pinfunction "SHIELD") (pintype "passive"))
    (pad "SH" smd roundrect (at 3.8 0.449 180) (size 1.8 1.9) (layers "F.Cu" "F.Paste" "F.Mask") (roundrect_rratio 0.1)
      (net 1 "GND") (pinfunction "SHIELD") (pintype "passive"))
  )

  (footprint "antmicro-footprints:C_0402_1005Metric" (layer "F.Cu")
    (at 78.28 79.07 180)
    (descr "Capacitor SMD 0402")
    (tags "capacitor SMD 0402")
    (property "Author" "Antmicro")
    (property "Dielectric" "")
    (property "License" "Apache-2.0")
    (property "MPN" "CC0402MRX5R5BB106")
    (property "Manufacturer" "YAGEO")
    (property "Public" "False")
    (property "Sheetfile" "power-supply.kicad_sch")
    (property "Sheetname" "Power supply")
    (property "Val" "10u")
    (property "Voltage" "")
    (property "ki_description" "SMD Multilayer Ceramic Capacitor, 10 µF, 6.3 V, 0402 [1005 Metric], ± 20%, X5R, CC Series")
    (property "ki_keywords" "0402, SMT, CAPACITOR, PASSIVE, MLCC, CERAMIC")
    (attr smd)
    (fp_text reference "C262" (at -2.43 -0.015) (layer "F.SilkS")
        (effects (font (size 0.7 0.7) (thickness 0.127)))
    )
    (fp_text value "C_10u_0402" (at 0 1.17) (layer "F.Fab")
        (effects (font (size 1 1) (thickness 0.15)))
    )
    (fp_text user "Author: Antmicro" (at -0.939 3.399 180) (layer "F.Fab") hide
        (effects (font (size 0.7 0.7) (thickness 0.15)) (justify left bottom))
    )
    (fp_text user "License: Apache-2.0" (at -0.939 5.799 180) (layer "F.Fab") hide
        (effects (font (size 0.7 0.7) (thickness 0.15)) (justify left bottom))
    )
    (fp_text user "${REFERENCE}" (at 0 0) (layer "F.Fab")
        (effects (font (size 0.25 0.25) (thickness 0.04)))
    )
    (fp_rect (start -0.925 -0.47) (end 0.925 0.47)
      (stroke (width 0.05) (type default)) (fill none) (layer "F.CrtYd"))
    (fp_line (start -0.494 -0.25) (end 0.504 -0.25)
      (stroke (width 0.15) (type solid)) (layer "F.Fab"))
    (fp_line (start -0.494 0.248) (end -0.494 -0.25)
      (stroke (width 0.15) (type solid)) (layer "F.Fab"))
    (fp_line (start 0.504 -0.25) (end 0.504 0.248)
      (stroke (width 0.15) (type solid)) (layer "F.Fab"))
    (fp_line (start 0.504 0.248) (end -0.494 0.248)
      (stroke (width 0.15) (type solid)) (layer "F.Fab"))
    (pad "1" smd roundrect (at -0.48 0 180) (size 0.59 0.64) (layers "F.Cu" "F.Paste" "F.Mask") (roundrect_rratio 0.25)
      (net 1 "GND") (pintype "passive"))
    (pad "2" smd roundrect (at 0.48 0 180) (size 0.59 0.64) (layers "F.Cu" "F.Paste" "F.Mask") (roundrect_rratio 0.25)
      (net 270 "/Power supply/5V0_PG") (pintype "passive"))
  )

  (footprint "antmicro-footprints:R_0402_1005Metric" (layer "F.Cu")
    (at 80.24 73.64 -90)
    (descr "Resistor SMD 0402")
    (tags "resistor SMD 0402")
    (property "Author" "Antmicro")
    (property "License" "Apache-2.0")
    (property "MPN" "CR0402-FX-1003GLF")
    (property "Manufacturer" "Bourns")
    (property "Public" "False")
    (property "Sheetfile" "power-supply.kicad_sch")
    (property "Sheetname" "Power supply")
    (property "Tolerance" "1%")
    (property "Val" "100k")
    (property "ki_description" "SMD Chip Resistor, 100 kohm, ± 1%, 62.5 mW, 0402 [1005 Metric], Thick Film, General Purpose")
    (property "ki_keywords" "0402, SMT, RESISTOR, PASSIVE")
    (attr smd)
    (fp_text reference "R8" (at -2.128167 4.86 90) (layer "F.SilkS")
        (effects (font (size 0.7 0.7) (thickness 0.127)))
    )
    (fp_text value "R_100k_0402" (at 0 1.17 90) (layer "F.Fab")
        (effects (font (size 1 1) (thickness 0.15)))
    )
    (fp_text user "License: Apache-2.0" (at -0.95 5.169 -90) (layer "F.Fab") hide
        (effects (font (size 0.7 0.7) (thickness 0.15)) (justify left bottom))
    )
    (fp_text user "${REFERENCE}" (at 0 0 90) (layer "F.Fab")
        (effects (font (size 0.25 0.25) (thickness 0.04)))
    )
    (fp_text user "Author: Antmicro" (at -0.95 4.169 -90) (layer "F.Fab") hide
        (effects (font (size 0.7 0.7) (thickness 0.15)) (justify left bottom))
    )
    (fp_rect (start -0.925 -0.47) (end 0.925 0.47)
      (stroke (width 0.05) (type default)) (fill none) (layer "F.CrtYd"))
    (fp_rect (start -0.5 -0.25) (end 0.5 0.25)
      (stroke (width 0.15) (type solid)) (fill none) (layer "F.Fab"))
    (pad "1" smd roundrect (at -0.48 0 270) (size 0.59 0.64) (layers "F.Cu" "F.Paste" "F.Mask") (roundrect_rratio 0.25)
      (net 11 "VCC5V0") (pintype "passive"))
    (pad "2" smd roundrect (at 0.48 0 270) (size 0.59 0.64) (layers "F.Cu" "F.Paste" "F.Mask") (roundrect_rratio 0.25)
      (net 270 "/Power supply/5V0_PG") (pintype "passive"))
  )

  (footprint "antmicro-footprints:TP_SMD_1mm" (layer "F.Cu")
    (at 83.025 106.225)
    (property "Author" "Antmicro")
    (property "License" "Apache-2.0")
    (property "MPN" "")
    (property "Manufacturer" "")
    (property "Sheetfile" "interfaces.kicad_sch")
    (property "Sheetname" "Interfaces")
    (property "exclude_from_bom" "")
    (property "ki_description" "Test point 1mm SMD")
    (property "ki_keywords" "TESTPOINT")
    (attr exclude_from_pos_files exclude_from_bom)
    (fp_text reference "TP16" (at -1.315 1.66) (layer "F.SilkS")
        (effects (font (size 0.7 0.7) (thickness 0.15)) (justify left bottom))
    )
    (fp_text value "TP_1mm_SMD" (at 0 1.4) (layer "F.Fab")
        (effects (font (size 0.7 0.7) (thickness 0.15)) (justify left bottom))
    )
    (fp_text user "License: Apache-2.0" (at -0.5 5.2) (layer "F.Fab") hide
        (effects (font (size 0.7 0.7) (thickness 0.15)) (justify left bottom))
    )
    (fp_text user "${REFERENCE}" (at -0.5 2.8) (layer "F.Fab") hide
        (effects (font (size 0.7 0.7) (thickness 0.15)) (justify left bottom))
    )
    (fp_text user "Author: Antmicro" (at -0.5 4) (layer "F.Fab") hide
        (effects (font (size 0.7 0.7) (thickness 0.15)) (justify left bottom))
    )
    (fp_circle (center 0 0) (end 0.6 0)
      (stroke (width 0.05) (type default)) (fill none) (layer "F.CrtYd"))
    (pad "1" smd circle (at 0 0) (size 1 1) (layers "F.Cu" "F.Mask")
      (net 437 "Net-(U6-DS)") (pinfunction "1") (pintype "passive"))
  )

  (footprint "antmicro-footprints:R_0603_1608Metric" (layer "F.Cu")
    (at 74.55 87.2 90)
    (descr "Resistor SMD 0603")
    (tags "resistor SMD 0603")
    (property "Author" "Antmicro")
    (property "Current" "1A")
    (property "License" "Apache-2.0")
    (property "MPN" "CR0603-J/-000ELF")
    (property "Manufacturer" "Bourns")
    (property "Public" "False")
    (property "Sheetfile" "power-supply.kicad_sch")
    (property "Sheetname" "Power supply")
    (property "Tolerance" "")
    (property "Val" "0R")
    (property "ki_description" "Zero Ohm Resistor, Jumper, 0603 [1608 Metric], Thick Film, 100 mW, 1 A, Surface Mount Device, CR")
    (property "ki_keywords" "0603, SMT, RESISTOR, PASSIVE")
    (attr smd)
    (fp_text reference "R144" (at 0.175 -0.97 90) (layer "F.SilkS")
        (effects (font (size 0.7 0.7) (thickness 0.127)))
    )
    (fp_text value "R_0R_0603" (at 0 1.9 90) (layer "F.Fab")
        (effects (font (size 1 1) (thickness 0.15)))
    )
    (fp_text user "${REFERENCE}" (at -1.25 3.898 90) (layer "F.Fab") hide
        (effects (font (size 0.7 0.7) (thickness 0.15)) (justify left bottom))
    )
    (fp_text user "Author: Antmicro" (at -1.25 4.9 90) (layer "F.Fab") hide
        (effects (font (size 0.7 0.7) (thickness 0.15)) (justify left bottom))
    )
    (fp_text user "License: Apache-2.0" (at -1.25 5.9 90) (layer "F.Fab") hide
        (effects (font (size 0.7 0.7) (thickness 0.15)) (justify left bottom))
    )
    (fp_line (start -0.15 -0.4) (end 0.15 -0.4)
      (stroke (width 0.15) (type solid)) (layer "F.SilkS"))
    (fp_line (start -0.15 0.4) (end 0.15 0.4)
      (stroke (width 0.15) (type solid)) (layer "F.SilkS"))
    (fp_rect (start -1.25 -0.65) (end 1.25 0.65)
      (stroke (width 0.05) (type solid)) (fill none) (layer "F.CrtYd"))
    (fp_rect (start -0.8 -0.4) (end 0.8 0.4)
      (stroke (width 0.15) (type solid)) (fill none) (layer "F.Fab"))
    (pad "1" smd roundrect (at -0.7 0 90) (size 0.8 1) (layers "F.Cu" "F.Paste" "F.Mask") (roundrect_rratio 0.2)
      (net 12 "VCC1V0") (pintype "passive"))
    (pad "2" smd roundrect (at 0.7 0 90) (size 0.8 1) (layers "F.Cu" "F.Paste" "F.Mask") (roundrect_rratio 0.2)
      (net 358 "Net-(C121-Pad2)") (pintype "passive"))
  )

  (footprint "antmicro-footprints:QFN-8_2x1.5mm" (layer "F.Cu")
    (at 89.1 86.15 90)
    (property "Author" "Antmicro")
    (property "License" "Apache-2.0")
    (property "MPN" "TPS62823DLCT")
    (property "Manufacturer" "Texas Instruments")
    (property "Sheetfile" "power-supply.kicad_sch")
    (property "Sheetname" "Power supply")
    (property "ki_description" "DC/DC converter")
    (property "ki_keywords" "SMT, PMIC, IC, SWITCHING, VOLTAGE, REGULATOR, DC-DC")
    (attr smd)
    (fp_text reference "U16" (at -0.455 1.96 90) (layer "F.SilkS")
        (effects (font (size 0.7 0.7) (thickness 0.127)))
    )
    (fp_text value "TPS62823DLCT" (at 0 2.075 90) (layer "F.Fab")
        (effects (font (size 1 1) (thickness 0.15)))
    )
    (fp_text user "Author: Antmicro" (at -1.651 5.275 90) (layer "F.Fab") hide
        (effects (font (size 0.7 0.7) (thickness 0.15)) (justify left bottom))
    )
    (fp_text user "${REFERENCE}" (at 0 0 90) (layer "F.Fab")
        (effects (font (size 0.5 0.5) (thickness 0.075)))
    )
    (fp_text user "License: Apache-2.0" (at -1.651 6.475 90) (layer "F.Fab") hide
        (effects (font (size 0.7 0.7) (thickness 0.15)) (justify left bottom))
    )
    (fp_line (start -0.9 1.05) (end 0.9 1.05)
      (stroke (width 0.15) (type solid)) (layer "F.SilkS"))
    (fp_line (start -0.25 -1.05) (end 0.9 -1.05)
      (stroke (width 0.15) (type solid)) (layer "F.SilkS"))
    (fp_circle (center -0.9 -1.05) (end -0.849 -1.05)
      (stroke (width 0.15) (type solid)) (fill solid) (layer "F.SilkS"))
    (fp_rect (start -1.1 -1.25) (end 1.1 1.25)
      (stroke (width 0.05) (type solid)) (fill none) (layer "F.CrtYd"))
    (fp_line (start -1 -0.5) (end -0.5 -1)
      (stroke (width 0.15) (type solid)) (layer "F.Fab"))
    (fp_line (start -1 0.998) (end -1 -0.5)
      (stroke (width 0.15) (type solid)) (layer "F.Fab"))
    (fp_line (start -0.5 -1) (end 0.998 -1)
      (stroke (width 0.15) (type solid)) (layer "F.Fab"))
    (fp_line (start 0.998 -1) (end 0.998 0.998)
      (stroke (width 0.15) (type solid)) (layer "F.Fab"))
    (fp_line (start 0.998 0.998) (end -1 0.998)
      (stroke (width 0.15) (type solid)) (layer "F.Fab"))
    (pad "1" smd rect (at -0.677 -0.75 90) (size 0.55 0.25) (layers "F.Cu" "F.Paste" "F.Mask")
      (net 230 "/Power supply/VCCAUX_EN") (pinfunction "EN") (pintype "input"))
    (pad "2" smd rect (at -0.677 -0.25 90) (size 0.55 0.25) (layers "F.Cu" "F.Paste" "F.Mask")
      (net 301 "Net-(U16-FB)") (pinfunction "FB") (pintype "bidirectional"))
    (pad "3" smd rect (at -0.677 0.248 90) (size 0.55 0.25) (layers "F.Cu" "F.Paste" "F.Mask")
      (net 1 "GND") (pinfunction "AGND") (pintype "power_in"))
    (pad "4" smd rect (at -0.677 0.748 90) (size 0.55 0.25) (layers "F.Cu" "F.Paste" "F.Mask")
      (net 542 "unconnected-(U16-NC-Pad4)") (pinfunction "NC") (pintype "no_connect"))
    (pad "5" smd rect (at 0.675 0.748 90) (size 0.55 0.25) (layers "F.Cu" "F.Paste" "F.Mask")
      (net 1 "GND") (pinfunction "PGND") (pintype "power_in"))
    (pad "6" smd rect (at 0.675 0.248 90) (size 0.55 0.25) (layers "F.Cu" "F.Paste" "F.Mask")
      (net 393 "Net-(U16-SW)") (pinfunction "SW") (pintype "bidirectional"))
    (pad "7" smd rect (at 0.675 -0.25 90) (size 0.55 0.25) (layers "F.Cu" "F.Paste" "F.Mask")
      (net 11 "VCC5V0") (pinfunction "VIN") (pintype "power_in"))
    (pad "8" smd rect (at 0.675 -0.75 90) (size 0.55 0.25) (layers "F.Cu" "F.Paste" "F.Mask")
      (net 236 "/Power supply/2V5_PG") (pinfunction "PG") (pintype "output"))
  )

  (footprint "antmicro-footprints:BGA-170-100_18x14mm_Layout17x10_P1mm" (layer "F.Cu")
    (at 88.2 98.05 90)
    (descr "Uses depopulated JEDEC-MO-304B")
    (property "Author" "Antmicro")
    (property "License" "Apache-2.0")
    (property "MANUFACTURER" "Micron")
    (property "MPN" "MTFC16GAPALNA-AIT")
    (property "Manufacturer" "Micron Technology")
    (property "Package" "100-ball TBGA 14x18")
    (property "Sheetfile" "interfaces.kicad_sch")
    (property "Sheetname" "Interfaces")
    (property "ki_description" "Managed NAND Flash Serial e-MMC 3.3V 128G-bit 128G/32G/16G x 1/4-bit/8-bit Automotive AEC-Q100 100-Pin TBGA Tray")
    (property "ki_keywords" "SMT, FLASH, IC")
    (attr smd)
    (fp_text reference "U6" (at -8.075 -8 180) (layer "F.SilkS")
        (effects (font (size 0.7 0.7) (thickness 0.127)))
    )
    (fp_text value "MTFC16GAPALNA-AIT" (at 16.305925 13.334495 90) (layer "F.Fab")
        (effects (font (size 1.339362 1.339362) (thickness 0.015)))
    )
    (fp_text user "License: Apache-2.0" (at -7.4 12.3 90) (layer "F.Fab") hide
        (effects (font (size 0.7 0.7) (thickness 0.15)) (justify left bottom))
    )
    (fp_text user "Author: Antmicro" (at -7.4 14.7 90) (layer "F.Fab") hide
        (effects (font (size 0.7 0.7) (thickness 0.15)) (justify left bottom))
    )
    (fp_text user "${REFERENCE}" (at -7.4 13.5 90) (layer "F.Fab") hide
        (effects (font (size 0.7 0.7) (thickness 0.15)) (justify left bottom))
    )
    (fp_line (start -7 8.999) (end -7 -9)
      (stroke (width 0.15) (type solid)) (layer "F.SilkS"))
    (fp_line (start 6.998 -9) (end -7 -9)
      (stroke (width 0.15) (type solid)) (layer "F.SilkS"))
    (fp_line (start 6.998 8.999) (end -7 8.999)
      (stroke (width 0.15) (type solid)) (layer "F.SilkS"))
    (fp_line (start 6.998 8.999) (end 6.998 -9)
      (stroke (width 0.15) (type solid)) (layer "F.SilkS"))
    (fp_circle (center -7.2 -9.2) (end -7.15 -9.2)
      (stroke (width 0.15) (type solid)) (fill solid) (layer "F.SilkS"))
    (fp_rect (start -7.3 -9.3) (end 7.3 9.3)
      (stroke (width 0.05) (type solid)) (fill none) (layer "F.CrtYd"))
    (fp_line (start -7 8.999) (end -7 -9)
      (stroke (width 0.15) (type solid)) (layer "F.Fab"))
    (fp_line (start 6.998 -9) (end -7 -9)
      (stroke (width 0.15) (type solid)) (layer "F.Fab"))
    (fp_line (start 6.998 8.999) (end -7 8.999)
      (stroke (width 0.15) (type solid)) (layer "F.Fab"))
    (fp_line (start 6.998 8.999) (end 6.998 -9)
      (stroke (width 0.15) (type solid)) (layer "F.Fab"))
    (pad "A1" smd circle (at -4.5 -8 90) (size 0.37 0.37) (layers "F.Cu" "F.Paste" "F.Mask")
      (net 442 "unconnected-(U6-NC-PadA1)") (pinfunction "NC") (pintype "no_connect"))
    (pad "A2" smd circle (at -3.5 -8 90) (size 0.37 0.37) (layers "F.Cu" "F.Paste" "F.Mask")
      (net 443 "unconnected-(U6-NC-PadA2)") (pinfunction "NC") (pintype "no_connect"))
    (pad "A9" smd circle (at 3.499 -8 90) (size 0.37 0.37) (layers "F.Cu" "F.Paste" "F.Mask")
      (net 444 "unconnected-(U6-NC-PadA9)") (pinfunction "NC") (pintype "no_connect"))
    (pad "A10" smd circle (at 4.499 -8 90) (size 0.37 0.37) (layers "F.Cu" "F.Paste" "F.Mask")
      (net 445 "unconnected-(U6-NC-PadA10)") (pinfunction "NC") (pintype "no_connect"))
    (pad "B1" smd circle (at -4.5 -7 90) (size 0.37 0.37) (layers "F.Cu" "F.Paste" "F.Mask")
      (net 446 "unconnected-(U6-NC-PadB1)") (pinfunction "NC") (pintype "no_connect"))
    (pad "B10" smd circle (at 4.499 -7 90) (size 0.37 0.37) (layers "F.Cu" "F.Paste" "F.Mask")
      (net 447 "unconnected-(U6-NC-PadB10)") (pinfunction "NC") (pintype "no_connect"))
    (pad "D2" smd circle (at -3.5 -5 90) (size 0.37 0.37) (layers "F.Cu" "F.Paste" "F.Mask")
      (net 448 "unconnected-(U6-VSF1-PadD2)") (pinfunction "VSF1") (pintype "no_connect"))
    (pad "D3" smd circle (at -2.5 -5 90) (size 0.37 0.37) (layers "F.Cu" "F.Paste" "F.Mask")
      (net 449 "unconnected-(U6-VSF2-PadD3)") (pinfunction "VSF2") (pintype "no_connect"))
    (pad "D4" smd circle (at -1.5 -5 90) (size 0.37 0.37) (layers "F.Cu" "F.Paste" "F.Mask")
      (net 450 "unconnected-(U6-VSF3-PadD4)") (pinfunction "VSF3") (pintype "no_connect"))
    (pad "D5" smd circle (at -0.5 -5 90) (size 0.37 0.37) (layers "F.Cu" "F.Paste" "F.Mask")
      (net 451 "unconnected-(U6-VSF4-PadD5)") (pinfunction "VSF4") (pintype "no_connect"))
    (pad "D6" smd circle (at 0.499 -5 90) (size 0.37 0.37) (layers "F.Cu" "F.Paste" "F.Mask")
      (net 452 "unconnected-(U6-VSF5-PadD6)") (pinfunction "VSF5") (pintype "no_connect"))
    (pad "D7" smd circle (at 1.499 -5 90) (size 0.37 0.37) (layers "F.Cu" "F.Paste" "F.Mask")
      (net 453 "unconnected-(U6-VSF6-PadD7)") (pinfunction "VSF6") (pintype "no_connect"))
    (pad "D8" smd circle (at 2.499 -5 90) (size 0.37 0.37) (layers "F.Cu" "F.Paste" "F.Mask")
      (net 454 "unconnected-(U6-VSF7-PadD8)") (pinfunction "VSF7") (pintype "no_connect"))
    (pad "D9" smd circle (at 3.499 -5 90) (size 0.37 0.37) (layers "F.Cu" "F.Paste" "F.Mask")
      (net 455 "unconnected-(U6-VSF8-PadD9)") (pinfunction "VSF8") (pintype "no_connect"))
    (pad "E2" smd circle (at -3.5 -4 90) (size 0.37 0.37) (layers "F.Cu" "F.Paste" "F.Mask")
      (net 456 "unconnected-(U6-RFU-PadE2)") (pinfunction "RFU") (pintype "no_connect"))
    (pad "E3" smd circle (at -2.5 -4 90) (size 0.37 0.37) (layers "F.Cu" "F.Paste" "F.Mask")
      (net 457 "unconnected-(U6-RFU-PadE3)") (pinfunction "RFU") (pintype "no_connect"))
    (pad "E4" smd circle (at -1.5 -4 90) (size 0.37 0.37) (layers "F.Cu" "F.Paste" "F.Mask")
      (net 219 "Net-(U6-VDDIM)") (pinfunction "VDDIM") (pintype "power_in"))
    (pad "E5" smd circle (at -0.5 -4 90) (size 0.37 0.37) (layers "F.Cu" "F.Paste" "F.Mask")
      (net 458 "unconnected-(U6-RFU-PadE5)") (pinfunction "RFU") (pintype "no_connect"))
    (pad "E6" smd circle (at 0.499 -4 90) (size 0.37 0.37) (layers "F.Cu" "F.Paste" "F.Mask")
      (net 459 "unconnected-(U6-RFU-PadE6)") (pinfunction "RFU") (pintype "no_connect"))
    (pad "E7" smd circle (at 1.499 -4 90) (size 0.37 0.37) (layers "F.Cu" "F.Paste" "F.Mask")
      (net 460 "unconnected-(U6-RFU-PadE7)") (pinfunction "RFU") (pintype "no_connect"))
    (pad "E8" smd circle (at 2.499 -4 90) (size 0.37 0.37) (layers "F.Cu" "F.Paste" "F.Mask")
      (net 461 "unconnected-(U6-RFU-PadE8)") (pinfunction "RFU") (pintype "no_connect"))
    (pad "E9" smd circle (at 3.499 -4 90) (size 0.37 0.37) (layers "F.Cu" "F.Paste" "F.Mask")
      (net 462 "unconnected-(U6-RFU-PadE9)") (pinfunction "RFU") (pintype "no_connect"))
    (pad "F2" smd circle (at -3.5 -3 90) (size 0.37 0.37) (layers "F.Cu" "F.Paste" "F.Mask")
      (net 2 "VCC3V3") (pinfunction "VCC") (pintype "power_in"))
    (pad "F3" smd circle (at -2.5 -3 90) (size 0.37 0.37) (layers "F.Cu" "F.Paste" "F.Mask")
      (net 2 "VCC3V3") (pinfunction "VCC") (pintype "passive"))
    (pad "F4" smd circle (at -1.5 -3 90) (size 0.37 0.37) (layers "F.Cu" "F.Paste" "F.Mask")
      (net 2 "VCC3V3") (pinfunction "VCC") (pintype "passive"))
    (pad "F5" smd circle (at -0.5 -3 90) (size 0.37 0.37) (layers "F.Cu" "F.Paste" "F.Mask")
      (net 2 "VCC3V3") (pinfunction "VCC") (pintype "passive"))
    (pad "F6" smd circle (at 0.499 -3 90) (size 0.37 0.37) (layers "F.Cu" "F.Paste" "F.Mask")
      (net 2 "VCC3V3") (pinfunction "VCC") (pintype "passive"))
    (pad "F7" smd circle (at 1.499 -3 90) (size 0.37 0.37) (layers "F.Cu" "F.Paste" "F.Mask")
      (net 2 "VCC3V3") (pinfunction "VCC") (pintype "passive"))
    (pad "F8" smd circle (at 2.499 -3 90) (size 0.37 0.37) (layers "F.Cu" "F.Paste" "F.Mask")
      (net 2 "VCC3V3") (pinfunction "VCC") (pintype "passive"))
    (pad "F9" smd circle (at 3.499 -3 90) (size 0.37 0.37) (layers "F.Cu" "F.Paste" "F.Mask")
      (net 2 "VCC3V3") (pinfunction "VCC") (pintype "passive"))
    (pad "G2" smd circle (at -3.5 -2 90) (size 0.37 0.37) (layers "F.Cu" "F.Paste" "F.Mask")
      (net 1 "GND") (pinfunction "VSS") (pintype "power_in"))
    (pad "G3" smd circle (at -2.5 -2 90) (size 0.37 0.37) (layers "F.Cu" "F.Paste" "F.Mask")
      (net 1 "GND") (pinfunction "VSS") (pintype "passive"))
    (pad "G4" smd circle (at -1.5 -2 90) (size 0.37 0.37) (layers "F.Cu" "F.Paste" "F.Mask")
      (net 1 "GND") (pinfunction "VSS") (pintype "passive"))
    (pad "G5" smd circle (at -0.5 -2 90) (size 0.37 0.37) (layers "F.Cu" "F.Paste" "F.Mask")
      (net 1 "GND") (pinfunction "VSS") (pintype "passive"))
    (pad "G6" smd circle (at 0.499 -2 90) (size 0.37 0.37) (layers "F.Cu" "F.Paste" "F.Mask")
      (net 1 "GND") (pinfunction "VSS") (pintype "passive"))
    (pad "G7" smd circle (at 1.499 -2 90) (size 0.37 0.37) (layers "F.Cu" "F.Paste" "F.Mask")
      (net 1 "GND") (pinfunction "VSS") (pintype "passive"))
    (pad "G8" smd circle (at 2.499 -2 90) (size 0.37 0.37) (layers "F.Cu" "F.Paste" "F.Mask")
      (net 1 "GND") (pinfunction "VSS") (pintype "passive"))
    (pad "G9" smd circle (at 3.499 -2 90) (size 0.37 0.37) (layers "F.Cu" "F.Paste" "F.Mask")
      (net 1 "GND") (pinfunction "VSS") (pintype "passive"))
    (pad "H2" smd circle (at -3.5 -1 90) (size 0.37 0.37) (layers "F.Cu" "F.Paste" "F.Mask")
      (net 1 "GND") (pinfunction "VSSQ") (pintype "power_in"))
    (pad "H3" smd circle (at -2.5 -1 90) (size 0.37 0.37) (layers "F.Cu" "F.Paste" "F.Mask")
      (net 2 "VCC3V3") (pinfunction "VCCQ") (pintype "power_in"))
    (pad "H4" smd circle (at -1.5 -1 90) (size 0.37 0.37) (layers "F.Cu" "F.Paste" "F.Mask")
      (net 463 "unconnected-(U6-RFU-PadH4)") (pinfunction "RFU") (pintype "no_connect"))
    (pad "H5" smd circle (at -0.5 -1 90) (size 0.37 0.37) (layers "F.Cu" "F.Paste" "F.Mask")
      (net 464 "unconnected-(U6-RFU-PadH5)") (pinfunction "RFU") (pintype "no_connect"))
    (pad "H6" smd circle (at 0.499 -1 90) (size 0.37 0.37) (layers "F.Cu" "F.Paste" "F.Mask")
      (net 465 "unconnected-(U6-RFU-PadH6)") (pinfunction "RFU") (pintype "no_connect"))
    (pad "H7" smd circle (at 1.499 -1 90) (size 0.37 0.37) (layers "F.Cu" "F.Paste" "F.Mask")
      (net 466 "unconnected-(U6-RFU-PadH7)") (pinfunction "RFU") (pintype "no_connect"))
    (pad "H8" smd circle (at 2.499 -1 90) (size 0.37 0.37) (layers "F.Cu" "F.Paste" "F.Mask")
      (net 2 "VCC3V3") (pinfunction "VCCQ") (pintype "passive"))
    (pad "H9" smd circle (at 3.499 -1 90) (size 0.37 0.37) (layers "F.Cu" "F.Paste" "F.Mask")
      (net 1 "GND") (pinfunction "VSSQ") (pintype "passive"))
    (pad "J2" smd circle (at -3.5 0 90) (size 0.37 0.37) (layers "F.Cu" "F.Paste" "F.Mask")
      (net 467 "unconnected-(U6-RFU-PadJ2)") (pinfunction "RFU") (pintype "no_connect"))
    (pad "J3" smd circle (at -2.5 0 90) (size 0.37 0.37) (layers "F.Cu" "F.Paste" "F.Mask")
      (net 468 "unconnected-(U6-RFU-PadJ3)") (pinfunction "RFU") (pintype "no_connect"))
    (pad "J4" smd circle (at -1.5 0 90) (size 0.37 0.37) (layers "F.Cu" "F.Paste" "F.Mask")
      (net 469 "unconnected-(U6-RFU-PadJ4)") (pinfunction "RFU") (pintype "no_connect"))
    (pad "J5" smd circle (at -0.5 0 90) (size 0.37 0.37) (layers "F.Cu" "F.Paste" "F.Mask")
      (net 1 "GND") (pinfunction "VSS") (pintype "passive"))
    (pad "J6" smd circle (at 0.499 0 90) (size 0.37 0.37) (layers "F.Cu" "F.Paste" "F.Mask")
      (net 470 "unconnected-(U6-RFU-PadJ6)") (pinfunction "RFU") (pintype "no_connect"))
    (pad "J7" smd circle (at 1.499 0 90) (size 0.37 0.37) (layers "F.Cu" "F.Paste" "F.Mask")
      (net 471 "unconnected-(U6-RFU-PadJ7)") (pinfunction "RFU") (pintype "no_connect"))
    (pad "J8" smd circle (at 2.499 0 90) (size 0.37 0.37) (layers "F.Cu" "F.Paste" "F.Mask")
      (net 472 "unconnected-(U6-RFU-PadJ8)") (pinfunction "RFU") (pintype "no_connect"))
    (pad "J9" smd circle (at 3.499 0 90) (size 0.37 0.37) (layers "F.Cu" "F.Paste" "F.Mask")
      (net 473 "unconnected-(U6-RFU-PadJ9)") (pinfunction "RFU") (pintype "no_connect"))
    (pad "K2" smd circle (at -3.5 0.999 90) (size 0.37 0.37) (layers "F.Cu" "F.Paste" "F.Mask")
      (net 279 "MMC_DAT0") (pinfunction "DAT0") (pintype "bidirectional"))
    (pad "K3" smd circle (at -2.5 0.999 90) (size 0.37 0.37) (layers "F.Cu" "F.Paste" "F.Mask")
      (net 281 "MMC_DAT2") (pinfunction "DAT2") (pintype "bidirectional"))
    (pad "K4" smd circle (at -1.5 0.999 90) (size 0.37 0.37) (layers "F.Cu" "F.Paste" "F.Mask")
      (net 474 "unconnected-(U6-RFU-PadK4)") (pinfunction "RFU") (pintype "no_connect"))
    (pad "K5" smd circle (at -0.5 0.999 90) (size 0.37 0.37) (layers "F.Cu" "F.Paste" "F.Mask")
      (net 437 "Net-(U6-DS)") (pinfunction "DS") (pintype "output"))
    (pad "K6" smd circle (at 0.499 0.999 90) (size 0.37 0.37) (layers "F.Cu" "F.Paste" "F.Mask")
      (net 475 "unconnected-(U6-RFU-PadK6)") (pinfunction "RFU") (pintype "no_connect"))
    (pad "K7" smd circle (at 1.499 0.999 90) (size 0.37 0.37) (layers "F.Cu" "F.Paste" "F.Mask")
      (net 476 "unconnected-(U6-RFU-PadK7)") (pinfunction "RFU") (pintype "no_connect"))
    (pad "K8" smd circle (at 2.499 0.999 90) (size 0.37 0.37) (layers "F.Cu" "F.Paste" "F.Mask")
      (net 284 "MMC_DAT5") (pinfunction "DAT5") (pintype "bidirectional"))
    (pad "K9" smd circle (at 3.499 0.999 90) (size 0.37 0.37) (layers "F.Cu" "F.Paste" "F.Mask")
      (net 286 "MMC_DAT7") (pinfunction "DAT7") (pintype "bidirectional"))
    (pad "L2" smd circle (at -3.5 1.999 90) (size 0.37 0.37) (layers "F.Cu" "F.Paste" "F.Mask")
      (net 2 "VCC3V3") (pinfunction "VCCQ") (pintype "passive"))
    (pad "L3" smd circle (at -2.5 1.999 90) (size 0.37 0.37) (layers "F.Cu" "F.Paste" "F.Mask")
      (net 1 "GND") (pinfunction "VSSQ") (pintype "passive"))
    (pad "L4" smd circle (at -1.5 1.999 90) (size 0.37 0.37) (layers "F.Cu" "F.Paste" "F.Mask")
      (net 2 "VCC3V3") (pinfunction "VCCQ") (pintype "passive"))
    (pad "L5" smd circle (at -0.5 1.999 90) (size 0.37 0.37) (layers "F.Cu" "F.Paste" "F.Mask")
      (net 477 "unconnected-(U6-RFU-PadL5)") (pinfunction "RFU") (pintype "no_connect"))
    (pad "L6" smd circle (at 0.499 1.999 90) (size 0.37 0.37) (layers "F.Cu" "F.Paste" "F.Mask")
      (net 478 "unconnected-(U6-RFU-PadL6)") (pinfunction "RFU") (pintype "no_connect"))
    (pad "L7" smd circle (at 1.499 1.999 90) (size 0.37 0.37) (layers "F.Cu" "F.Paste" "F.Mask")
      (net 2 "VCC3V3") (pinfunction "VCCQ") (pintype "passive"))
    (pad "L8" smd circle (at 2.499 1.999 90) (size 0.37 0.37) (layers "F.Cu" "F.Paste" "F.Mask")
      (net 1 "GND") (pinfunction "VSSQ") (pintype "passive"))
    (pad "L9" smd circle (at 3.499 1.999 90) (size 0.37 0.37) (layers "F.Cu" "F.Paste" "F.Mask")
      (net 2 "VCC3V3") (pinfunction "VCCQ") (pintype "passive"))
    (pad "M2" smd circle (at -3.5 2.999 90) (size 0.37 0.37) (layers "F.Cu" "F.Paste" "F.Mask")
      (net 479 "unconnected-(U6-RFU-PadM2)") (pinfunction "RFU") (pintype "no_connect"))
    (pad "M3" smd circle (at -2.5 2.999 90) (size 0.37 0.37) (layers "F.Cu" "F.Paste" "F.Mask")
      (net 480 "unconnected-(U6-RFU-PadM3)") (pinfunction "RFU") (pintype "no_connect"))
    (pad "M4" smd circle (at -1.5 2.999 90) (size 0.37 0.37) (layers "F.Cu" "F.Paste" "F.Mask")
      (net 1 "GND") (pinfunction "VSSQ") (pintype "passive"))
    (pad "M5" smd circle (at -0.5 2.999 90) (size 0.37 0.37) (layers "F.Cu" "F.Paste" "F.Mask")
      (net 377 "MMC_RSTN") (pinfunction "RST_N") (pintype "input"))
    (pad "M6" smd circle (at 0.499 2.999 90) (size 0.37 0.37) (layers "F.Cu" "F.Paste" "F.Mask")
      (net 481 "unconnected-(U6-RFU-PadM6)") (pinfunction "RFU") (pintype "no_connect"))
    (pad "M7" smd circle (at 1.499 2.999 90) (size 0.37 0.37) (layers "F.Cu" "F.Paste" "F.Mask")
      (net 1 "GND") (pinfunction "VSSQ") (pintype "passive"))
    (pad "M8" smd circle (at 2.499 2.999 90) (size 0.37 0.37) (layers "F.Cu" "F.Paste" "F.Mask")
      (net 482 "unconnected-(U6-RFU-PadM8)") (pinfunction "RFU") (pintype "no_connect"))
    (pad "M9" smd circle (at 3.499 2.999 90) (size 0.37 0.37) (layers "F.Cu" "F.Paste" "F.Mask")
      (net 483 "unconnected-(U6-RFU-PadM9)") (pinfunction "RFU") (pintype "no_connect"))
    (pad "N2" smd circle (at -3.5 3.999 90) (size 0.37 0.37) (layers "F.Cu" "F.Paste" "F.Mask")
      (net 280 "MMC_DAT1") (pinfunction "DAT1") (pintype "bidirectional"))
    (pad "N3" smd circle (at -2.5 3.999 90) (size 0.37 0.37) (layers "F.Cu" "F.Paste" "F.Mask")
      (net 282 "MMC_DAT3") (pinfunction "DAT3") (pintype "bidirectional"))
    (pad "N4" smd circle (at -1.5 3.999 90) (size 0.37 0.37) (layers "F.Cu" "F.Paste" "F.Mask")
      (net 484 "unconnected-(U6-RFU-PadN4)") (pinfunction "RFU") (pintype "no_connect"))
    (pad "N5" smd circle (at -0.5 3.999 90) (size 0.37 0.37) (layers "F.Cu" "F.Paste" "F.Mask")
      (net 485 "unconnected-(U6-RFU-PadN5)") (pinfunction "RFU") (pintype "no_connect"))
    (pad "N6" smd circle (at 0.499 3.999 90) (size 0.37 0.37) (layers "F.Cu" "F.Paste" "F.Mask")
      (net 486 "unconnected-(U6-RFU-PadN6)") (pinfunction "RFU") (pintype "no_connect"))
    (pad "N7" smd circle (at 1.499 3.999 90) (size 0.37 0.37) (layers "F.Cu" "F.Paste" "F.Mask")
      (net 487 "unconnected-(U6-RFU-PadN7)") (pinfunction "RFU") (pintype "no_connect"))
    (pad "N8" smd circle (at 2.499 3.999 90) (size 0.37 0.37) (layers "F.Cu" "F.Paste" "F.Mask")
      (net 283 "MMC_DAT4") (pinfunction "DAT4") (pintype "bidirectional"))
    (pad "N9" smd circle (at 3.499 3.999 90) (size 0.37 0.37) (layers "F.Cu" "F.Paste" "F.Mask")
      (net 285 "MMC_DAT6") (pinfunction "DAT6") (pintype "bidirectional"))
    (pad "P2" smd circle (at -3.5 4.999 90) (size 0.37 0.37) (layers "F.Cu" "F.Paste" "F.Mask")
      (net 1 "GND") (pinfunction "VSSQ") (pintype "passive"))
    (pad "P3" smd circle (at -2.5 4.999 90) (size 0.37 0.37) (layers "F.Cu" "F.Paste" "F.Mask")
      (net 2 "VCC3V3") (pinfunction "VCCQ") (pintype "passive"))
    (pad "P4" smd circle (at -1.5 4.999 90) (size 0.37 0.37) (layers "F.Cu" "F.Paste" "F.Mask")
      (net 488 "unconnected-(U6-RFU-PadP4)") (pinfunction "RFU") (pintype "no_connect"))
    (pad "P5" smd circle (at -0.5 4.999 90) (size 0.37 0.37) (layers "F.Cu" "F.Paste" "F.Mask")
      (net 287 "MMC_CMD") (pinfunction "CMD") (pintype "bidirectional"))
    (pad "P6" smd circle (at 0.499 4.999 90) (size 0.37 0.37) (layers "F.Cu" "F.Paste" "F.Mask")
      (net 403 "Net-(U6-CLK)") (pinfunction "CLK") (pintype "input"))
    (pad "P7" smd circle (at 1.499 4.999 90) (size 0.37 0.37) (layers "F.Cu" "F.Paste" "F.Mask")
      (net 489 "unconnected-(U6-RFU-PadP7)") (pinfunction "RFU") (pintype "no_connect"))
    (pad "P8" smd circle (at 2.499 4.999 90) (size 0.37 0.37) (layers "F.Cu" "F.Paste" "F.Mask")
      (net 2 "VCC3V3") (pinfunction "VCCQ") (pintype "passive"))
    (pad "P9" smd circle (at 3.499 4.999 90) (size 0.37 0.37) (layers "F.Cu" "F.Paste" "F.Mask")
      (net 1 "GND") (pinfunction "VSSQ") (pintype "passive"))
    (pad "T1" smd circle (at -4.5 6.998 90) (size 0.37 0.37) (layers "F.Cu" "F.Paste" "F.Mask")
      (net 490 "unconnected-(U6-NC-PadT1)") (pinfunction "NC") (pintype "no_connect"))
    (pad "T10" smd circle (at 4.499 6.998 90) (size 0.37 0.37) (layers "F.Cu" "F.Paste" "F.Mask")
      (net 491 "unconnected-(U6-NC-PadT10)") (pinfunction "NC") (pintype "no_connect"))
    (pad "U1" smd circle (at -4.5 7.998 90) (size 0.37 0.37) (layers "F.Cu" "F.Paste" "F.Mask")
      (net 492 "unconnected-(U6-NC-PadU1)") (pinfunction "NC") (pintype "no_connect"))
    (pad "U2" smd circle (at -3.5 7.998 90) (size 0.37 0.37) (layers "F.Cu" "F.Paste" "F.Mask")
      (net 493 "unconnected-(U6-NC-PadU2)") (pinfunction "NC") (pintype "no_connect"))
    (pad "U9" smd circle (at 3.499 7.998 90) (size 0.37 0.37) (layers "F.Cu" "F.Paste" "F.Mask")
      (net 494 "unconnected-(U6-NC-PadU9)") (pinfunction "NC") (pintype "no_connect"))
    (pad "U10" smd circle (at 4.499 7.998 90) (size 0.37 0.37) (layers "F.Cu" "F.Paste" "F.Mask")
      (net 495 "unconnected-(U6-NC-PadU10)") (pinfunction "NC") (pintype "no_connect"))
  )

  (footprint "antmicro-footprints:R_0402_1005Metric" (layer "F.Cu")
    (at 107 104 90)
    (descr "Resistor SMD 0402")
    (tags "resistor SMD 0402")
    (property "Author" "Antmicro")
    (property "License" "Apache-2.0")
    (property "MPN" "CR0402-FX-2201GLF")
    (property "Manufacturer" "Bourns")
    (property "Public" "False")
    (property "Sheetfile" "ethernet.kicad_sch")
    (property "Sheetname" "Ethernet")
    (property "Tolerance" "1%")
    (property "Val" "2k2")
    (property "ki_description" "SMD Chip Resistor, 2.2 kohm, ± 1%, 62.5 mW, 0402 [1005 Metric], Thick Film, General Purpose")
    (property "ki_keywords" "0402, SMT, RESISTOR, PASSIVE")
    (attr smd)
    (fp_text reference "R9" (at 0 9 90) (layer "F.SilkS")
        (effects (font (size 0.7 0.7) (thickness 0.127)))
    )
    (fp_text value "R_2k2_0402" (at 0 1.17 90) (layer "F.Fab")
        (effects (font (size 1 1) (thickness 0.15)))
    )
    (fp_text user "${REFERENCE}" (at 0 0 90) (layer "F.Fab")
        (effects (font (size 0.25 0.25) (thickness 0.04)))
    )
    (fp_text user "License: Apache-2.0" (at -0.95 5.169 90) (layer "F.Fab") hide
        (effects (font (size 0.7 0.7) (thickness 0.15)) (justify left bottom))
    )
    (fp_text user "Author: Antmicro" (at -0.95 4.169 90) (layer "F.Fab") hide
        (effects (font (size 0.7 0.7) (thickness 0.15)) (justify left bottom))
    )
    (fp_rect (start -0.925 -0.47) (end 0.925 0.47)
      (stroke (width 0.05) (type default)) (fill none) (layer "F.CrtYd"))
    (fp_rect (start -0.5 -0.25) (end 0.5 0.25)
      (stroke (width 0.15) (type solid)) (fill none) (layer "F.Fab"))
    (pad "1" smd roundrect (at -0.48 0 90) (size 0.59 0.64) (layers "F.Cu" "F.Paste" "F.Mask") (roundrect_rratio 0.25)
      (net 2 "VCC3V3") (pintype "passive"))
    (pad "2" smd roundrect (at 0.48 0 90) (size 0.59 0.64) (layers "F.Cu" "F.Paste" "F.Mask") (roundrect_rratio 0.25)
      (net 162 "ETH_MDIO") (pintype "passive"))
  )

  (footprint "antmicro-footprints:Conn_Molex_Pico-Lock_1x2_504050-0291" (layer "F.Cu")
    (at 66.27 163.64 -90)
    (property "Author" "Antmicro")
    (property "License" "Apache-2.0")
    (property "MPN" "504050-0291")
    (property "Manufacturer" "Molex")
    (property "Sheetfile" "power-supply.kicad_sch")
    (property "Sheetname" "Power supply")
    (property "ki_description" "Connector Header Surface Mount, Right Angle 2 position 0.059\" (1.50mm)")
    (property "ki_keywords" "CONNECTOR, HEADER, SMT")
    (attr smd)
    (fp_text reference "J8" (at -2.045 -3.84 -90) (layer "F.SilkS")
        (effects (font (size 0.7 0.7) (thickness 0.15)) (justify left bottom))
    )
    (fp_text value "Molex_Pico-Lock_1x2_504050-0291" (at -0.749 4.35 -90) (layer "F.Fab")
        (effects (font (size 0.7 0.7) (thickness 0.15)) (justify left bottom))
    )
    (fp_text user "License: Apache-2.0" (at -3.481 12.573 -90) (layer "F.Fab") hide
        (effects (font (size 0.7 0.7) (thickness 0.15)) (justify left bottom))
    )
    (fp_text user "${REFERENCE}" (at -3.481 10.175 -90) (layer "F.Fab") hide
        (effects (font (size 0.7 0.7) (thickness 0.15)) (justify left bottom))
    )
    (fp_text user "Author: Antmicro" (at -3.481 11.374 -90) (layer "F.Fab") hide
        (effects (font (size 0.7 0.7) (thickness 0.15)) (justify left bottom))
    )
    (fp_line (start -3.374 -2.86) (end -1.4 -2.86)
      (stroke (width 0.15) (type solid)) (layer "F.SilkS"))
    (fp_line (start -3.374 1.088) (end -3.374 -2.86)
      (stroke (width 0.15) (type solid)) (layer "F.SilkS"))
    (fp_line (start -1.639 3.239) (end -1.639 1.289)
      (stroke (width 0.15) (type solid)) (layer "F.SilkS"))
    (fp_line (start 1.399 -2.86) (end 3.374 -2.86)
      (stroke (width 0.15) (type solid)) (layer "F.SilkS"))
    (fp_line (start 1.649 1.289) (end -1.639 1.289)
      (stroke (width 0.15) (type solid)) (layer "F.SilkS"))
    (fp_line (start 1.649 1.289) (end 1.649 3.228)
      (stroke (width 0.15) (type solid)) (layer "F.SilkS"))
    (fp_line (start 3.374 -2.86) (end 3.374 1.088)
      (stroke (width 0.15) (type solid)) (layer "F.SilkS"))
    (fp_circle (center -1.249 -3.15) (end -1.199 -3.15)
      (stroke (width 0.15) (type solid)) (fill solid) (layer "F.SilkS"))
    (fp_line (start -4.249 1.18) (end -3.629 1.18)
      (stroke (width 0.05) (type solid)) (layer "F.CrtYd"))
    (fp_line (start -4.249 3.47) (end -4.249 1.18)
      (stroke (width 0.05) (type solid)) (layer "F.CrtYd"))
    (fp_line (start -3.629 -3.61) (end 3.621 -3.61)
      (stroke (width 0.05) (type solid)) (layer "F.CrtYd"))
    (fp_line (start -3.629 1.18) (end -3.629 -3.61)
      (stroke (width 0.05) (type solid)) (layer "F.CrtYd"))
    (fp_line (start 3.621 -3.61) (end 3.621 1.18)
      (stroke (width 0.05) (type solid)) (layer "F.CrtYd"))
    (fp_line (start 3.621 1.18) (end 4.231 1.18)
      (stroke (width 0.05) (type solid)) (layer "F.CrtYd"))
    (fp_line (start 4.231 1.18) (end 4.231 3.47)
      (stroke (width 0.05) (type solid)) (layer "F.CrtYd"))
    (fp_line (start 4.231 3.47) (end -4.249 3.47)
      (stroke (width 0.05) (type solid)) (layer "F.CrtYd"))
    (fp_line (start -3.374 -2.86) (end 3.374 -2.86)
      (stroke (width 0.15) (type solid)) (layer "F.Fab"))
    (fp_line (start -3.374 3.239) (end -3.374 -2.86)
      (stroke (width 0.15) (type solid)) (layer "F.Fab"))
    (fp_line (start -3.374 3.239) (end -1.749 3.239)
      (stroke (width 0.15) (type solid)) (layer "F.Fab"))
    (fp_line (start -1.749 3.249) (end -1.749 1.188)
      (stroke (width 0.15) (type solid)) (layer "F.Fab"))
    (fp_line (start 1.75 1.188) (end -1.749 1.188)
      (stroke (width 0.15) (type solid)) (layer "F.Fab"))
    (fp_line (start 1.75 1.188) (end 1.75 3.239)
      (stroke (width 0.15) (type solid)) (layer "F.Fab"))
    (fp_line (start 1.75 3.239) (end 3.374 3.239)
      (stroke (width 0.15) (type solid)) (layer "F.Fab"))
    (fp_line (start 3.374 -2.86) (end 3.374 3.239)
      (stroke (width 0.15) (type solid)) (layer "F.Fab"))
    (pad "1" smd roundrect (at -0.749 -2.85 270) (size 0.6 1) (layers "F.Cu" "F.Paste" "F.Mask") (roundrect_rratio 0.25)
      (net 57 "P12V_AUX") (pinfunction "1") (pintype "passive"))
    (pad "2" smd roundrect (at 0.75 -2.85 270) (size 0.6 1) (layers "F.Cu" "F.Paste" "F.Mask") (roundrect_rratio 0.25)
      (net 1 "GND") (pinfunction "2") (pintype "passive"))
    (pad "SH" smd roundrect (at -3.354 2.338 270) (size 1.25 1.8) (layers "F.Cu" "F.Paste" "F.Mask") (roundrect_rratio 0.25)
      (net 1 "GND") (pinfunction "SH") (pintype "passive"))
    (pad "SH" smd roundrect (at 3.356 2.338 270) (size 1.25 1.8) (layers "F.Cu" "F.Paste" "F.Mask") (roundrect_rratio 0.25)
      (net 1 "GND") (pinfunction "SH") (pintype "passive"))
  )

  (footprint "antmicro-footprints:Conn_Molex_Pico-Lock_1x2_504050-0291" (layer "F.Cu")
    (at 143 148.48 180)
    (property "Author" "Antmicro")
    (property "License" "Apache-2.0")
    (property "MPN" "504050-0291")
    (property "Manufacturer" "Molex")
    (property "Sheetfile" "power-supply.kicad_sch")
    (property "Sheetname" "Power supply")
    (property "ki_description" "Connector Header Surface Mount, Right Angle 2 position 0.059\" (1.50mm)")
    (property "ki_keywords" "CONNECTOR, HEADER, SMT")
    (attr smd)
    (fp_text reference "J18" (at -1.17 -4.025 180) (layer "F.SilkS")
        (effects (font (size 0.7 0.7) (thickness 0.15)) (justify left bottom))
    )
    (fp_text value "Molex_Pico-Lock_1x2_504050-0291" (at -0.749 4.35 180) (layer "F.Fab")
        (effects (font (size 0.7 0.7) (thickness 0.15)) (justify left bottom))
    )
    (fp_text user "Author: Antmicro" (at -3.481 11.374 180) (layer "F.Fab") hide
        (effects (font (size 0.7 0.7) (thickness 0.15)) (justify left bottom))
    )
    (fp_text user "License: Apache-2.0" (at -3.481 12.573 180) (layer "F.Fab") hide
        (effects (font (size 0.7 0.7) (thickness 0.15)) (justify left bottom))
    )
    (fp_text user "${REFERENCE}" (at -3.481 10.175 180) (layer "F.Fab") hide
        (effects (font (size 0.7 0.7) (thickness 0.15)) (justify left bottom))
    )
    (fp_line (start -3.374 -2.86) (end -1.4 -2.86)
      (stroke (width 0.15) (type solid)) (layer "F.SilkS"))
    (fp_line (start -3.374 1.088) (end -3.374 -2.86)
      (stroke (width 0.15) (type solid)) (layer "F.SilkS"))
    (fp_line (start -1.639 3.239) (end -1.639 1.289)
      (stroke (width 0.15) (type solid)) (layer "F.SilkS"))
    (fp_line (start 1.399 -2.86) (end 3.374 -2.86)
      (stroke (width 0.15) (type solid)) (layer "F.SilkS"))
    (fp_line (start 1.649 1.289) (end -1.639 1.289)
      (stroke (width 0.15) (type solid)) (layer "F.SilkS"))
    (fp_line (start 1.649 1.289) (end 1.649 3.228)
      (stroke (width 0.15) (type solid)) (layer "F.SilkS"))
    (fp_line (start 3.374 -2.86) (end 3.374 1.088)
      (stroke (width 0.15) (type solid)) (layer "F.SilkS"))
    (fp_circle (center -1.249 -3.15) (end -1.199 -3.15)
      (stroke (width 0.15) (type solid)) (fill solid) (layer "F.SilkS"))
    (fp_line (start -4.249 1.18) (end -3.629 1.18)
      (stroke (width 0.05) (type solid)) (layer "F.CrtYd"))
    (fp_line (start -4.249 3.47) (end -4.249 1.18)
      (stroke (width 0.05) (type solid)) (layer "F.CrtYd"))
    (fp_line (start -3.629 -3.61) (end 3.621 -3.61)
      (stroke (width 0.05) (type solid)) (layer "F.CrtYd"))
    (fp_line (start -3.629 1.18) (end -3.629 -3.61)
      (stroke (width 0.05) (type solid)) (layer "F.CrtYd"))
    (fp_line (start 3.621 -3.61) (end 3.621 1.18)
      (stroke (width 0.05) (type solid)) (layer "F.CrtYd"))
    (fp_line (start 3.621 1.18) (end 4.231 1.18)
      (stroke (width 0.05) (type solid)) (layer "F.CrtYd"))
    (fp_line (start 4.231 1.18) (end 4.231 3.47)
      (stroke (width 0.05) (type solid)) (layer "F.CrtYd"))
    (fp_line (start 4.231 3.47) (end -4.249 3.47)
      (stroke (width 0.05) (type solid)) (layer "F.CrtYd"))
    (fp_line (start -3.374 -2.86) (end 3.374 -2.86)
      (stroke (width 0.15) (type solid)) (layer "F.Fab"))
    (fp_line (start -3.374 3.239) (end -3.374 -2.86)
      (stroke (width 0.15) (type solid)) (layer "F.Fab"))
    (fp_line (start -3.374 3.239) (end -1.749 3.239)
      (stroke (width 0.15) (type solid)) (layer "F.Fab"))
    (fp_line (start -1.749 3.249) (end -1.749 1.188)
      (stroke (width 0.15) (type solid)) (layer "F.Fab"))
    (fp_line (start 1.75 1.188) (end -1.749 1.188)
      (stroke (width 0.15) (type solid)) (layer "F.Fab"))
    (fp_line (start 1.75 1.188) (end 1.75 3.239)
      (stroke (width 0.15) (type solid)) (layer "F.Fab"))
    (fp_line (start 1.75 3.239) (end 3.374 3.239)
      (stroke (width 0.15) (type solid)) (layer "F.Fab"))
    (fp_line (start 3.374 -2.86) (end 3.374 3.239)
      (stroke (width 0.15) (type solid)) (layer "F.Fab"))
    (pad "1" smd roundrect (at -0.749 -2.85 180) (size 0.6 1) (layers "F.Cu" "F.Paste" "F.Mask") (roundrect_rratio 0.25)
      (net 414 "3V0_BAT") (pinfunction "1") (pintype "passive"))
    (pad "2" smd roundrect (at 0.75 -2.85 180) (size 0.6 1) (layers "F.Cu" "F.Paste" "F.Mask") (roundrect_rratio 0.25)
      (net 1 "GND") (pinfunction "2") (pintype "passive"))
    (pad "SH" smd roundrect (at -3.354 2.338 180) (size 1.25 1.8) (layers "F.Cu" "F.Paste" "F.Mask") (roundrect_rratio 0.25)
      (net 1 "GND") (pinfunction "SH") (pintype "passive"))
    (pad "SH" smd roundrect (at 3.356 2.338 180) (size 1.25 1.8) (layers "F.Cu" "F.Paste" "F.Mask") (roundrect_rratio 0.25)
      (net 1 "GND") (pinfunction "SH") (pintype "passive"))
  )

  (footprint "antmicro-footprints:Oscillator_SMD_Abracon_ASEMB_3.2x2.5mm" (layer "F.Cu")
    (at 130.54 117.1 180)
    (property "Author" "Antmicro")
    (property "License" "Apache-2.0")
    (property "MPN" "ASEMB-24.000MHZ-LC-T")
    (property "Manufacturer" "Abracon")
    (property "Public" "False")
    (property "Sheetfile" "interfaces.kicad_sch")
    (property "Sheetname" "Interfaces")
    (property "Val" "24 MHz")
    (property "ki_description" "MEMS Oscillator, Clock, Pure Silicon&trade;, 24 MHz, SMD, 3.2mm x 2.5mm, 50 ppm, 3.3 V, ASEMB, LVCMOS")
    (property "ki_keywords" "OSCILLATOR, MEMS")
    (attr smd)
    (fp_text reference "Y2" (at -2.84 -0.675 270) (layer "F.SilkS")
        (effects (font (size 0.7 0.7) (thickness 0.15)) (justify left bottom))
    )
    (fp_text value "Oscillator_24MHz_ASEMB" (at -10.2616 2.8956 180) (layer "F.Fab")
        (effects (font (size 0.7 0.7) (thickness 0.15)) (justify left bottom))
    )
    (fp_text user "." (at -1.651 -2 180) (layer "F.SilkS") hide
        (effects (font (size 0.7 0.7) (thickness 0.15)) (justify left bottom))
    )
    (fp_text user "${REFERENCE}" (at -10.2616 4.8956 180) (layer "F.Fab") hide
        (effects (font (size 0.7 0.7) (thickness 0.15)) (justify left bottom))
    )
    (fp_text user "Author: Antmicro" (at -10.2616 7.2956 180) (layer "F.Fab") hide
        (effects (font (size 0.7 0.7) (thickness 0.15)) (justify left bottom))
    )
    (fp_text user "License: Apache-2.0" (at -10.2616 6.0956 180) (layer "F.Fab") hide
        (effects (font (size 0.7 0.7) (thickness 0.15)) (justify left bottom))
    )
    (fp_circle (center -1.5748 -1.8034) (end -1.5248 -1.8034)
      (stroke (width 0.15) (type solid)) (fill solid) (layer "F.SilkS"))
    (fp_rect (start -1.752 -2.101) (end 1.749 2.1)
      (stroke (width 0.05) (type solid)) (fill none) (layer "F.CrtYd"))
    (fp_line (start -1.2192 -1.4224) (end -1.0668 -1.5748)
      (stroke (width 0.15) (type solid)) (layer "F.Fab"))
    (fp_rect (start -1.252 -1.601) (end 1.249 1.6)
      (stroke (width 0.15) (type solid)) (fill none) (layer "F.Fab"))
    (pad "1" smd rect (at -0.951 -1.049 180) (size 1 0.9) (layers "F.Cu" "F.Paste" "F.Mask")
      (net 2 "VCC3V3") (pinfunction "EN") (pintype "input"))
    (pad "2" smd rect (at -0.951 1.05 180) (size 1 0.9) (layers "F.Cu" "F.Paste" "F.Mask")
      (net 1 "GND") (pinfunction "GND") (pintype "power_in"))
    (pad "3" smd rect (at 0.948 1.05 180) (size 1 0.9) (layers "F.Cu" "F.Paste" "F.Mask")
      (net 679 "/Interfaces/USB1_CLK") (pinfunction "OUT") (pintype "output"))
    (pad "4" smd rect (at 0.948 -1.049 180) (size 1 0.9) (layers "F.Cu" "F.Paste" "F.Mask")
      (net 2 "VCC3V3") (pinfunction "VDD") (pintype "power_in"))
  )

  (footprint "antmicro-footprints:Oscillator_SMD_Abracon_ASEMB_3.2x2.5mm" (layer "F.Cu")
    (at 125.64 133.18 180)
    (property "Author" "Antmicro")
    (property "License" "Apache-2.0")
    (property "MPN" "ASEMB-24.000MHZ-LC-T")
    (property "Manufacturer" "Abracon")
    (property "Public" "False")
    (property "Sheetfile" "interfaces.kicad_sch")
    (property "Sheetname" "Interfaces")
    (property "Val" "24 MHz")
    (property "ki_description" "MEMS Oscillator, Clock, Pure Silicon&trade;, 24 MHz, SMD, 3.2mm x 2.5mm, 50 ppm, 3.3 V, ASEMB, LVCMOS")
    (property "ki_keywords" "OSCILLATOR, MEMS")
    (attr smd)
    (fp_text reference "Y3" (at 1.86 -0.535 90) (layer "F.SilkS")
        (effects (font (size 0.7 0.7) (thickness 0.15)) (justify left bottom))
    )
    (fp_text value "Oscillator_24MHz_ASEMB" (at -10.2616 2.8956 180) (layer "F.Fab")
        (effects (font (size 0.7 0.7) (thickness 0.15)) (justify left bottom))
    )
    (fp_text user "." (at -1.651 -2 180) (layer "F.SilkS") hide
        (effects (font (size 0.7 0.7) (thickness 0.15)) (justify left bottom))
    )
    (fp_text user "Author: Antmicro" (at -10.2616 7.2956 180) (layer "F.Fab") hide
        (effects (font (size 0.7 0.7) (thickness 0.15)) (justify left bottom))
    )
    (fp_text user "License: Apache-2.0" (at -10.2616 6.0956 180) (layer "F.Fab") hide
        (effects (font (size 0.7 0.7) (thickness 0.15)) (justify left bottom))
    )
    (fp_text user "${REFERENCE}" (at -10.2616 4.8956 180) (layer "F.Fab") hide
        (effects (font (size 0.7 0.7) (thickness 0.15)) (justify left bottom))
    )
    (fp_circle (center -1.5748 -1.8034) (end -1.5248 -1.8034)
      (stroke (width 0.15) (type solid)) (fill solid) (layer "F.SilkS"))
    (fp_rect (start -1.752 -2.101) (end 1.749 2.1)
      (stroke (width 0.05) (type solid)) (fill none) (layer "F.CrtYd"))
    (fp_line (start -1.2192 -1.4224) (end -1.0668 -1.5748)
      (stroke (width 0.15) (type solid)) (layer "F.Fab"))
    (fp_rect (start -1.252 -1.601) (end 1.249 1.6)
      (stroke (width 0.15) (type solid)) (fill none) (layer "F.Fab"))
    (pad "1" smd rect (at -0.951 -1.049 180) (size 1 0.9) (layers "F.Cu" "F.Paste" "F.Mask")
      (net 2 "VCC3V3") (pinfunction "EN") (pintype "input"))
    (pad "2" smd rect (at -0.951 1.05 180) (size 1 0.9) (layers "F.Cu" "F.Paste" "F.Mask")
      (net 1 "GND") (pinfunction "GND") (pintype "power_in"))
    (pad "3" smd rect (at 0.948 1.05 180) (size 1 0.9) (layers "F.Cu" "F.Paste" "F.Mask")
      (net 678 "/Interfaces/USB2_CLK") (pinfunction "OUT") (pintype "output"))
    (pad "4" smd rect (at 0.948 -1.049 180) (size 1 0.9) (layers "F.Cu" "F.Paste" "F.Mask")
      (net 2 "VCC3V3") (pinfunction "VDD") (pintype "power_in"))
  )

  (footprint "antmicro-footprints:SOT-23-3" (layer "F.Cu")
    (at 72.89 165.11)
    (property "Author" "Antmicro")
    (property "License" "Apache-2.0")
    (property "MPN" "2N7002")
    (property "Manufacturer" "ON Semiconductor")
    (property "Sheetfile" "fpga-banks.kicad_sch")
    (property "Sheetname" "FPGA banks")
    (property "ki_description" "Power MOSFET, N Channel, 60 V, 115 mA, 1.2 ohm, SOT-23, Surface Mount")
    (property "ki_keywords" "SMT, TRANSISTOR, SEMICONDUCTOR, NMOS")
    (attr smd)
    (fp_text reference "Q17" (at 2.14 1.55 180) (layer "F.SilkS")
        (effects (font (size 0.7 0.7) (thickness 0.127)))
    )
    (fp_text value "2N7002" (at 0.025 3.25 180) (layer "F.Fab")
        (effects (font (size 1 1) (thickness 0.15)))
    )
    (fp_text user "Author: Antmicro" (at -1.837 5.3) (layer "F.Fab") hide
        (effects (font (size 0.7 0.7) (thickness 0.15)) (justify left bottom))
    )
    (fp_text user "License: Apache-2.0" (at -1.8 6.8) (layer "F.Fab") hide
        (effects (font (size 0.7 0.7) (thickness 0.15)) (justify left bottom))
    )
    (fp_text user "${REFERENCE}" (at -0.125 0.15 180) (layer "F.Fab")
        (effects (font (size 0.25 0.25) (thickness 0.05)))
    )
    (fp_line (start -1.45 -1.35) (end -0.85 -1.35)
      (stroke (width 0.15) (type solid)) (layer "F.SilkS"))
    (fp_line (start -0.85 -1.35) (end -0.7 -1.5)
      (stroke (width 0.15) (type solid)) (layer "F.SilkS"))
    (fp_line (start -0.7 1.5) (end -0.7 1.35)
      (stroke (width 0.15) (type solid)) (layer "F.SilkS"))
    (fp_line (start 0.7 -1.5) (end -0.7 -1.5)
      (stroke (width 0.15) (type solid)) (layer "F.SilkS"))
    (fp_line (start 0.7 -0.4) (end 0.7 -1.5)
      (stroke (width 0.15) (type solid)) (layer "F.SilkS"))
    (fp_line (start 0.7 0.4) (end 0.7 1.5)
      (stroke (width 0.15) (type solid)) (layer "F.SilkS"))
    (fp_line (start 0.7 1.5) (end -0.7 1.5)
      (stroke (width 0.15) (type solid)) (layer "F.SilkS"))
    (fp_line (start -1.75 -0.5) (end -1.75 -1.4)
      (stroke (width 0.05) (type solid)) (layer "F.CrtYd"))
    (fp_line (start -1.75 0.5) (end -0.85 0.5)
      (stroke (width 0.05) (type solid)) (layer "F.CrtYd"))
    (fp_line (start -1.75 1.4) (end -1.75 0.5)
      (stroke (width 0.05) (type solid)) (layer "F.CrtYd"))
    (fp_line (start -0.9 -1.6) (end -0.9 -1.4)
      (stroke (width 0.05) (type solid)) (layer "F.CrtYd"))
    (fp_line (start -0.9 -1.6) (end 0.825 -1.6)
      (stroke (width 0.05) (type solid)) (layer "F.CrtYd"))
    (fp_line (start -0.9 -1.4) (end -1.75 -1.4)
      (stroke (width 0.05) (type solid)) (layer "F.CrtYd"))
    (fp_line (start -0.85 -0.5) (end -1.75 -0.5)
      (stroke (width 0.05) (type solid)) (layer "F.CrtYd"))
    (fp_line (start -0.85 0.5) (end -0.85 -0.5)
      (stroke (width 0.05) (type solid)) (layer "F.CrtYd"))
    (fp_line (start -0.85 1.4) (end -1.75 1.4)
      (stroke (width 0.05) (type solid)) (layer "F.CrtYd"))
    (fp_line (start -0.85 1.65) (end -0.85 1.4)
      (stroke (width 0.05) (type solid)) (layer "F.CrtYd"))
    (fp_line (start 0.825 -1.6) (end 0.825 -0.45)
      (stroke (width 0.05) (type solid)) (layer "F.CrtYd"))
    (fp_line (start 0.825 -0.45) (end 1.75 -0.45)
      (stroke (width 0.05) (type solid)) (layer "F.CrtYd"))
    (fp_line (start 0.85 0.45) (end 0.85 1.65)
      (stroke (width 0.05) (type solid)) (layer "F.CrtYd"))
    (fp_line (start 0.85 1.65) (end -0.85 1.65)
      (stroke (width 0.05) (type solid)) (layer "F.CrtYd"))
    (fp_line (start 1.75 -0.45) (end 1.75 0.45)
      (stroke (width 0.05) (type solid)) (layer "F.CrtYd"))
    (fp_line (start 1.75 0.45) (end 0.85 0.45)
      (stroke (width 0.05) (type solid)) (layer "F.CrtYd"))
    (fp_line (start -0.712 -1.325) (end -0.712 1.523)
      (stroke (width 0.15) (type solid)) (layer "F.Fab"))
    (fp_line (start -0.712 1.519) (end 0.688 1.519)
      (stroke (width 0.15) (type solid)) (layer "F.Fab"))
    (fp_line (start -0.437 -1.526) (end -0.712 -1.325)
      (stroke (width 0.15) (type solid)) (layer "F.Fab"))
    (fp_line (start -0.437 -1.526) (end 0.688 -1.526)
      (stroke (width 0.15) (type solid)) (layer "F.Fab"))
    (fp_line (start 0.688 1.519) (end 0.688 -1.52)
      (stroke (width 0.15) (type solid)) (layer "F.Fab"))
    (pad "1" smd roundrect (at -1.1 -0.951) (size 1 0.6) (layers "F.Cu" "F.Paste" "F.Mask") (roundrect_rratio 0.15)
      (net 401 "Net-(Q17-G)") (pinfunction "G") (pintype "passive"))
    (pad "2" smd roundrect (at -1.1 0.949) (size 1 0.6) (layers "F.Cu" "F.Paste" "F.Mask") (roundrect_rratio 0.15)
      (net 1 "GND") (pinfunction "S") (pintype "passive"))
    (pad "3" smd roundrect (at 1.1 -0.0005) (size 1 0.6) (layers "F.Cu" "F.Paste" "F.Mask") (roundrect_rratio 0.15)
      (net 349 "Net-(D15-C)") (pinfunction "D") (pintype "passive"))
  )

  (footprint "antmicro-footprints:LED_0603_1608Metric_G" (layer "F.Cu")
    (at 73.32 167.87 180)
    (descr "LED SMD 0603 Green")
    (tags "LED SMD 0603 Green")
    (property "Author" "Antmicro")
    (property "Color" "Green")
    (property "License" "Apache-2.0")
    (property "MPN" "LG L29K-G2J1-24-Z")
    (property "Manufacturer" "OSRAM")
    (property "Sheetfile" "fpga-banks.kicad_sch")
    (property "Sheetname" "FPGA banks")
    (property "ki_description" "LED, Green, SMD, 0603, 20 mA, 1.7 V, 570 nm")
    (property "ki_keywords" "SMT, DIODE, SEMICONDUCTOR, LED")
    (attr smd)
    (fp_text reference "D15" (at -2.35 -0.025) (layer "F.SilkS")
        (effects (font (size 0.7 0.7) (thickness 0.127)))
    )
    (fp_text value "LED_G_0603_LG_L29K-G2J1-24-Z" (at 0 1.77) (layer "F.Fab")
        (effects (font (size 1 1) (thickness 0.15)))
    )
    (fp_text user "Author: Antmicro" (at -1.4224 4.799 180) (layer "F.Fab") hide
        (effects (font (size 0.7 0.7) (thickness 0.15)) (justify left bottom))
    )
    (fp_text user "License: Apache-2.0" (at -1.4224 3.599 180) (layer "F.Fab") hide
        (effects (font (size 0.7 0.7) (thickness 0.15)) (justify left bottom))
    )
    (fp_text user "${REFERENCE}" (at -1.4224 5.999 180) (layer "F.Fab") hide
        (effects (font (size 0.7 0.7) (thickness 0.15)) (justify left bottom))
    )
    (fp_line (start -1.18 -0.319) (end -1.18 0.321)
      (stroke (width 0.15) (type solid)) (layer "F.SilkS"))
    (fp_line (start -0.094672 0.001008) (end -0.24 0.001008)
      (stroke (width 0.1) (type solid)) (layer "F.SilkS"))
    (fp_line (start -0.094672 0.001008) (end 0.105328 -0.198992)
      (stroke (width 0.1) (type solid)) (layer "F.SilkS"))
    (fp_line (start -0.094672 0.201008) (end -0.094672 -0.198992)
      (stroke (width 0.1) (type solid)) (layer "F.SilkS"))
    (fp_line (start 0.105328 0.001008) (end 0.24 0.001)
      (stroke (width 0.1) (type solid)) (layer "F.SilkS"))
    (fp_line (start 0.105328 0.201008) (end -0.094672 0.001008)
      (stroke (width 0.1) (type solid)) (layer "F.SilkS"))
    (fp_line (start 0.105328 0.201008) (end 0.105328 -0.198992)
      (stroke (width 0.1) (type solid)) (layer "F.SilkS"))
    (fp_line (start 0.22 -0.35) (end -0.22 -0.35)
      (stroke (width 0.15) (type solid)) (layer "F.SilkS"))
    (fp_line (start 0.22 0.35) (end -0.22 0.35)
      (stroke (width 0.15) (type solid)) (layer "F.SilkS"))
    (fp_rect (start 1.25 0.65) (end -1.25 -0.65)
      (stroke (width 0.05) (type solid)) (fill none) (layer "F.CrtYd"))
    (fp_line (start -0.199 -0.202) (end -0.199 0.1)
      (stroke (width 0.15) (type solid)) (layer "F.Fab"))
    (fp_line (start -0.199 0) (end -0.597 0)
      (stroke (width 0.15) (type solid)) (layer "F.Fab"))
    (fp_line (start -0.199 0.2) (end -0.199 0.1)
      (stroke (width 0.15) (type solid)) (layer "F.Fab"))
    (fp_line (start -0.101 0) (end 0.201 0.2)
      (stroke (width 0.15) (type solid)) (layer "F.Fab"))
    (fp_line (start 0.201 -0.202) (end -0.101 0)
      (stroke (width 0.15) (type solid)) (layer "F.Fab"))
    (fp_line (start 0.201 0) (end 0.201 -0.202)
      (stroke (width 0.15) (type solid)) (layer "F.Fab"))
    (fp_line (start 0.201 0.2) (end 0.201 0)
      (stroke (width 0.15) (type solid)) (layer "F.Fab"))
    (fp_line (start 0.599 0) (end 0.201 0)
      (stroke (width 0.15) (type solid)) (layer "F.Fab"))
    (fp_rect (start 0.848 0.4) (end -0.85 -0.402)
      (stroke (width 0.15) (type solid)) (fill none) (layer "F.Fab"))
    (pad "1" smd roundrect (at -0.7 0) (size 0.8 1) (layers "F.Cu" "F.Paste" "F.Mask") (roundrect_rratio 0.2)
      (net 349 "Net-(D15-C)") (pinfunction "C") (pintype "passive"))
    (pad "2" smd roundrect (at 0.7 0) (size 0.8 1) (layers "F.Cu" "F.Paste" "F.Mask") (roundrect_rratio 0.2)
      (net 350 "Net-(D15-A)") (pinfunction "A") (pintype "passive"))
  )

  (footprint "antmicro-footprints:R_0402_1005Metric" (layer "F.Cu")
    (at 70.83 167.87)
    (descr "Resistor SMD 0402")
    (tags "resistor SMD 0402")
    (property "Author" "Antmicro")
    (property "License" "Apache-2.0")
    (property "MPN" "CR0402-FX-1001GLF")
    (property "Manufacturer" "Bourns")
    (property "Public" "False")
    (property "Sheetfile" "fpga-banks.kicad_sch")
    (property "Sheetname" "FPGA banks")
    (property "Tolerance" "1%")
    (property "Val" "1k")
    (property "ki_description" "SMD Chip Resistor, 1 kohm, ± 1%, 63 mW, 0402 [1005 Metric], Thick Film, General Purpose")
    (property "ki_keywords" "0402, SMT, RESISTOR, PASSIVE")
    (attr smd)
    (fp_text reference "R130" (at -2.32 0.03) (layer "F.SilkS")
        (effects (font (size 0.7 0.7) (thickness 0.127)))
    )
    (fp_text value "R_1k_0402" (at 0 1.17) (layer "F.Fab")
        (effects (font (size 1 1) (thickness 0.15)))
    )
    (fp_text user "${REFERENCE}" (at 0 0) (layer "F.Fab")
        (effects (font (size 0.25 0.25) (thickness 0.04)))
    )
    (fp_text user "Author: Antmicro" (at -0.95 4.169) (layer "F.Fab") hide
        (effects (font (size 0.7 0.7) (thickness 0.15)) (justify left bottom))
    )
    (fp_text user "License: Apache-2.0" (at -0.95 5.169) (layer "F.Fab") hide
        (effects (font (size 0.7 0.7) (thickness 0.15)) (justify left bottom))
    )
    (fp_rect (start -0.925 -0.47) (end 0.925 0.47)
      (stroke (width 0.05) (type default)) (fill none) (layer "F.CrtYd"))
    (fp_rect (start -0.5 -0.25) (end 0.5 0.25)
      (stroke (width 0.15) (type solid)) (fill none) (layer "F.Fab"))
    (pad "1" smd roundrect (at -0.48 0) (size 0.59 0.64) (layers "F.Cu" "F.Paste" "F.Mask") (roundrect_rratio 0.25)
      (net 2 "VCC3V3") (pintype "passive"))
    (pad "2" smd roundrect (at 0.48 0) (size 0.59 0.64) (layers "F.Cu" "F.Paste" "F.Mask") (roundrect_rratio 0.25)
      (net 350 "Net-(D15-A)") (pintype "passive"))
  )

  (footprint "antmicro-footprints:F_1206_3216Metric" (layer "F.Cu")
    (at 84.69 64.125 180)
    (property "Author" "Antmicro")
    (property "License" "Apache-2.0")
    (property "MPN" "0466003.NR ")
    (property "Manufacturer" "Littelfuse")
    (property "Sheetfile" "power-supply.kicad_sch")
    (property "Sheetname" "Power supply")
    (property "ki_description" "Fuse, Surface Mount, 3 A, Very Fast Acting, 32 V, 32 V, 1206 (3216 Metric), 466")
    (property "ki_keywords" "FUSE, PASSIVE")
    (attr smd)
    (fp_text reference "F1" (at -2.59 0.3 90) (layer "F.SilkS")
        (effects (font (size 0.7 0.7) (thickness 0.127)) (justify right))
    )
    (fp_text value "0466003.NR" (at 0.1778 2.3622) (layer "F.Fab")
        (effects (font (size 1.27 1.27) (thickness 0.15)))
    )
    (fp_text user "License: Apache-2.0" (at -1.95 5.2 180) (layer "F.Fab") hide
        (effects (font (size 0.7 0.7) (thickness 0.15)) (justify left bottom))
    )
    (fp_text user "${REFERENCE}" (at -1.95 4 180) (layer "F.Fab") hide
        (effects (font (size 0.7 0.7) (thickness 0.15)) (justify left bottom))
    )
    (fp_text user "Author: Antmicro" (at -1.95 6.4 180) (layer "F.Fab") hide
        (effects (font (size 0.7 0.7) (thickness 0.15)) (justify left bottom))
    )
    (fp_line (start 0.8 -0.899) (end -0.8 -0.899)
      (stroke (width 0.15) (type solid)) (layer "F.SilkS"))
    (fp_line (start 0.8 0.901) (end -0.8 0.901)
      (stroke (width 0.15) (type solid)) (layer "F.SilkS"))
    (fp_rect (start -2.325 -1.15) (end 2.325 1.15)
      (stroke (width 0.05) (type default)) (fill none) (layer "F.CrtYd"))
    (fp_line (start -1.677 -0.861) (end 1.624 -0.861)
      (stroke (width 0.15) (type solid)) (layer "F.Fab"))
    (fp_line (start -1.677 0.792) (end -1.677 -0.861)
      (stroke (width 0.15) (type solid)) (layer "F.Fab"))
    (fp_line (start 1.624 -0.861) (end 1.624 0.792)
      (stroke (width 0.15) (type solid)) (layer "F.Fab"))
    (fp_line (start 1.624 0.792) (end -1.677 0.792)
      (stroke (width 0.15) (type solid)) (layer "F.Fab"))
    (pad "1" smd roundrect (at -1.5 0.001 180) (size 1.15 1.8) (layers "F.Cu" "F.Paste" "F.Mask") (roundrect_rratio 0.25)
      (net 57 "P12V_AUX") (pintype "passive"))
    (pad "2" smd roundrect (at 1.5 0.001 180) (size 1.15 1.8) (layers "F.Cu" "F.Paste" "F.Mask") (roundrect_rratio 0.25)
      (net 15 "VCC12V") (pintype "passive"))
  )

  (footprint "antmicro-footprints:TP_1206_SMD_RCW-0C" (layer "F.Cu")
    (at 86.03 60.84 90)
    (property "Author" "Antmicro")
    (property "License" "Apache-2.0")
    (property "MPN" "RCW-0C")
    (property "Manufacturer" "TE Connectivity")
    (property "Sheetfile" "power-supply.kicad_sch")
    (property "Sheetname" "Power supply")
    (property "ki_description" "Circuit Probe Pad, SMD, Test Point, 1206")
    (property "ki_keywords" "1206, SMT, TESTPOINT, PASSIVE")
    (attr smd)
    (fp_text reference "TP4" (at 0.955 -3.97 90) (layer "F.SilkS")
        (effects (font (size 0.7 0.7) (thickness 0.127)))
    )
    (fp_text value "RCW-0C" (at 0 2.05 90) (layer "F.Fab")
        (effects (font (size 1 1) (thickness 0.15)))
    )
    (fp_text user "${REFERENCE}" (at 0 0 90) (layer "F.Fab")
        (effects (font (size 0.4 0.4) (thickness 0.04)))
    )
    (fp_text user "Author: Antmicro" (at -4.68 4.25 90) (layer "F.Fab") hide
        (effects (font (size 0.7 0.7) (thickness 0.15)) (justify left bottom))
    )
    (fp_text user "License: Apache-2.0" (at -4.68 5.45 90) (layer "F.Fab") hide
        (effects (font (size 0.7 0.7) (thickness 0.15)) (justify left bottom))
    )
    (fp_line (start -1.779 -0.981) (end -1.779 -0.479)
      (stroke (width 0.15) (type solid)) (layer "F.SilkS"))
    (fp_line (start -1.779 -0.981) (end -1.279 -0.981)
      (stroke (width 0.15) (type solid)) (layer "F.SilkS"))
    (fp_line (start -1.779 0.482) (end -1.779 0.98)
      (stroke (width 0.15) (type solid)) (layer "F.SilkS"))
    (fp_line (start -1.779 0.98) (end -1.279 0.98)
      (stroke (width 0.15) (type solid)) (layer "F.SilkS"))
    (fp_line (start 1.78 -0.981) (end 1.281 -0.981)
      (stroke (width 0.15) (type solid)) (layer "F.SilkS"))
    (fp_line (start 1.78 -0.981) (end 1.78 -0.479)
      (stroke (width 0.15) (type solid)) (layer "F.SilkS"))
    (fp_line (start 1.78 0.982) (end 1.281 0.982)
      (stroke (width 0.15) (type solid)) (layer "F.SilkS"))
    (fp_line (start 1.78 0.982) (end 1.78 0.482)
      (stroke (width 0.15) (type solid)) (layer "F.SilkS"))
    (fp_rect (start -2.101 -1.314) (end 2.1 1.312)
      (stroke (width 0.05) (type solid)) (fill none) (layer "F.CrtYd"))
    (fp_rect (start -1.601 -0.814) (end 1.6 0.812)
      (stroke (width 0.15) (type solid)) (fill none) (layer "F.Fab"))
    (pad "1" smd rect (at 0 0 90) (size 3.4 1.8) (layers "F.Cu" "F.Paste" "F.Mask")
      (net 57 "P12V_AUX") (pinfunction "1") (pintype "passive"))
  )

  (footprint "antmicro-footprints:TP_1206_SMD_RCW-0C" (layer "F.Cu")
    (at 83.6 60.84 90)
    (property "Author" "Antmicro")
    (property "License" "Apache-2.0")
    (property "MPN" "RCW-0C")
    (property "Manufacturer" "TE Connectivity")
    (property "Sheetfile" "power-supply.kicad_sch")
    (property "Sheetname" "Power supply")
    (property "ki_description" "Circuit Probe Pad, SMD, Test Point, 1206")
    (property "ki_keywords" "1206, SMT, TESTPOINT, PASSIVE")
    (attr smd)
    (fp_text reference "TP5" (at 0.94 -2.6 90) (layer "F.SilkS")
        (effects (font (size 0.7 0.7) (thickness 0.127)))
    )
    (fp_text value "RCW-0C" (at 0 2.05 90) (layer "F.Fab")
        (effects (font (size 1 1) (thickness 0.15)))
    )
    (fp_text user "${REFERENCE}" (at 0 0 90) (layer "F.Fab")
        (effects (font (size 0.4 0.4) (thickness 0.04)))
    )
    (fp_text user "License: Apache-2.0" (at -4.68 5.45 90) (layer "F.Fab") hide
        (effects (font (size 0.7 0.7) (thickness 0.15)) (justify left bottom))
    )
    (fp_text user "Author: Antmicro" (at -4.68 4.25 90) (layer "F.Fab") hide
        (effects (font (size 0.7 0.7) (thickness 0.15)) (justify left bottom))
    )
    (fp_line (start -1.779 -0.981) (end -1.779 -0.479)
      (stroke (width 0.15) (type solid)) (layer "F.SilkS"))
    (fp_line (start -1.779 -0.981) (end -1.279 -0.981)
      (stroke (width 0.15) (type solid)) (layer "F.SilkS"))
    (fp_line (start -1.779 0.482) (end -1.779 0.98)
      (stroke (width 0.15) (type solid)) (layer "F.SilkS"))
    (fp_line (start -1.779 0.98) (end -1.279 0.98)
      (stroke (width 0.15) (type solid)) (layer "F.SilkS"))
    (fp_line (start 1.78 -0.981) (end 1.281 -0.981)
      (stroke (width 0.15) (type solid)) (layer "F.SilkS"))
    (fp_line (start 1.78 -0.981) (end 1.78 -0.479)
      (stroke (width 0.15) (type solid)) (layer "F.SilkS"))
    (fp_line (start 1.78 0.982) (end 1.281 0.982)
      (stroke (width 0.15) (type solid)) (layer "F.SilkS"))
    (fp_line (start 1.78 0.982) (end 1.78 0.482)
      (stroke (width 0.15) (type solid)) (layer "F.SilkS"))
    (fp_rect (start -2.101 -1.314) (end 2.1 1.312)
      (stroke (width 0.05) (type solid)) (fill none) (layer "F.CrtYd"))
    (fp_rect (start -1.601 -0.814) (end 1.6 0.812)
      (stroke (width 0.15) (type solid)) (fill none) (layer "F.Fab"))
    (pad "1" smd rect (at 0 0 90) (size 3.4 1.8) (layers "F.Cu" "F.Paste" "F.Mask")
      (net 1 "GND") (pinfunction "1") (pintype "passive"))
  )

  (footprint "antmicro-footprints:C_0402_1005Metric" (layer "F.Cu")
    (at 135.545 168.325 -90)
    (descr "Capacitor SMD 0402")
    (tags "capacitor SMD 0402")
    (property "Author" "Antmicro")
    (property "Dielectric" "X5R")
    (property "License" "Apache-2.0")
    (property "MPN" "GRM155R61H104KE14D")
    (property "Manufacturer" "Murata")
    (property "Public" "False")
    (property "Sheetfile" "pcie-conn.kicad_sch")
    (property "Sheetname" "PCIe-connector")
    (property "Val" "100n")
    (property "Voltage" "50V")
    (property "ki_description" "SMD Multilayer Ceramic Capacitor, 0.1 µF, 50 V, 0402 [1005 Metric], ± 10%, X5R, GRM Series")
    (property "ki_keywords" "0402, SMT, CAPACITOR, PASSIVE, CERAMIC, MLCC")
    (attr smd)
    (fp_text reference "C34" (at 2.14 -0.01 90) (layer "F.SilkS")
        (effects (font (size 0.7 0.7) (thickness 0.127)))
    )
    (fp_text value "C_100n_0402" (at 0 1.17 90) (layer "F.Fab")
        (effects (font (size 1 1) (thickness 0.15)))
    )
    (fp_text user "License: Apache-2.0" (at -0.939 5.799 -90) (layer "F.Fab") hide
        (effects (font (size 0.7 0.7) (thickness 0.15)) (justify left bottom))
    )
    (fp_text user "Author: Antmicro" (at -0.939 3.399 -90) (layer "F.Fab") hide
        (effects (font (size 0.7 0.7) (thickness 0.15)) (justify left bottom))
    )
    (fp_text user "${REFERENCE}" (at 0 0 90) (layer "F.Fab")
        (effects (font (size 0.25 0.25) (thickness 0.04)))
    )
    (fp_rect (start -0.925 -0.47) (end 0.925 0.47)
      (stroke (width 0.05) (type default)) (fill none) (layer "F.CrtYd"))
    (fp_line (start -0.494 -0.25) (end 0.504 -0.25)
      (stroke (width 0.15) (type solid)) (layer "F.Fab"))
    (fp_line (start -0.494 0.248) (end -0.494 -0.25)
      (stroke (width 0.15) (type solid)) (layer "F.Fab"))
    (fp_line (start 0.504 -0.25) (end 0.504 0.248)
      (stroke (width 0.15) (type solid)) (layer "F.Fab"))
    (fp_line (start 0.504 0.248) (end -0.494 0.248)
      (stroke (width 0.15) (type solid)) (layer "F.Fab"))
    (pad "1" smd roundrect (at -0.48 0 270) (size 0.59 0.64) (layers "F.Cu" "F.Paste" "F.Mask") (roundrect_rratio 0.25)
      (net 212 "Net-(J2-PET3_P)") (pintype "passive"))
    (pad "2" smd roundrect (at 0.48 0 270) (size 0.59 0.64) (layers "F.Cu" "F.Paste" "F.Mask") (roundrect_rratio 0.25)
      (net 691 "PCIE_HPM_TX3_P") (pintype "passive"))
  )

  (footprint "antmicro-footprints:antmicro-logo_scaled_20mm" (layer "F.Cu")
    (at 92.8 154.6)
    (property "Author" "Antmicro")
    (property "License" "Apache-2.0")
    (property "MPN" "")
    (property "Manufacturer" "")
    (property "Public" "False")
    (property "Sheetfile" "ecp5-dc-scm.kicad_sch")
    (property "Sheetname" "")
    (property "ki_description" "Mechanical part")
    (attr allow_soldermask_bridges)
    (fp_text reference "N1" (at 0.05 -5.5) (layer "F.SilkS") hide
        (effects (font (size 0.7 0.7) (thickness 0.15)) (justify left bottom))
    )
    (fp_text value "antmicro_logo" (at -0.101 5.099) (layer "F.SilkS") hide
        (effects (font (size 0.7 0.7) (thickness 0.15)) (justify left bottom))
    )
    (fp_text user "License: Apache-2.0" (at -9.998 9.499) (layer "F.Fab") hide
        (effects (font (size 0.7 0.7) (thickness 0.15)) (justify left bottom))
    )
    (fp_text user "${REFERENCE}" (at -9.998 7.099) (layer "F.Fab") hide
        (effects (font (size 0.7 0.7) (thickness 0.15)) (justify left bottom))
    )
    (fp_text user "Author: Antmicro" (at -9.998 8.299) (layer "F.Fab") hide
        (effects (font (size 0.7 0.7) (thickness 0.15)) (justify left bottom))
    )
    (fp_poly
      (pts
        (xy 5.212 0.944)
        (xy 4.834 0.944)
        (xy 4.834 -1.292)
        (xy 5.212 -1.292)
        (xy 5.212 0.944)
      )

      (stroke (width 0.00186) (type solid)) (fill solid) (layer "F.Cu"))
    (fp_poly
      (pts
        (xy 8.164 -1.321)
        (xy 8.193 -1.317)
        (xy 8.204 -1.31)
        (xy 8.204 -1.308)
        (xy 8.2 -1.285)
        (xy 8.188 -1.24)
        (xy 8.171 -1.181)
        (xy 8.163 -1.156)
        (xy 8.142 -1.092)
        (xy 8.126 -1.053)
        (xy 8.112 -1.034)
        (xy 8.097 -1.031)
        (xy 8.094 -1.032)
        (xy 7.996 -1.053)
        (xy 7.886 -1.06)
        (xy 7.778 -1.053)
        (xy 7.683 -1.032)
        (xy 7.665 -1.026)
        (xy 7.622 -1.009)
        (xy 7.622 0.944)
        (xy 7.244 0.944)
        (xy 7.244 -1.178)
        (xy 7.358 -1.219)
        (xy 7.457 -1.253)
        (xy 7.548 -1.277)
        (xy 7.639 -1.295)
        (xy 7.738 -1.307)
        (xy 7.856 -1.315)
        (xy 7.94 -1.319)
        (xy 8.042 -1.322)
        (xy 8.115 -1.322)
        (xy 8.164 -1.321)
      )

      (stroke (width 0.00186) (type solid)) (fill solid) (layer "F.Cu"))
    (fp_poly
      (pts
        (xy 0.795 -1.891)
        (xy 0.798 -1.849)
        (xy 0.8 -1.786)
        (xy 0.802 -1.705)
        (xy 0.803 -1.612)
        (xy 0.803 -1.599)
        (xy 0.803 -1.292)
        (xy 1.181 -1.292)
        (xy 1.181 -1.04)
        (xy 0.803 -1.04)
        (xy 0.803 0.498)
        (xy 0.838 0.566)
        (xy 0.885 0.631)
        (xy 0.944 0.671)
        (xy 1.021 0.688)
        (xy 1.082 0.689)
        (xy 1.181 0.685)
        (xy 1.181 0.806)
        (xy 1.178 0.88)
        (xy 1.17 0.926)
        (xy 1.161 0.939)
        (xy 1.138 0.945)
        (xy 1.09 0.95)
        (xy 1.028 0.954)
        (xy 0.984 0.956)
        (xy 0.897 0.957)
        (xy 0.832 0.953)
        (xy 0.778 0.942)
        (xy 0.743 0.931)
        (xy 0.647 0.886)
        (xy 0.571 0.823)
        (xy 0.508 0.737)
        (xy 0.488 0.701)
        (xy 0.433 0.593)
        (xy 0.428 -0.223)
        (xy 0.424 -1.04)
        (xy 0.173 -1.04)
        (xy 0.173 -1.292)
        (xy 0.425 -1.292)
        (xy 0.425 -1.795)
        (xy 0.603 -1.85)
        (xy 0.673 -1.872)
        (xy 0.733 -1.89)
        (xy 0.774 -1.902)
        (xy 0.792 -1.906)
        (xy 0.795 -1.891)
      )

      (stroke (width 0.00186) (type solid)) (fill solid) (layer "F.Cu"))
    (fp_poly
      (pts
        (xy -0.82 -1.315)
        (xy -0.737 -1.312)
        (xy -0.672 -1.308)
        (xy -0.621 -1.301)
        (xy -0.577 -1.291)
        (xy -0.56 -1.286)
        (xy -0.417 -1.232)
        (xy -0.302 -1.164)
        (xy -0.212 -1.082)
        (xy -0.154 -0.996)
        (xy -0.135 -0.961)
        (xy -0.119 -0.927)
        (xy -0.105 -0.893)
        (xy -0.094 -0.855)
        (xy -0.085 -0.811)
        (xy -0.078 -0.758)
        (xy -0.073 -0.693)
        (xy -0.069 -0.612)
        (xy -0.067 -0.515)
        (xy -0.065 -0.397)
        (xy -0.064 -0.256)
        (xy -0.064 -0.088)
        (xy -0.063 0.105)
        (xy -0.063 0.944)
        (xy -0.441 0.944)
        (xy -0.441 0.113)
        (xy -0.442 -0.083)
        (xy -0.442 -0.25)
        (xy -0.443 -0.391)
        (xy -0.445 -0.508)
        (xy -0.448 -0.604)
        (xy -0.452 -0.682)
        (xy -0.457 -0.744)
        (xy -0.465 -0.794)
        (xy -0.474 -0.833)
        (xy -0.486 -0.864)
        (xy -0.501 -0.89)
        (xy -0.518 -0.913)
        (xy -0.538 -0.937)
        (xy -0.539 -0.939)
        (xy -0.604 -0.997)
        (xy -0.684 -1.039)
        (xy -0.784 -1.066)
        (xy -0.822 -1.072)
        (xy -0.927 -1.078)
        (xy -1.044 -1.073)
        (xy -1.158 -1.056)
        (xy -1.24 -1.034)
        (xy -1.3 -1.013)
        (xy -1.304 -0.034)
        (xy -1.308 0.944)
        (xy -1.686 0.944)
        (xy -1.686 -1.178)
        (xy -1.54 -1.225)
        (xy -1.44 -1.257)
        (xy -1.354 -1.28)
        (xy -1.276 -1.297)
        (xy -1.195 -1.307)
        (xy -1.105 -1.313)
        (xy -0.995 -1.315)
        (xy -0.93 -1.315)
        (xy -0.82 -1.315)
      )

      (stroke (width 0.00186) (type solid)) (fill solid) (layer "F.Cu"))
    (fp_poly
      (pts
        (xy 3.757 -1.312)
        (xy 3.91 -1.278)
        (xy 4.043 -1.223)
        (xy 4.153 -1.146)
        (xy 4.24 -1.047)
        (xy 4.282 -0.977)
        (xy 4.299 -0.943)
        (xy 4.313 -0.91)
        (xy 4.325 -0.876)
        (xy 4.335 -0.837)
        (xy 4.343 -0.791)
        (xy 4.349 -0.734)
        (xy 4.353 -0.665)
        (xy 4.357 -0.581)
        (xy 4.359 -0.478)
        (xy 4.361 -0.354)
        (xy 4.361 -0.206)
        (xy 4.362 -0.031)
        (xy 4.362 0.111)
        (xy 4.362 0.944)
        (xy 3.985 0.944)
        (xy 3.98 0.074)
        (xy 3.976 -0.796)
        (xy 3.93 -0.879)
        (xy 3.867 -0.961)
        (xy 3.786 -1.022)
        (xy 3.691 -1.062)
        (xy 3.586 -1.079)
        (xy 3.476 -1.074)
        (xy 3.366 -1.045)
        (xy 3.26 -0.994)
        (xy 3.185 -0.938)
        (xy 3.118 -0.88)
        (xy 3.118 0.944)
        (xy 2.74 0.944)
        (xy 2.74 0.092)
        (xy 2.739 -0.122)
        (xy 2.739 -0.305)
        (xy 2.737 -0.459)
        (xy 2.735 -0.585)
        (xy 2.732 -0.683)
        (xy 2.729 -0.755)
        (xy 2.725 -0.802)
        (xy 2.722 -0.821)
        (xy 2.679 -0.91)
        (xy 2.613 -0.981)
        (xy 2.523 -1.034)
        (xy 2.413 -1.067)
        (xy 2.284 -1.079)
        (xy 2.154 -1.073)
        (xy 2.082 -1.064)
        (xy 2.031 -1.056)
        (xy 1.989 -1.046)
        (xy 1.944 -1.031)
        (xy 1.917 -1.021)
        (xy 1.874 -1.005)
        (xy 1.874 0.944)
        (xy 1.511 0.944)
        (xy 1.511 -1.18)
        (xy 1.661 -1.228)
        (xy 1.83 -1.276)
        (xy 1.988 -1.306)
        (xy 2.148 -1.319)
        (xy 2.314 -1.319)
        (xy 2.448 -1.311)
        (xy 2.557 -1.297)
        (xy 2.649 -1.272)
        (xy 2.732 -1.237)
        (xy 2.811 -1.189)
        (xy 2.843 -1.165)
        (xy 2.947 -1.087)
        (xy 3.012 -1.14)
        (xy 3.14 -1.224)
        (xy 3.283 -1.283)
        (xy 3.443 -1.315)
        (xy 3.582 -1.323)
        (xy 3.757 -1.312)
      )

      (stroke (width 0.00186) (type solid)) (fill solid) (layer "F.Cu"))
    (fp_poly
      (pts
        (xy 9.278 -1.313)
        (xy 9.419 -1.281)
        (xy 9.543 -1.225)
        (xy 9.656 -1.146)
        (xy 9.708 -1.097)
        (xy 9.808 -0.975)
        (xy 9.887 -0.831)
        (xy 9.945 -0.666)
        (xy 9.984 -0.476)
        (xy 9.998 -0.354)
        (xy 10.005 -0.134)
        (xy 9.992 0.072)
        (xy 9.96 0.262)
        (xy 9.908 0.434)
        (xy 9.837 0.585)
        (xy 9.749 0.714)
        (xy 9.643 0.819)
        (xy 9.578 0.867)
        (xy 9.475 0.918)
        (xy 9.352 0.956)
        (xy 9.219 0.98)
        (xy 9.087 0.986)
        (xy 8.966 0.975)
        (xy 8.81 0.933)
        (xy 8.673 0.864)
        (xy 8.553 0.771)
        (xy 8.452 0.653)
        (xy 8.371 0.511)
        (xy 8.31 0.346)
        (xy 8.277 0.202)
        (xy 8.249 -0.011)
        (xy 8.243 -0.182)
        (xy 8.619 -0.182)
        (xy 8.626 -0.007)
        (xy 8.647 0.163)
        (xy 8.682 0.318)
        (xy 8.73 0.449)
        (xy 8.792 0.552)
        (xy 8.87 0.633)
        (xy 8.961 0.69)
        (xy 9.06 0.721)
        (xy 9.164 0.724)
        (xy 9.268 0.699)
        (xy 9.303 0.683)
        (xy 9.391 0.625)
        (xy 9.465 0.546)
        (xy 9.524 0.443)
        (xy 9.569 0.315)
        (xy 9.601 0.162)
        (xy 9.62 0)
        (xy 9.628 -0.198)
        (xy 9.62 -0.382)
        (xy 9.597 -0.55)
        (xy 9.558 -0.698)
        (xy 9.505 -0.825)
        (xy 9.439 -0.927)
        (xy 9.397 -0.971)
        (xy 9.307 -1.035)
        (xy 9.21 -1.071)
        (xy 9.109 -1.079)
        (xy 9.009 -1.062)
        (xy 8.915 -1.019)
        (xy 8.831 -0.953)
        (xy 8.76 -0.863)
        (xy 8.733 -0.813)
        (xy 8.684 -0.68)
        (xy 8.648 -0.526)
        (xy 8.627 -0.358)
        (xy 8.619 -0.182)
        (xy 8.243 -0.182)
        (xy 8.242 -0.218)
        (xy 8.255 -0.417)
        (xy 8.288 -0.602)
        (xy 8.339 -0.772)
        (xy 8.41 -0.923)
        (xy 8.498 -1.051)
        (xy 8.524 -1.081)
        (xy 8.637 -1.182)
        (xy 8.765 -1.255)
        (xy 8.908 -1.302)
        (xy 9.068 -1.322)
        (xy 9.117 -1.323)
        (xy 9.278 -1.313)
      )

      (stroke (width 0.00186) (type solid)) (fill solid) (layer "F.Cu"))
    (fp_poly
      (pts
        (xy 6.48 -1.32)
        (xy 6.584 -1.31)
        (xy 6.642 -1.3)
        (xy 6.701 -1.282)
        (xy 6.765 -1.259)
        (xy 6.825 -1.233)
        (xy 6.873 -1.209)
        (xy 6.9 -1.189)
        (xy 6.902 -1.186)
        (xy 6.901 -1.166)
        (xy 6.889 -1.128)
        (xy 6.872 -1.079)
        (xy 6.852 -1.03)
        (xy 6.833 -0.989)
        (xy 6.818 -0.966)
        (xy 6.815 -0.963)
        (xy 6.795 -0.969)
        (xy 6.757 -0.985)
        (xy 6.717 -1.002)
        (xy 6.597 -1.044)
        (xy 6.478 -1.06)
        (xy 6.365 -1.05)
        (xy 6.267 -1.016)
        (xy 6.184 -0.957)
        (xy 6.109 -0.87)
        (xy 6.042 -0.76)
        (xy 5.988 -0.629)
        (xy 5.964 -0.554)
        (xy 5.946 -0.461)
        (xy 5.934 -0.347)
        (xy 5.929 -0.22)
        (xy 5.931 -0.091)
        (xy 5.938 0.032)
        (xy 5.953 0.138)
        (xy 5.965 0.191)
        (xy 6.018 0.347)
        (xy 6.085 0.476)
        (xy 6.166 0.576)
        (xy 6.262 0.649)
        (xy 6.269 0.653)
        (xy 6.318 0.678)
        (xy 6.36 0.692)
        (xy 6.409 0.698)
        (xy 6.476 0.7)
        (xy 6.48 0.7)
        (xy 6.551 0.697)
        (xy 6.613 0.686)
        (xy 6.676 0.665)
        (xy 6.75 0.631)
        (xy 6.805 0.602)
        (xy 6.811 0.606)
        (xy 6.823 0.627)
        (xy 6.842 0.667)
        (xy 6.868 0.73)
        (xy 6.904 0.819)
        (xy 6.907 0.827)
        (xy 6.898 0.844)
        (xy 6.866 0.868)
        (xy 6.818 0.895)
        (xy 6.759 0.922)
        (xy 6.697 0.945)
        (xy 6.68 0.95)
        (xy 6.596 0.968)
        (xy 6.494 0.98)
        (xy 6.388 0.984)
        (xy 6.292 0.98)
        (xy 6.251 0.975)
        (xy 6.192 0.96)
        (xy 6.121 0.935)
        (xy 6.055 0.906)
        (xy 5.924 0.825)
        (xy 5.811 0.718)
        (xy 5.717 0.586)
        (xy 5.641 0.431)
        (xy 5.585 0.252)
        (xy 5.566 0.164)
        (xy 5.552 0.061)
        (xy 5.545 -0.061)
        (xy 5.544 -0.193)
        (xy 5.549 -0.327)
        (xy 5.56 -0.453)
        (xy 5.576 -0.563)
        (xy 5.589 -0.623)
        (xy 5.65 -0.797)
        (xy 5.731 -0.949)
        (xy 5.831 -1.077)
        (xy 5.948 -1.181)
        (xy 6.081 -1.259)
        (xy 6.187 -1.298)
        (xy 6.27 -1.314)
        (xy 6.372 -1.322)
        (xy 6.48 -1.32)
      )

      (stroke (width 0.00186) (type solid)) (fill solid) (layer "F.Cu"))
    (fp_poly
      (pts
        (xy -2.763 -1.313)
        (xy -2.663 -1.294)
        (xy -2.55 -1.259)
        (xy -2.459 -1.216)
        (xy -2.38 -1.16)
        (xy -2.341 -1.124)
        (xy -2.284 -1.053)
        (xy -2.232 -0.961)
        (xy -2.192 -0.861)
        (xy -2.174 -0.79)
        (xy -2.17 -0.754)
        (xy -2.167 -0.69)
        (xy -2.164 -0.599)
        (xy -2.162 -0.485)
        (xy -2.16 -0.35)
        (xy -2.159 -0.196)
        (xy -2.158 -0.027)
        (xy -2.158 0.064)
        (xy -2.158 0.833)
        (xy -2.232 0.865)
        (xy -2.364 0.913)
        (xy -2.517 0.949)
        (xy -2.682 0.974)
        (xy -2.85 0.986)
        (xy -3.011 0.983)
        (xy -3.097 0.975)
        (xy -3.264 0.942)
        (xy -3.407 0.889)
        (xy -3.525 0.817)
        (xy -3.618 0.725)
        (xy -3.686 0.616)
        (xy -3.729 0.487)
        (xy -3.746 0.341)
        (xy -3.746 0.268)
        (xy -3.744 0.254)
        (xy -3.383 0.254)
        (xy -3.38 0.384)
        (xy -3.352 0.497)
        (xy -3.298 0.591)
        (xy -3.221 0.665)
        (xy -3.12 0.719)
        (xy -3.072 0.735)
        (xy -3.011 0.745)
        (xy -2.928 0.75)
        (xy -2.835 0.75)
        (xy -2.74 0.744)
        (xy -2.655 0.734)
        (xy -2.589 0.72)
        (xy -2.579 0.716)
        (xy -2.504 0.689)
        (xy -2.504 -0.302)
        (xy -2.595 -0.291)
        (xy -2.653 -0.282)
        (xy -2.728 -0.267)
        (xy -2.806 -0.25)
        (xy -2.831 -0.244)
        (xy -2.992 -0.194)
        (xy -3.125 -0.133)
        (xy -3.229 -0.06)
        (xy -3.306 0.026)
        (xy -3.357 0.125)
        (xy -3.381 0.238)
        (xy -3.383 0.254)
        (xy -3.744 0.254)
        (xy -3.725 0.126)
        (xy -3.678 0)
        (xy -3.602 -0.112)
        (xy -3.559 -0.158)
        (xy -3.465 -0.233)
        (xy -3.343 -0.303)
        (xy -3.198 -0.365)
        (xy -3.034 -0.417)
        (xy -2.856 -0.46)
        (xy -2.666 -0.49)
        (xy -2.663 -0.49)
        (xy -2.5 -0.51)
        (xy -2.51 -0.644)
        (xy -2.528 -0.77)
        (xy -2.564 -0.871)
        (xy -2.62 -0.949)
        (xy -2.697 -1.007)
        (xy -2.797 -1.045)
        (xy -2.845 -1.056)
        (xy -2.975 -1.067)
        (xy -3.12 -1.056)
        (xy -3.272 -1.024)
        (xy -3.426 -0.972)
        (xy -3.439 -0.967)
        (xy -3.488 -0.947)
        (xy -3.523 -0.936)
        (xy -3.537 -0.934)
        (xy -3.545 -0.95)
        (xy -3.56 -0.987)
        (xy -3.579 -1.035)
        (xy -3.598 -1.086)
        (xy -3.613 -1.129)
        (xy -3.622 -1.155)
        (xy -3.623 -1.159)
        (xy -3.609 -1.169)
        (xy -3.575 -1.188)
        (xy -3.537 -1.206)
        (xy -3.395 -1.257)
        (xy -3.239 -1.294)
        (xy -3.075 -1.316)
        (xy -2.914 -1.323)
        (xy -2.763 -1.313)
      )

      (stroke (width 0.00186) (type solid)) (fill solid) (layer "F.Cu"))
    (fp_poly
      (pts
        (xy -7.153 -3.366)
        (xy -7.087 -3.351)
        (xy -7.086 -3.351)
        (xy -7.066 -3.34)
        (xy -7.021 -3.315)
        (xy -6.953 -3.277)
        (xy -6.865 -3.227)
        (xy -6.759 -3.167)
        (xy -6.639 -3.099)
        (xy -6.505 -3.022)
        (xy -6.361 -2.94)
        (xy -6.209 -2.853)
        (xy -6.052 -2.762)
        (xy -5.891 -2.67)
        (xy -5.729 -2.577)
        (xy -5.569 -2.485)
        (xy -5.413 -2.395)
        (xy -5.264 -2.309)
        (xy -5.123 -2.227)
        (xy -4.994 -2.152)
        (xy -4.878 -2.085)
        (xy -4.778 -2.027)
        (xy -4.697 -1.979)
        (xy -4.636 -1.943)
        (xy -4.599 -1.921)
        (xy -4.595 -1.918)
        (xy -4.528 -1.863)
        (xy -4.476 -1.798)
        (xy -4.434 -1.725)
        (xy -4.429 -0.224)
        (xy -4.429 0.063)
        (xy -4.428 0.323)
        (xy -4.429 0.553)
        (xy -4.429 0.755)
        (xy -4.43 0.928)
        (xy -4.432 1.071)
        (xy -4.434 1.184)
        (xy -4.436 1.266)
        (xy -4.439 1.318)
        (xy -4.441 1.337)
        (xy -4.448 1.36)
        (xy -4.454 1.382)
        (xy -4.463 1.403)
        (xy -4.476 1.423)
        (xy -4.494 1.445)
        (xy -4.519 1.47)
        (xy -4.552 1.497)
        (xy -4.596 1.529)
        (xy -4.652 1.567)
        (xy -4.721 1.611)
        (xy -4.805 1.663)
        (xy -4.906 1.723)
        (xy -5.025 1.794)
        (xy -5.165 1.875)
        (xy -5.326 1.969)
        (xy -5.511 2.076)
        (xy -5.72 2.197)
        (xy -5.813 2.251)
        (xy -7.079 2.982)
        (xy -7.197 2.988)
        (xy -7.315 2.994)
        (xy -7.78 2.727)
        (xy -8.064 2.563)
        (xy -8.323 2.415)
        (xy -8.557 2.28)
        (xy -8.767 2.159)
        (xy -8.955 2.051)
        (xy -9.122 1.954)
        (xy -9.27 1.868)
        (xy -9.399 1.792)
        (xy -9.51 1.726)
        (xy -9.606 1.669)
        (xy -9.688 1.619)
        (xy -9.756 1.576)
        (xy -9.812 1.539)
        (xy -9.857 1.507)
        (xy -9.893 1.481)
        (xy -9.92 1.458)
        (xy -9.94 1.437)
        (xy -9.955 1.42)
        (xy -9.965 1.403)
        (xy -9.972 1.387)
        (xy -9.977 1.371)
        (xy -9.981 1.354)
        (xy -9.985 1.337)
        (xy -9.988 1.309)
        (xy -9.991 1.25)
        (xy -9.993 1.161)
        (xy -9.995 1.041)
        (xy -9.996 0.891)
        (xy -9.997 0.712)
        (xy -9.998 0.503)
        (xy -9.998 0.266)
        (xy -9.997 0)
        (xy -9.997 -0.189)
        (xy -9.024 -0.189)
        (xy -9.024 0.015)
        (xy -9.024 0.191)
        (xy -9.023 0.34)
        (xy -9.022 0.464)
        (xy -9.021 0.567)
        (xy -9.018 0.65)
        (xy -9.014 0.717)
        (xy -9.01 0.768)
        (xy -9.003 0.808)
        (xy -8.995 0.837)
        (xy -8.986 0.859)
        (xy -8.974 0.876)
        (xy -8.961 0.891)
        (xy -8.945 0.905)
        (xy -8.943 0.906)
        (xy -8.922 0.921)
        (xy -8.877 0.949)
        (xy -8.81 0.989)
        (xy -8.725 1.039)
        (xy -8.625 1.098)
        (xy -8.512 1.164)
        (xy -8.389 1.235)
        (xy -8.26 1.31)
        (xy -8.128 1.386)
        (xy -7.995 1.463)
        (xy -7.864 1.538)
        (xy -7.739 1.609)
        (xy -7.622 1.676)
        (xy -7.517 1.735)
        (xy -7.425 1.787)
        (xy -7.351 1.828)
        (xy -7.297 1.857)
        (xy -7.266 1.872)
        (xy -7.261 1.874)
        (xy -7.222 1.885)
        (xy -7.195 1.886)
        (xy -7.163 1.875)
        (xy -7.144 1.867)
        (xy -7.117 1.854)
        (xy -7.067 1.827)
        (xy -6.997 1.788)
        (xy -6.909 1.738)
        (xy -6.805 1.679)
        (xy -6.691 1.614)
        (xy -6.567 1.543)
        (xy -6.438 1.469)
        (xy -6.306 1.392)
        (xy -6.174 1.316)
        (xy -6.045 1.241)
        (xy -5.922 1.17)
        (xy -5.809 1.103)
        (xy -5.708 1.044)
        (xy -5.622 0.992)
        (xy -5.553 0.952)
        (xy -5.507 0.923)
        (xy -5.484 0.907)
        (xy -5.483 0.907)
        (xy -5.467 0.892)
        (xy -5.453 0.878)
        (xy -5.441 0.861)
        (xy -5.431 0.839)
        (xy -5.423 0.81)
        (xy -5.417 0.772)
        (xy -5.412 0.721)
        (xy -5.408 0.656)
        (xy -5.406 0.574)
        (xy -5.404 0.473)
        (xy -5.403 0.35)
        (xy -5.402 0.203)
        (xy -5.402 0.03)
        (xy -5.402 -0.172)
        (xy -5.402 -0.189)
        (xy -5.402 -0.395)
        (xy -5.402 -0.572)
        (xy -5.403 -0.721)
        (xy -5.404 -0.847)
        (xy -5.406 -0.95)
        (xy -5.408 -1.034)
        (xy -5.412 -1.101)
        (xy -5.418 -1.153)
        (xy -5.425 -1.193)
        (xy -5.434 -1.223)
        (xy -5.445 -1.245)
        (xy -5.458 -1.262)
        (xy -5.473 -1.276)
        (xy -5.491 -1.29)
        (xy -5.499 -1.295)
        (xy -5.522 -1.31)
        (xy -5.57 -1.339)
        (xy -5.64 -1.381)
        (xy -5.729 -1.433)
        (xy -5.835 -1.496)
        (xy -5.956 -1.566)
        (xy -6.088 -1.643)
        (xy -6.229 -1.725)
        (xy -6.348 -1.793)
        (xy -6.519 -1.891)
        (xy -6.664 -1.974)
        (xy -6.786 -2.044)
        (xy -6.888 -2.101)
        (xy -6.971 -2.147)
        (xy -7.038 -2.183)
        (xy -7.091 -2.21)
        (xy -7.132 -2.229)
        (xy -7.163 -2.242)
        (xy -7.187 -2.249)
        (xy -7.205 -2.252)
        (xy -7.211 -2.252)
        (xy -7.228 -2.251)
        (xy -7.249 -2.246)
        (xy -7.276 -2.236)
        (xy -7.312 -2.219)
        (xy -7.359 -2.196)
        (xy -7.419 -2.165)
        (xy -7.495 -2.123)
        (xy -7.587 -2.072)
        (xy -7.699 -2.008)
        (xy -7.832 -1.932)
        (xy -7.99 -1.842)
        (xy -8.1 -1.778)
        (xy -8.248 -1.693)
        (xy -8.388 -1.611)
        (xy -8.519 -1.535)
        (xy -8.637 -1.466)
        (xy -8.739 -1.406)
        (xy -8.825 -1.355)
        (xy -8.89 -1.316)
        (xy -8.933 -1.29)
        (xy -8.951 -1.278)
        (xy -8.966 -1.265)
        (xy -8.978 -1.251)
        (xy -8.989 -1.234)
        (xy -8.998 -1.212)
        (xy -9.005 -1.182)
        (xy -9.011 -1.141)
        (xy -9.015 -1.087)
        (xy -9.018 -1.019)
        (xy -9.021 -0.933)
        (xy -9.022 -0.827)
        (xy -9.023 -0.699)
        (xy -9.024 -0.546)
        (xy -9.024 -0.366)
        (xy -9.024 -0.189)
        (xy -9.997 -0.189)
        (xy -9.997 -0.224)
        (xy -9.996 -0.479)
        (xy -9.996 -0.705)
        (xy -9.995 -0.903)
        (xy -9.994 -1.075)
        (xy -9.993 -1.223)
        (xy -9.992 -1.35)
        (xy -9.99 -1.456)
        (xy -9.987 -1.545)
        (xy -9.984 -1.617)
        (xy -9.98 -1.675)
        (xy -9.974 -1.721)
        (xy -9.968 -1.757)
        (xy -9.961 -1.784)
        (xy -9.952 -1.805)
        (xy -9.941 -1.821)
        (xy -9.929 -1.834)
        (xy -9.915 -1.847)
        (xy -9.9 -1.86)
        (xy -9.893 -1.866)
        (xy -9.873 -1.88)
        (xy -9.828 -1.909)
        (xy -9.759 -1.951)
        (xy -9.669 -2.005)
        (xy -9.56 -2.07)
        (xy -9.433 -2.145)
        (xy -9.291 -2.228)
        (xy -9.136 -2.319)
        (xy -8.969 -2.416)
        (xy -8.793 -2.518)
        (xy -8.61 -2.624)
        (xy -8.59 -2.635)
        (xy -8.377 -2.759)
        (xy -8.189 -2.867)
        (xy -8.024 -2.962)
        (xy -7.882 -3.044)
        (xy -7.759 -3.114)
        (xy -7.656 -3.173)
        (xy -7.568 -3.221)
        (xy -7.496 -3.261)
        (xy -7.437 -3.293)
        (xy -7.389 -3.317)
        (xy -7.351 -3.336)
        (xy -7.321 -3.349)
        (xy -7.296 -3.357)
        (xy -7.276 -3.363)
        (xy -7.259 -3.366)
        (xy -7.242 -3.367)
        (xy -7.237 -3.368)
        (xy -7.153 -3.366)
      )

      (stroke (width 0.00186) (type solid)) (fill solid) (layer "F.Cu"))
    (fp_poly
      (pts
        (xy -7.128 -1.48)
        (xy -7.114 -1.475)
        (xy -7.042 -1.428)
        (xy -6.989 -1.361)
        (xy -6.96 -1.281)
        (xy -6.957 -1.196)
        (xy -6.961 -1.175)
        (xy -6.992 -1.094)
        (xy -7.046 -1.034)
        (xy -7.101 -1.001)
        (xy -7.166 -0.969)
        (xy -7.166 -0.599)
        (xy -6.891 -0.599)
        (xy -6.778 -0.711)
        (xy -6.665 -0.824)
        (xy -6.673 -0.905)
        (xy -6.673 -0.906)
        (xy -6.566 -0.906)
        (xy -6.549 -0.87)
        (xy -6.512 -0.853)
        (xy -6.467 -0.856)
        (xy -6.435 -0.876)
        (xy -6.412 -0.913)
        (xy -6.42 -0.95)
        (xy -6.441 -0.977)
        (xy -6.471 -1.002)
        (xy -6.496 -1.005)
        (xy -6.53 -0.986)
        (xy -6.532 -0.984)
        (xy -6.56 -0.949)
        (xy -6.566 -0.906)
        (xy -6.673 -0.906)
        (xy -6.676 -0.957)
        (xy -6.669 -0.992)
        (xy -6.648 -1.025)
        (xy -6.639 -1.036)
        (xy -6.582 -1.084)
        (xy -6.519 -1.106)
        (xy -6.456 -1.105)
        (xy -6.397 -1.084)
        (xy -6.349 -1.044)
        (xy -6.316 -0.99)
        (xy -6.304 -0.925)
        (xy -6.315 -0.859)
        (xy -6.351 -0.797)
        (xy -6.408 -0.757)
        (xy -6.484 -0.741)
        (xy -6.497 -0.741)
        (xy -6.529 -0.74)
        (xy -6.557 -0.734)
        (xy -6.585 -0.719)
        (xy -6.619 -0.693)
        (xy -6.667 -0.651)
        (xy -6.705 -0.615)
        (xy -6.84 -0.489)
        (xy -7.166 -0.489)
        (xy -7.166 -0.237)
        (xy -6.568 -0.237)
        (xy -6.545 -0.282)
        (xy -6.502 -0.333)
        (xy -6.443 -0.364)
        (xy -6.377 -0.373)
        (xy -6.311 -0.36)
        (xy -6.255 -0.322)
        (xy -6.249 -0.317)
        (xy -6.209 -0.253)
        (xy -6.195 -0.188)
        (xy -6.205 -0.126)
        (xy -6.234 -0.072)
        (xy -6.28 -0.03)
        (xy -6.337 -0.006)
        (xy -6.402 -0.002)
        (xy -6.472 -0.025)
        (xy -6.486 -0.033)
        (xy -6.523 -0.061)
        (xy -6.545 -0.091)
        (xy -6.547 -0.096)
        (xy -6.552 -0.106)
        (xy -6.561 -0.114)
        (xy -6.58 -0.12)
        (xy -6.613 -0.123)
        (xy -6.664 -0.125)
        (xy -6.737 -0.126)
        (xy -6.836 -0.126)
        (xy -6.861 -0.126)
        (xy -7.166 -0.126)
        (xy -7.166 0.11)
        (xy -6.842 0.11)
        (xy -6.581 0.373)
        (xy -6.507 0.366)
        (xy -6.428 0.372)
        (xy -6.367 0.402)
        (xy -6.325 0.457)
        (xy -6.314 0.486)
        (xy -6.304 0.561)
        (xy -6.322 0.626)
        (xy -6.361 0.678)
        (xy -6.422 0.72)
        (xy -6.487 0.736)
        (xy -6.55 0.727)
        (xy -6.605 0.697)
        (xy -6.648 0.648)
        (xy -6.671 0.583)
        (xy -6.672 0.536)
        (xy -6.564 0.536)
        (xy -6.559 0.575)
        (xy -6.544 0.597)
        (xy -6.508 0.625)
        (xy -6.474 0.623)
        (xy -6.441 0.598)
        (xy -6.414 0.56)
        (xy -6.417 0.525)
        (xy -6.44 0.497)
        (xy -6.48 0.476)
        (xy -6.518 0.48)
        (xy -6.549 0.502)
        (xy -6.564 0.536)
        (xy -6.672 0.536)
        (xy -6.673 0.52)
        (xy -6.664 0.445)
        (xy -6.891 0.22)
        (xy -7.166 0.22)
        (xy -7.166 0.593)
        (xy -7.101 0.622)
        (xy -7.033 0.668)
        (xy -6.986 0.732)
        (xy -6.96 0.805)
        (xy -6.956 0.883)
        (xy -6.973 0.959)
        (xy -7.013 1.026)
        (xy -7.074 1.079)
        (xy -7.088 1.087)
        (xy -7.171 1.112)
        (xy -7.258 1.112)
        (xy -7.34 1.087)
        (xy -7.341 1.086)
        (xy -7.406 1.036)
        (xy -7.448 0.97)
        (xy -7.469 0.895)
        (xy -7.468 0.858)
        (xy -7.361 0.858)
        (xy -7.355 0.905)
        (xy -7.331 0.942)
        (xy -7.31 0.962)
        (xy -7.252 0.999)
        (xy -7.195 1.005)
        (xy -7.137 0.979)
        (xy -7.116 0.962)
        (xy -7.08 0.923)
        (xy -7.066 0.883)
        (xy -7.065 0.858)
        (xy -7.079 0.801)
        (xy -7.116 0.751)
        (xy -7.167 0.718)
        (xy -7.213 0.708)
        (xy -7.27 0.722)
        (xy -7.319 0.76)
        (xy -7.352 0.812)
        (xy -7.361 0.858)
        (xy -7.468 0.858)
        (xy -7.468 0.817)
        (xy -7.445 0.742)
        (xy -7.401 0.677)
        (xy -7.336 0.628)
        (xy -7.325 0.622)
        (xy -7.26 0.593)
        (xy -7.26 0.22)
        (xy -7.535 0.22)
        (xy -7.762 0.445)
        (xy -7.753 0.52)
        (xy -7.757 0.595)
        (xy -7.785 0.658)
        (xy -7.83 0.703)
        (xy -7.887 0.73)
        (xy -7.951 0.735)
        (xy -8.015 0.715)
        (xy -8.065 0.678)
        (xy -8.109 0.617)
        (xy -8.123 0.551)
        (xy -8.12 0.532)
        (xy -8.012 0.532)
        (xy -8.009 0.566)
        (xy -7.985 0.598)
        (xy -7.946 0.625)
        (xy -7.912 0.623)
        (xy -7.883 0.599)
        (xy -7.863 0.558)
        (xy -7.868 0.517)
        (xy -7.896 0.486)
        (xy -7.915 0.478)
        (xy -7.961 0.48)
        (xy -7.985 0.496)
        (xy -8.012 0.532)
        (xy -8.12 0.532)
        (xy -8.112 0.486)
        (xy -8.079 0.422)
        (xy -8.025 0.381)
        (xy -7.953 0.365)
        (xy -7.919 0.366)
        (xy -7.845 0.373)
        (xy -7.584 0.11)
        (xy -7.26 0.11)
        (xy -7.26 -0.126)
        (xy -7.566 -0.126)
        (xy -7.672 -0.126)
        (xy -7.75 -0.126)
        (xy -7.805 -0.124)
        (xy -7.841 -0.121)
        (xy -7.863 -0.116)
        (xy -7.875 -0.108)
        (xy -7.881 -0.098)
        (xy -7.883 -0.094)
        (xy -7.908 -0.058)
        (xy -7.954 -0.026)
        (xy -8.009 -0.005)
        (xy -8.045 -0.001)
        (xy -8.117 -0.014)
        (xy -8.174 -0.049)
        (xy -8.213 -0.102)
        (xy -8.23 -0.164)
        (xy -8.228 -0.186)
        (xy -8.124 -0.186)
        (xy -8.12 -0.163)
        (xy -8.104 -0.143)
        (xy -8.063 -0.115)
        (xy -8.021 -0.117)
        (xy -7.994 -0.135)
        (xy -7.971 -0.176)
        (xy -7.976 -0.202)
        (xy -6.455 -0.202)
        (xy -6.449 -0.158)
        (xy -6.432 -0.135)
        (xy -6.392 -0.113)
        (xy -6.35 -0.121)
        (xy -6.322 -0.143)
        (xy -6.303 -0.169)
        (xy -6.304 -0.193)
        (xy -6.316 -0.218)
        (xy -6.35 -0.254)
        (xy -6.39 -0.265)
        (xy -6.429 -0.247)
        (xy -6.432 -0.244)
        (xy -6.455 -0.202)
        (xy -7.976 -0.202)
        (xy -7.979 -0.218)
        (xy -7.999 -0.244)
        (xy -8.04 -0.265)
        (xy -8.078 -0.255)
        (xy -8.11 -0.218)
        (xy -8.124 -0.186)
        (xy -8.228 -0.186)
        (xy -8.224 -0.232)
        (xy -8.192 -0.297)
        (xy -8.177 -0.317)
        (xy -8.121 -0.358)
        (xy -8.055 -0.374)
        (xy -7.988 -0.365)
        (xy -7.927 -0.333)
        (xy -7.885 -0.284)
        (xy -7.857 -0.237)
        (xy -7.26 -0.237)
        (xy -7.26 -0.489)
        (xy -7.586 -0.489)
        (xy -7.721 -0.615)
        (xy -7.779 -0.669)
        (xy -7.821 -0.704)
        (xy -7.852 -0.726)
        (xy -7.879 -0.737)
        (xy -7.908 -0.74)
        (xy -7.934 -0.741)
        (xy -8.011 -0.752)
        (xy -8.068 -0.787)
        (xy -8.105 -0.846)
        (xy -8.112 -0.866)
        (xy -8.119 -0.923)
        (xy -8.016 -0.923)
        (xy -8.003 -0.887)
        (xy -7.969 -0.862)
        (xy -7.928 -0.852)
        (xy -7.888 -0.861)
        (xy -7.878 -0.87)
        (xy -7.86 -0.907)
        (xy -7.866 -0.949)
        (xy -7.894 -0.984)
        (xy -7.924 -1.002)
        (xy -7.941 -1.008)
        (xy -7.964 -0.997)
        (xy -7.991 -0.969)
        (xy -8.011 -0.939)
        (xy -8.016 -0.923)
        (xy -8.119 -0.923)
        (xy -8.121 -0.94)
        (xy -8.105 -1.004)
        (xy -8.069 -1.055)
        (xy -8.018 -1.091)
        (xy -7.958 -1.108)
        (xy -7.894 -1.104)
        (xy -7.831 -1.076)
        (xy -7.787 -1.036)
        (xy -7.762 -1.001)
        (xy -7.751 -0.968)
        (xy -7.751 -0.923)
        (xy -7.753 -0.905)
        (xy -7.762 -0.824)
        (xy -7.648 -0.711)
        (xy -7.535 -0.599)
        (xy -7.26 -0.599)
        (xy -7.26 -0.971)
        (xy -7.323 -0.998)
        (xy -7.396 -1.046)
        (xy -7.446 -1.114)
        (xy -7.465 -1.166)
        (xy -7.472 -1.24)
        (xy -7.365 -1.24)
        (xy -7.359 -1.204)
        (xy -7.347 -1.177)
        (xy -7.307 -1.123)
        (xy -7.254 -1.093)
        (xy -7.194 -1.09)
        (xy -7.134 -1.116)
        (xy -7.127 -1.121)
        (xy -7.081 -1.171)
        (xy -7.065 -1.225)
        (xy -7.078 -1.283)
        (xy -7.116 -1.342)
        (xy -7.166 -1.375)
        (xy -7.222 -1.384)
        (xy -7.278 -1.368)
        (xy -7.326 -1.326)
        (xy -7.354 -1.278)
        (xy -7.365 -1.24)
        (xy -7.472 -1.24)
        (xy -7.474 -1.25)
        (xy -7.455 -1.328)
        (xy -7.416 -1.396)
        (xy -7.358 -1.449)
        (xy -7.288 -1.484)
        (xy -7.21 -1.495)
        (xy -7.128 -1.48)
      )

      (stroke (width 0.00186) (type solid)) (fill solid) (layer "F.Cu"))
    (fp_poly
      (pts
        (xy 5.212 0.944)
        (xy 4.834 0.944)
        (xy 4.834 -1.292)
        (xy 5.212 -1.292)
        (xy 5.212 0.944)
      )

      (stroke (width 0.00186) (type solid)) (fill solid) (layer "F.Mask"))
    (fp_poly
      (pts
        (xy 8.164 -1.321)
        (xy 8.193 -1.317)
        (xy 8.204 -1.31)
        (xy 8.204 -1.308)
        (xy 8.2 -1.285)
        (xy 8.188 -1.24)
        (xy 8.171 -1.181)
        (xy 8.163 -1.156)
        (xy 8.142 -1.092)
        (xy 8.126 -1.053)
        (xy 8.112 -1.034)
        (xy 8.097 -1.031)
        (xy 8.094 -1.032)
        (xy 7.996 -1.053)
        (xy 7.886 -1.06)
        (xy 7.778 -1.053)
        (xy 7.683 -1.032)
        (xy 7.665 -1.026)
        (xy 7.622 -1.009)
        (xy 7.622 0.944)
        (xy 7.244 0.944)
        (xy 7.244 -1.178)
        (xy 7.358 -1.219)
        (xy 7.457 -1.253)
        (xy 7.548 -1.277)
        (xy 7.639 -1.295)
        (xy 7.738 -1.307)
        (xy 7.856 -1.315)
        (xy 7.94 -1.319)
        (xy 8.042 -1.322)
        (xy 8.115 -1.322)
        (xy 8.164 -1.321)
      )

      (stroke (width 0.00186) (type solid)) (fill solid) (layer "F.Mask"))
    (fp_poly
      (pts
        (xy 0.795 -1.891)
        (xy 0.798 -1.849)
        (xy 0.8 -1.786)
        (xy 0.802 -1.705)
        (xy 0.803 -1.612)
        (xy 0.803 -1.599)
        (xy 0.803 -1.292)
        (xy 1.181 -1.292)
        (xy 1.181 -1.04)
        (xy 0.803 -1.04)
        (xy 0.803 0.498)
        (xy 0.838 0.566)
        (xy 0.885 0.631)
        (xy 0.944 0.671)
        (xy 1.021 0.688)
        (xy 1.082 0.689)
        (xy 1.181 0.685)
        (xy 1.181 0.806)
        (xy 1.178 0.88)
        (xy 1.17 0.926)
        (xy 1.161 0.939)
        (xy 1.138 0.945)
        (xy 1.09 0.95)
        (xy 1.028 0.954)
        (xy 0.984 0.956)
        (xy 0.897 0.957)
        (xy 0.832 0.953)
        (xy 0.778 0.942)
        (xy 0.743 0.931)
        (xy 0.647 0.886)
        (xy 0.571 0.823)
        (xy 0.508 0.737)
        (xy 0.488 0.701)
        (xy 0.433 0.593)
        (xy 0.428 -0.223)
        (xy 0.424 -1.04)
        (xy 0.173 -1.04)
        (xy 0.173 -1.292)
        (xy 0.425 -1.292)
        (xy 0.425 -1.795)
        (xy 0.603 -1.85)
        (xy 0.673 -1.872)
        (xy 0.733 -1.89)
        (xy 0.774 -1.902)
        (xy 0.792 -1.906)
        (xy 0.795 -1.891)
      )

      (stroke (width 0.00186) (type solid)) (fill solid) (layer "F.Mask"))
    (fp_poly
      (pts
        (xy -0.82 -1.315)
        (xy -0.737 -1.312)
        (xy -0.672 -1.308)
        (xy -0.621 -1.301)
        (xy -0.577 -1.291)
        (xy -0.56 -1.286)
        (xy -0.417 -1.232)
        (xy -0.302 -1.164)
        (xy -0.212 -1.082)
        (xy -0.154 -0.996)
        (xy -0.135 -0.961)
        (xy -0.119 -0.927)
        (xy -0.105 -0.893)
        (xy -0.094 -0.855)
        (xy -0.085 -0.811)
        (xy -0.078 -0.758)
        (xy -0.073 -0.693)
        (xy -0.069 -0.612)
        (xy -0.067 -0.515)
        (xy -0.065 -0.397)
        (xy -0.064 -0.256)
        (xy -0.064 -0.088)
        (xy -0.063 0.105)
        (xy -0.063 0.944)
        (xy -0.441 0.944)
        (xy -0.441 0.113)
        (xy -0.442 -0.083)
        (xy -0.442 -0.25)
        (xy -0.443 -0.391)
        (xy -0.445 -0.508)
        (xy -0.448 -0.604)
        (xy -0.452 -0.682)
        (xy -0.457 -0.744)
        (xy -0.465 -0.794)
        (xy -0.474 -0.833)
        (xy -0.486 -0.864)
        (xy -0.501 -0.89)
        (xy -0.518 -0.913)
        (xy -0.538 -0.937)
        (xy -0.539 -0.939)
        (xy -0.604 -0.997)
        (xy -0.684 -1.039)
        (xy -0.784 -1.066)
        (xy -0.822 -1.072)
        (xy -0.927 -1.078)
        (xy -1.044 -1.073)
        (xy -1.158 -1.056)
        (xy -1.24 -1.034)
        (xy -1.3 -1.013)
        (xy -1.304 -0.034)
        (xy -1.308 0.944)
        (xy -1.686 0.944)
        (xy -1.686 -1.178)
        (xy -1.54 -1.225)
        (xy -1.44 -1.257)
        (xy -1.354 -1.28)
        (xy -1.276 -1.297)
        (xy -1.195 -1.307)
        (xy -1.105 -1.313)
        (xy -0.995 -1.315)
        (xy -0.93 -1.315)
        (xy -0.82 -1.315)
      )

      (stroke (width 0.00186) (type solid)) (fill solid) (layer "F.Mask"))
    (fp_poly
      (pts
        (xy 3.757 -1.312)
        (xy 3.91 -1.278)
        (xy 4.043 -1.223)
        (xy 4.153 -1.146)
        (xy 4.24 -1.047)
        (xy 4.282 -0.977)
        (xy 4.299 -0.943)
        (xy 4.313 -0.91)
        (xy 4.325 -0.876)
        (xy 4.335 -0.837)
        (xy 4.343 -0.791)
        (xy 4.349 -0.734)
        (xy 4.353 -0.665)
        (xy 4.357 -0.581)
        (xy 4.359 -0.478)
        (xy 4.361 -0.354)
        (xy 4.361 -0.206)
        (xy 4.362 -0.031)
        (xy 4.362 0.111)
        (xy 4.362 0.944)
        (xy 3.985 0.944)
        (xy 3.98 0.074)
        (xy 3.976 -0.796)
        (xy 3.93 -0.879)
        (xy 3.867 -0.961)
        (xy 3.786 -1.022)
        (xy 3.691 -1.062)
        (xy 3.586 -1.079)
        (xy 3.476 -1.074)
        (xy 3.366 -1.045)
        (xy 3.26 -0.994)
        (xy 3.185 -0.938)
        (xy 3.118 -0.88)
        (xy 3.118 0.944)
        (xy 2.74 0.944)
        (xy 2.74 0.092)
        (xy 2.739 -0.122)
        (xy 2.739 -0.305)
        (xy 2.737 -0.459)
        (xy 2.735 -0.585)
        (xy 2.732 -0.683)
        (xy 2.729 -0.755)
        (xy 2.725 -0.802)
        (xy 2.722 -0.821)
        (xy 2.679 -0.91)
        (xy 2.613 -0.981)
        (xy 2.523 -1.034)
        (xy 2.413 -1.067)
        (xy 2.284 -1.079)
        (xy 2.154 -1.073)
        (xy 2.082 -1.064)
        (xy 2.031 -1.056)
        (xy 1.989 -1.046)
        (xy 1.944 -1.031)
        (xy 1.917 -1.021)
        (xy 1.874 -1.005)
        (xy 1.874 0.944)
        (xy 1.511 0.944)
        (xy 1.511 -1.18)
        (xy 1.661 -1.228)
        (xy 1.83 -1.276)
        (xy 1.988 -1.306)
        (xy 2.148 -1.319)
        (xy 2.314 -1.319)
        (xy 2.448 -1.311)
        (xy 2.557 -1.297)
        (xy 2.649 -1.272)
        (xy 2.732 -1.237)
        (xy 2.811 -1.189)
        (xy 2.843 -1.165)
        (xy 2.947 -1.087)
        (xy 3.012 -1.14)
        (xy 3.14 -1.224)
        (xy 3.283 -1.283)
        (xy 3.443 -1.315)
        (xy 3.582 -1.323)
        (xy 3.757 -1.312)
      )

      (stroke (width 0.00186) (type solid)) (fill solid) (layer "F.Mask"))
    (fp_poly
      (pts
        (xy 9.278 -1.313)
        (xy 9.419 -1.281)
        (xy 9.543 -1.225)
        (xy 9.656 -1.146)
        (xy 9.708 -1.097)
        (xy 9.808 -0.975)
        (xy 9.887 -0.831)
        (xy 9.945 -0.666)
        (xy 9.984 -0.476)
        (xy 9.998 -0.354)
        (xy 10.005 -0.134)
        (xy 9.992 0.072)
        (xy 9.96 0.262)
        (xy 9.908 0.434)
        (xy 9.837 0.585)
        (xy 9.749 0.714)
        (xy 9.643 0.819)
        (xy 9.578 0.867)
        (xy 9.475 0.918)
        (xy 9.352 0.956)
        (xy 9.219 0.98)
        (xy 9.087 0.986)
        (xy 8.966 0.975)
        (xy 8.81 0.933)
        (xy 8.673 0.864)
        (xy 8.553 0.771)
        (xy 8.452 0.653)
        (xy 8.371 0.511)
        (xy 8.31 0.346)
        (xy 8.277 0.202)
        (xy 8.249 -0.011)
        (xy 8.243 -0.182)
        (xy 8.619 -0.182)
        (xy 8.626 -0.007)
        (xy 8.647 0.163)
        (xy 8.682 0.318)
        (xy 8.73 0.449)
        (xy 8.792 0.552)
        (xy 8.87 0.633)
        (xy 8.961 0.69)
        (xy 9.06 0.721)
        (xy 9.164 0.724)
        (xy 9.268 0.699)
        (xy 9.303 0.683)
        (xy 9.391 0.625)
        (xy 9.465 0.546)
        (xy 9.524 0.443)
        (xy 9.569 0.315)
        (xy 9.601 0.162)
        (xy 9.62 0)
        (xy 9.628 -0.198)
        (xy 9.62 -0.382)
        (xy 9.597 -0.55)
        (xy 9.558 -0.698)
        (xy 9.505 -0.825)
        (xy 9.439 -0.927)
        (xy 9.397 -0.971)
        (xy 9.307 -1.035)
        (xy 9.21 -1.071)
        (xy 9.109 -1.079)
        (xy 9.009 -1.062)
        (xy 8.915 -1.019)
        (xy 8.831 -0.953)
        (xy 8.76 -0.863)
        (xy 8.733 -0.813)
        (xy 8.684 -0.68)
        (xy 8.648 -0.526)
        (xy 8.627 -0.358)
        (xy 8.619 -0.182)
        (xy 8.243 -0.182)
        (xy 8.242 -0.218)
        (xy 8.255 -0.417)
        (xy 8.288 -0.602)
        (xy 8.339 -0.772)
        (xy 8.41 -0.923)
        (xy 8.498 -1.051)
        (xy 8.524 -1.081)
        (xy 8.637 -1.182)
        (xy 8.765 -1.255)
        (xy 8.908 -1.302)
        (xy 9.068 -1.322)
        (xy 9.117 -1.323)
        (xy 9.278 -1.313)
      )

      (stroke (width 0.00186) (type solid)) (fill solid) (layer "F.Mask"))
    (fp_poly
      (pts
        (xy 6.48 -1.32)
        (xy 6.584 -1.31)
        (xy 6.642 -1.3)
        (xy 6.701 -1.282)
        (xy 6.765 -1.259)
        (xy 6.825 -1.233)
        (xy 6.873 -1.209)
        (xy 6.9 -1.189)
        (xy 6.902 -1.186)
        (xy 6.901 -1.166)
        (xy 6.889 -1.128)
        (xy 6.872 -1.079)
        (xy 6.852 -1.03)
        (xy 6.833 -0.989)
        (xy 6.818 -0.966)
        (xy 6.815 -0.963)
        (xy 6.795 -0.969)
        (xy 6.757 -0.985)
        (xy 6.717 -1.002)
        (xy 6.597 -1.044)
        (xy 6.478 -1.06)
        (xy 6.365 -1.05)
        (xy 6.267 -1.016)
        (xy 6.184 -0.957)
        (xy 6.109 -0.87)
        (xy 6.042 -0.76)
        (xy 5.988 -0.629)
        (xy 5.964 -0.554)
        (xy 5.946 -0.461)
        (xy 5.934 -0.347)
        (xy 5.929 -0.22)
        (xy 5.931 -0.091)
        (xy 5.938 0.032)
        (xy 5.953 0.138)
        (xy 5.965 0.191)
        (xy 6.018 0.347)
        (xy 6.085 0.476)
        (xy 6.166 0.576)
        (xy 6.262 0.649)
        (xy 6.269 0.653)
        (xy 6.318 0.678)
        (xy 6.36 0.692)
        (xy 6.409 0.698)
        (xy 6.476 0.7)
        (xy 6.48 0.7)
        (xy 6.551 0.697)
        (xy 6.613 0.686)
        (xy 6.676 0.665)
        (xy 6.75 0.631)
        (xy 6.805 0.602)
        (xy 6.811 0.606)
        (xy 6.823 0.627)
        (xy 6.842 0.667)
        (xy 6.868 0.73)
        (xy 6.904 0.819)
        (xy 6.907 0.827)
        (xy 6.898 0.844)
        (xy 6.866 0.868)
        (xy 6.818 0.895)
        (xy 6.759 0.922)
        (xy 6.697 0.945)
        (xy 6.68 0.95)
        (xy 6.596 0.968)
        (xy 6.494 0.98)
        (xy 6.388 0.984)
        (xy 6.292 0.98)
        (xy 6.251 0.975)
        (xy 6.192 0.96)
        (xy 6.121 0.935)
        (xy 6.055 0.906)
        (xy 5.924 0.825)
        (xy 5.811 0.718)
        (xy 5.717 0.586)
        (xy 5.641 0.431)
        (xy 5.585 0.252)
        (xy 5.566 0.164)
        (xy 5.552 0.061)
        (xy 5.545 -0.061)
        (xy 5.544 -0.193)
        (xy 5.549 -0.327)
        (xy 5.56 -0.453)
        (xy 5.576 -0.563)
        (xy 5.589 -0.623)
        (xy 5.65 -0.797)
        (xy 5.731 -0.949)
        (xy 5.831 -1.077)
        (xy 5.948 -1.181)
        (xy 6.081 -1.259)
        (xy 6.187 -1.298)
        (xy 6.27 -1.314)
        (xy 6.372 -1.322)
        (xy 6.48 -1.32)
      )

      (stroke (width 0.00186) (type solid)) (fill solid) (layer "F.Mask"))
    (fp_poly
      (pts
        (xy -2.763 -1.313)
        (xy -2.663 -1.294)
        (xy -2.55 -1.259)
        (xy -2.459 -1.216)
        (xy -2.38 -1.16)
        (xy -2.341 -1.124)
        (xy -2.284 -1.053)
        (xy -2.232 -0.961)
        (xy -2.192 -0.861)
        (xy -2.174 -0.79)
        (xy -2.17 -0.754)
        (xy -2.167 -0.69)
        (xy -2.164 -0.599)
        (xy -2.162 -0.485)
        (xy -2.16 -0.35)
        (xy -2.159 -0.196)
        (xy -2.158 -0.027)
        (xy -2.158 0.064)
        (xy -2.158 0.833)
        (xy -2.232 0.865)
        (xy -2.364 0.913)
        (xy -2.517 0.949)
        (xy -2.682 0.974)
        (xy -2.85 0.986)
        (xy -3.011 0.983)
        (xy -3.097 0.975)
        (xy -3.264 0.942)
        (xy -3.407 0.889)
        (xy -3.525 0.817)
        (xy -3.618 0.725)
        (xy -3.686 0.616)
        (xy -3.729 0.487)
        (xy -3.746 0.341)
        (xy -3.746 0.268)
        (xy -3.744 0.254)
        (xy -3.383 0.254)
        (xy -3.38 0.384)
        (xy -3.352 0.497)
        (xy -3.298 0.591)
        (xy -3.221 0.665)
        (xy -3.12 0.719)
        (xy -3.072 0.735)
        (xy -3.011 0.745)
        (xy -2.928 0.75)
        (xy -2.835 0.75)
        (xy -2.74 0.744)
        (xy -2.655 0.734)
        (xy -2.589 0.72)
        (xy -2.579 0.716)
        (xy -2.504 0.689)
        (xy -2.504 -0.302)
        (xy -2.595 -0.291)
        (xy -2.653 -0.282)
        (xy -2.728 -0.267)
        (xy -2.806 -0.25)
        (xy -2.831 -0.244)
        (xy -2.992 -0.194)
        (xy -3.125 -0.133)
        (xy -3.229 -0.06)
        (xy -3.306 0.026)
        (xy -3.357 0.125)
        (xy -3.381 0.238)
        (xy -3.383 0.254)
        (xy -3.744 0.254)
        (xy -3.725 0.126)
        (xy -3.678 0)
        (xy -3.602 -0.112)
        (xy -3.559 -0.158)
        (xy -3.465 -0.233)
        (xy -3.343 -0.303)
        (xy -3.198 -0.365)
        (xy -3.034 -0.417)
        (xy -2.856 -0.46)
        (xy -2.666 -0.49)
        (xy -2.663 -0.49)
        (xy -2.5 -0.51)
        (xy -2.51 -0.644)
        (xy -2.528 -0.77)
        (xy -2.564 -0.871)
        (xy -2.62 -0.949)
        (xy -2.697 -1.007)
        (xy -2.797 -1.045)
        (xy -2.845 -1.056)
        (xy -2.975 -1.067)
        (xy -3.12 -1.056)
        (xy -3.272 -1.024)
        (xy -3.426 -0.972)
        (xy -3.439 -0.967)
        (xy -3.488 -0.947)
        (xy -3.523 -0.936)
        (xy -3.537 -0.934)
        (xy -3.545 -0.95)
        (xy -3.56 -0.987)
        (xy -3.579 -1.035)
        (xy -3.598 -1.086)
        (xy -3.613 -1.129)
        (xy -3.622 -1.155)
        (xy -3.623 -1.159)
        (xy -3.609 -1.169)
        (xy -3.575 -1.188)
        (xy -3.537 -1.206)
        (xy -3.395 -1.257)
        (xy -3.239 -1.294)
        (xy -3.075 -1.316)
        (xy -2.914 -1.323)
        (xy -2.763 -1.313)
      )

      (stroke (width 0.00186) (type solid)) (fill solid) (layer "F.Mask"))
    (fp_poly
      (pts
        (xy -7.153 -3.366)
        (xy -7.087 -3.351)
        (xy -7.086 -3.351)
        (xy -7.066 -3.34)
        (xy -7.021 -3.315)
        (xy -6.953 -3.277)
        (xy -6.865 -3.227)
        (xy -6.759 -3.167)
        (xy -6.639 -3.099)
        (xy -6.505 -3.022)
        (xy -6.361 -2.94)
        (xy -6.209 -2.853)
        (xy -6.052 -2.762)
        (xy -5.891 -2.67)
        (xy -5.729 -2.577)
        (xy -5.569 -2.485)
        (xy -5.413 -2.395)
        (xy -5.264 -2.309)
        (xy -5.123 -2.227)
        (xy -4.994 -2.152)
        (xy -4.878 -2.085)
        (xy -4.778 -2.027)
        (xy -4.697 -1.979)
        (xy -4.636 -1.943)
        (xy -4.599 -1.921)
        (xy -4.595 -1.918)
        (xy -4.528 -1.863)
        (xy -4.476 -1.798)
        (xy -4.434 -1.725)
        (xy -4.429 -0.224)
        (xy -4.429 0.063)
        (xy -4.428 0.323)
        (xy -4.429 0.553)
        (xy -4.429 0.755)
        (xy -4.43 0.928)
        (xy -4.432 1.071)
        (xy -4.434 1.184)
        (xy -4.436 1.266)
        (xy -4.439 1.318)
        (xy -4.441 1.337)
        (xy -4.448 1.36)
        (xy -4.454 1.382)
        (xy -4.463 1.403)
        (xy -4.476 1.423)
        (xy -4.494 1.445)
        (xy -4.519 1.47)
        (xy -4.552 1.497)
        (xy -4.596 1.529)
        (xy -4.652 1.567)
        (xy -4.721 1.611)
        (xy -4.805 1.663)
        (xy -4.906 1.723)
        (xy -5.025 1.794)
        (xy -5.165 1.875)
        (xy -5.326 1.969)
        (xy -5.511 2.076)
        (xy -5.72 2.197)
        (xy -5.813 2.251)
        (xy -7.079 2.982)
        (xy -7.197 2.988)
        (xy -7.315 2.994)
        (xy -7.78 2.727)
        (xy -8.064 2.563)
        (xy -8.323 2.415)
        (xy -8.557 2.28)
        (xy -8.767 2.159)
        (xy -8.955 2.051)
        (xy -9.122 1.954)
        (xy -9.27 1.868)
        (xy -9.399 1.792)
        (xy -9.51 1.726)
        (xy -9.606 1.669)
        (xy -9.688 1.619)
        (xy -9.756 1.576)
        (xy -9.812 1.539)
        (xy -9.857 1.507)
        (xy -9.893 1.481)
        (xy -9.92 1.458)
        (xy -9.94 1.437)
        (xy -9.955 1.42)
        (xy -9.965 1.403)
        (xy -9.972 1.387)
        (xy -9.977 1.371)
        (xy -9.981 1.354)
        (xy -9.985 1.337)
        (xy -9.988 1.309)
        (xy -9.991 1.25)
        (xy -9.993 1.161)
        (xy -9.995 1.041)
        (xy -9.996 0.891)
        (xy -9.997 0.712)
        (xy -9.998 0.503)
        (xy -9.998 0.266)
        (xy -9.997 0)
        (xy -9.997 -0.189)
        (xy -9.024 -0.189)
        (xy -9.024 0.015)
        (xy -9.024 0.191)
        (xy -9.023 0.34)
        (xy -9.022 0.464)
        (xy -9.021 0.567)
        (xy -9.018 0.65)
        (xy -9.014 0.717)
        (xy -9.01 0.768)
        (xy -9.003 0.808)
        (xy -8.995 0.837)
        (xy -8.986 0.859)
        (xy -8.974 0.876)
        (xy -8.961 0.891)
        (xy -8.945 0.905)
        (xy -8.943 0.906)
        (xy -8.922 0.921)
        (xy -8.877 0.949)
        (xy -8.81 0.989)
        (xy -8.725 1.039)
        (xy -8.625 1.098)
        (xy -8.512 1.164)
        (xy -8.389 1.235)
        (xy -8.26 1.31)
        (xy -8.128 1.386)
        (xy -7.995 1.463)
        (xy -7.864 1.538)
        (xy -7.739 1.609)
        (xy -7.622 1.676)
        (xy -7.517 1.735)
        (xy -7.425 1.787)
        (xy -7.351 1.828)
        (xy -7.297 1.857)
        (xy -7.266 1.872)
        (xy -7.261 1.874)
        (xy -7.222 1.885)
        (xy -7.195 1.886)
        (xy -7.163 1.875)
        (xy -7.144 1.867)
        (xy -7.117 1.854)
        (xy -7.067 1.827)
        (xy -6.997 1.788)
        (xy -6.909 1.738)
        (xy -6.805 1.679)
        (xy -6.691 1.614)
        (xy -6.567 1.543)
        (xy -6.438 1.469)
        (xy -6.306 1.392)
        (xy -6.174 1.316)
        (xy -6.045 1.241)
        (xy -5.922 1.17)
        (xy -5.809 1.103)
        (xy -5.708 1.044)
        (xy -5.622 0.992)
        (xy -5.553 0.952)
        (xy -5.507 0.923)
        (xy -5.484 0.907)
        (xy -5.483 0.907)
        (xy -5.467 0.892)
        (xy -5.453 0.878)
        (xy -5.441 0.861)
        (xy -5.431 0.839)
        (xy -5.423 0.81)
        (xy -5.417 0.772)
        (xy -5.412 0.721)
        (xy -5.408 0.656)
        (xy -5.406 0.574)
        (xy -5.404 0.473)
        (xy -5.403 0.35)
        (xy -5.402 0.203)
        (xy -5.402 0.03)
        (xy -5.402 -0.172)
        (xy -5.402 -0.189)
        (xy -5.402 -0.395)
        (xy -5.402 -0.572)
        (xy -5.403 -0.721)
        (xy -5.404 -0.847)
        (xy -5.406 -0.95)
        (xy -5.408 -1.034)
        (xy -5.412 -1.101)
        (xy -5.418 -1.153)
        (xy -5.425 -1.193)
        (xy -5.434 -1.223)
        (xy -5.445 -1.245)
        (xy -5.458 -1.262)
        (xy -5.473 -1.276)
        (xy -5.491 -1.29)
        (xy -5.499 -1.295)
        (xy -5.522 -1.31)
        (xy -5.57 -1.339)
        (xy -5.64 -1.381)
        (xy -5.729 -1.433)
        (xy -5.835 -1.496)
        (xy -5.956 -1.566)
        (xy -6.088 -1.643)
        (xy -6.229 -1.725)
        (xy -6.348 -1.793)
        (xy -6.519 -1.891)
        (xy -6.664 -1.974)
        (xy -6.786 -2.044)
        (xy -6.888 -2.101)
        (xy -6.971 -2.147)
        (xy -7.038 -2.183)
        (xy -7.091 -2.21)
        (xy -7.132 -2.229)
        (xy -7.163 -2.242)
        (xy -7.187 -2.249)
        (xy -7.205 -2.252)
        (xy -7.211 -2.252)
        (xy -7.228 -2.251)
        (xy -7.249 -2.246)
        (xy -7.276 -2.236)
        (xy -7.312 -2.219)
        (xy -7.359 -2.196)
        (xy -7.419 -2.165)
        (xy -7.495 -2.123)
        (xy -7.587 -2.072)
        (xy -7.699 -2.008)
        (xy -7.832 -1.932)
        (xy -7.99 -1.842)
        (xy -8.1 -1.778)
        (xy -8.248 -1.693)
        (xy -8.388 -1.611)
        (xy -8.519 -1.535)
        (xy -8.637 -1.466)
        (xy -8.739 -1.406)
        (xy -8.825 -1.355)
        (xy -8.89 -1.316)
        (xy -8.933 -1.29)
        (xy -8.951 -1.278)
        (xy -8.966 -1.265)
        (xy -8.978 -1.251)
        (xy -8.989 -1.234)
        (xy -8.998 -1.212)
        (xy -9.005 -1.182)
        (xy -9.011 -1.141)
        (xy -9.015 -1.087)
        (xy -9.018 -1.019)
        (xy -9.021 -0.933)
        (xy -9.022 -0.827)
        (xy -9.023 -0.699)
        (xy -9.024 -0.546)
        (xy -9.024 -0.366)
        (xy -9.024 -0.189)
        (xy -9.997 -0.189)
        (xy -9.997 -0.224)
        (xy -9.996 -0.479)
        (xy -9.996 -0.705)
        (xy -9.995 -0.903)
        (xy -9.994 -1.075)
        (xy -9.993 -1.223)
        (xy -9.992 -1.35)
        (xy -9.99 -1.456)
        (xy -9.987 -1.545)
        (xy -9.984 -1.617)
        (xy -9.98 -1.675)
        (xy -9.974 -1.721)
        (xy -9.968 -1.757)
        (xy -9.961 -1.784)
        (xy -9.952 -1.805)
        (xy -9.941 -1.821)
        (xy -9.929 -1.834)
        (xy -9.915 -1.847)
        (xy -9.9 -1.86)
        (xy -9.893 -1.866)
        (xy -9.873 -1.88)
        (xy -9.828 -1.909)
        (xy -9.759 -1.951)
        (xy -9.669 -2.005)
        (xy -9.56 -2.07)
        (xy -9.433 -2.145)
        (xy -9.291 -2.228)
        (xy -9.136 -2.319)
        (xy -8.969 -2.416)
        (xy -8.793 -2.518)
        (xy -8.61 -2.624)
        (xy -8.59 -2.635)
        (xy -8.377 -2.759)
        (xy -8.189 -2.867)
        (xy -8.024 -2.962)
        (xy -7.882 -3.044)
        (xy -7.759 -3.114)
        (xy -7.656 -3.173)
        (xy -7.568 -3.221)
        (xy -7.496 -3.261)
        (xy -7.437 -3.293)
        (xy -7.389 -3.317)
        (xy -7.351 -3.336)
        (xy -7.321 -3.349)
        (xy -7.296 -3.357)
        (xy -7.276 -3.363)
        (xy -7.259 -3.366)
        (xy -7.242 -3.367)
        (xy -7.237 -3.368)
        (xy -7.153 -3.366)
      )

      (stroke (width 0.00186) (type solid)) (fill solid) (layer "F.Mask"))
    (fp_poly
      (pts
        (xy -7.128 -1.48)
        (xy -7.114 -1.475)
        (xy -7.042 -1.428)
        (xy -6.989 -1.361)
        (xy -6.96 -1.281)
        (xy -6.957 -1.196)
        (xy -6.961 -1.175)
        (xy -6.992 -1.094)
        (xy -7.046 -1.034)
        (xy -7.101 -1.001)
        (xy -7.166 -0.969)
        (xy -7.166 -0.599)
        (xy -6.891 -0.599)
        (xy -6.778 -0.711)
        (xy -6.665 -0.824)
        (xy -6.673 -0.905)
        (xy -6.673 -0.906)
        (xy -6.566 -0.906)
        (xy -6.549 -0.87)
        (xy -6.512 -0.853)
        (xy -6.467 -0.856)
        (xy -6.435 -0.876)
        (xy -6.412 -0.913)
        (xy -6.42 -0.95)
        (xy -6.441 -0.977)
        (xy -6.471 -1.002)
        (xy -6.496 -1.005)
        (xy -6.53 -0.986)
        (xy -6.532 -0.984)
        (xy -6.56 -0.949)
        (xy -6.566 -0.906)
        (xy -6.673 -0.906)
        (xy -6.676 -0.957)
        (xy -6.669 -0.992)
        (xy -6.648 -1.025)
        (xy -6.639 -1.036)
        (xy -6.582 -1.084)
        (xy -6.519 -1.106)
        (xy -6.456 -1.105)
        (xy -6.397 -1.084)
        (xy -6.349 -1.044)
        (xy -6.316 -0.99)
        (xy -6.304 -0.925)
        (xy -6.315 -0.859)
        (xy -6.351 -0.797)
        (xy -6.408 -0.757)
        (xy -6.484 -0.741)
        (xy -6.497 -0.741)
        (xy -6.529 -0.74)
        (xy -6.557 -0.734)
        (xy -6.585 -0.719)
        (xy -6.619 -0.693)
        (xy -6.667 -0.651)
        (xy -6.705 -0.615)
        (xy -6.84 -0.489)
        (xy -7.166 -0.489)
        (xy -7.166 -0.237)
        (xy -6.568 -0.237)
        (xy -6.545 -0.282)
        (xy -6.502 -0.333)
        (xy -6.443 -0.364)
        (xy -6.377 -0.373)
        (xy -6.311 -0.36)
        (xy -6.255 -0.322)
        (xy -6.249 -0.317)
        (xy -6.209 -0.253)
        (xy -6.195 -0.188)
        (xy -6.205 -0.126)
        (xy -6.234 -0.072)
        (xy -6.28 -0.03)
        (xy -6.337 -0.006)
        (xy -6.402 -0.002)
        (xy -6.472 -0.025)
        (xy -6.486 -0.033)
        (xy -6.523 -0.061)
        (xy -6.545 -0.091)
        (xy -6.547 -0.096)
        (xy -6.552 -0.106)
        (xy -6.561 -0.114)
        (xy -6.58 -0.12)
        (xy -6.613 -0.123)
        (xy -6.664 -0.125)
        (xy -6.737 -0.126)
        (xy -6.836 -0.126)
        (xy -6.861 -0.126)
        (xy -7.166 -0.126)
        (xy -7.166 0.11)
        (xy -6.842 0.11)
        (xy -6.581 0.373)
        (xy -6.507 0.366)
        (xy -6.428 0.372)
        (xy -6.367 0.402)
        (xy -6.325 0.457)
        (xy -6.314 0.486)
        (xy -6.304 0.561)
        (xy -6.322 0.626)
        (xy -6.361 0.678)
        (xy -6.422 0.72)
        (xy -6.487 0.736)
        (xy -6.55 0.727)
        (xy -6.605 0.697)
        (xy -6.648 0.648)
        (xy -6.671 0.583)
        (xy -6.672 0.536)
        (xy -6.564 0.536)
        (xy -6.559 0.575)
        (xy -6.544 0.597)
        (xy -6.508 0.625)
        (xy -6.474 0.623)
        (xy -6.441 0.598)
        (xy -6.414 0.56)
        (xy -6.417 0.525)
        (xy -6.44 0.497)
        (xy -6.48 0.476)
        (xy -6.518 0.48)
        (xy -6.549 0.502)
        (xy -6.564 0.536)
        (xy -6.672 0.536)
        (xy -6.673 0.52)
        (xy -6.664 0.445)
        (xy -6.891 0.22)
        (xy -7.166 0.22)
        (xy -7.166 0.593)
        (xy -7.101 0.622)
        (xy -7.033 0.668)
        (xy -6.986 0.732)
        (xy -6.96 0.805)
        (xy -6.956 0.883)
        (xy -6.973 0.959)
        (xy -7.013 1.026)
        (xy -7.074 1.079)
        (xy -7.088 1.087)
        (xy -7.171 1.112)
        (xy -7.258 1.112)
        (xy -7.34 1.087)
        (xy -7.341 1.086)
        (xy -7.406 1.036)
        (xy -7.448 0.97)
        (xy -7.469 0.895)
        (xy -7.468 0.858)
        (xy -7.361 0.858)
        (xy -7.355 0.905)
        (xy -7.331 0.942)
        (xy -7.31 0.962)
        (xy -7.252 0.999)
        (xy -7.195 1.005)
        (xy -7.137 0.979)
        (xy -7.116 0.962)
        (xy -7.08 0.923)
        (xy -7.066 0.883)
        (xy -7.065 0.858)
        (xy -7.079 0.801)
        (xy -7.116 0.751)
        (xy -7.167 0.718)
        (xy -7.213 0.708)
        (xy -7.27 0.722)
        (xy -7.319 0.76)
        (xy -7.352 0.812)
        (xy -7.361 0.858)
        (xy -7.468 0.858)
        (xy -7.468 0.817)
        (xy -7.445 0.742)
        (xy -7.401 0.677)
        (xy -7.336 0.628)
        (xy -7.325 0.622)
        (xy -7.26 0.593)
        (xy -7.26 0.22)
        (xy -7.535 0.22)
        (xy -7.762 0.445)
        (xy -7.753 0.52)
        (xy -7.757 0.595)
        (xy -7.785 0.658)
        (xy -7.83 0.703)
        (xy -7.887 0.73)
        (xy -7.951 0.735)
        (xy -8.015 0.715)
        (xy -8.065 0.678)
        (xy -8.109 0.617)
        (xy -8.123 0.551)
        (xy -8.12 0.532)
        (xy -8.012 0.532)
        (xy -8.009 0.566)
        (xy -7.985 0.598)
        (xy -7.946 0.625)
        (xy -7.912 0.623)
        (xy -7.883 0.599)
        (xy -7.863 0.558)
        (xy -7.868 0.517)
        (xy -7.896 0.486)
        (xy -7.915 0.478)
        (xy -7.961 0.48)
        (xy -7.985 0.496)
        (xy -8.012 0.532)
        (xy -8.12 0.532)
        (xy -8.112 0.486)
        (xy -8.079 0.422)
        (xy -8.025 0.381)
        (xy -7.953 0.365)
        (xy -7.919 0.366)
        (xy -7.845 0.373)
        (xy -7.584 0.11)
        (xy -7.26 0.11)
        (xy -7.26 -0.126)
        (xy -7.566 -0.126)
        (xy -7.672 -0.126)
        (xy -7.75 -0.126)
        (xy -7.805 -0.124)
        (xy -7.841 -0.121)
        (xy -7.863 -0.116)
        (xy -7.875 -0.108)
        (xy -7.881 -0.098)
        (xy -7.883 -0.094)
        (xy -7.908 -0.058)
        (xy -7.954 -0.026)
        (xy -8.009 -0.005)
        (xy -8.045 -0.001)
        (xy -8.117 -0.014)
        (xy -8.174 -0.049)
        (xy -8.213 -0.102)
        (xy -8.23 -0.164)
        (xy -8.228 -0.186)
        (xy -8.124 -0.186)
        (xy -8.12 -0.163)
        (xy -8.104 -0.143)
        (xy -8.063 -0.115)
        (xy -8.021 -0.117)
        (xy -7.994 -0.135)
        (xy -7.971 -0.176)
        (xy -7.976 -0.202)
        (xy -6.455 -0.202)
        (xy -6.449 -0.158)
        (xy -6.432 -0.135)
        (xy -6.392 -0.113)
        (xy -6.35 -0.121)
        (xy -6.322 -0.143)
        (xy -6.303 -0.169)
        (xy -6.304 -0.193)
        (xy -6.316 -0.218)
        (xy -6.35 -0.254)
        (xy -6.39 -0.265)
        (xy -6.429 -0.247)
        (xy -6.432 -0.244)
        (xy -6.455 -0.202)
        (xy -7.976 -0.202)
        (xy -7.979 -0.218)
        (xy -7.999 -0.244)
        (xy -8.04 -0.265)
        (xy -8.078 -0.255)
        (xy -8.11 -0.218)
        (xy -8.124 -0.186)
        (xy -8.228 -0.186)
        (xy -8.224 -0.232)
        (xy -8.192 -0.297)
        (xy -8.177 -0.317)
        (xy -8.121 -0.358)
        (xy -8.055 -0.374)
        (xy -7.988 -0.365)
        (xy -7.927 -0.333)
        (xy -7.885 -0.284)
        (xy -7.857 -0.237)
        (xy -7.26 -0.237)
        (xy -7.26 -0.489)
        (xy -7.586 -0.489)
        (xy -7.721 -0.615)
        (xy -7.779 -0.669)
        (xy -7.821 -0.704)
        (xy -7.852 -0.726)
        (xy -7.879 -0.737)
        (xy -7.908 -0.74)
        (xy -7.934 -0.741)
        (xy -8.011 -0.752)
        (xy -8.068 -0.787)
        (xy -8.105 -0.846)
        (xy -8.112 -0.866)
        (xy -8.119 -0.923)
        (xy -8.016 -0.923)
        (xy -8.003 -0.887)
        (xy -7.969 -0.862)
        (xy -7.928 -0.852)
        (xy -7.888 -0.861)
        (xy -7.878 -0.87)
        (xy -7.86 -0.907)
        (xy -7.866 -0.949)
        (xy -7.894 -0.984)
        (xy -7.924 -1.002)
        (xy -7.941 -1.008)
        (xy -7.964 -0.997)
        (xy -7.991 -0.969)
        (xy -8.011 -0.939)
        (xy -8.016 -0.923)
        (xy -8.119 -0.923)
        (xy -8.121 -0.94)
        (xy -8.105 -1.004)
        (xy -8.069 -1.055)
        (xy -8.018 -1.091)
        (xy -7.958 -1.108)
        (xy -7.894 -1.104)
        (xy -7.831 -1.076)
        (xy -7.787 -1.036)
        (xy -7.762 -1.001)
        (xy -7.751 -0.968)
        (xy -7.751 -0.923)
        (xy -7.753 -0.905)
        (xy -7.762 -0.824)
        (xy -7.648 -0.711)
        (xy -7.535 -0.599)
        (xy -7.26 -0.599)
        (xy -7.26 -0.971)
        (xy -7.323 -0.998)
        (xy -7.396 -1.046)
        (xy -7.446 -1.114)
        (xy -7.465 -1.166)
        (xy -7.472 -1.24)
        (xy -7.365 -1.24)
        (xy -7.359 -1.204)
        (xy -7.347 -1.177)
        (xy -7.307 -1.123)
        (xy -7.254 -1.093)
        (xy -7.194 -1.09)
        (xy -7.134 -1.116)
        (xy -7.127 -1.121)
        (xy -7.081 -1.171)
        (xy -7.065 -1.225)
        (xy -7.078 -1.283)
        (xy -7.116 -1.342)
        (xy -7.166 -1.375)
        (xy -7.222 -1.384)
        (xy -7.278 -1.368)
        (xy -7.326 -1.326)
        (xy -7.354 -1.278)
        (xy -7.365 -1.24)
        (xy -7.472 -1.24)
        (xy -7.474 -1.25)
        (xy -7.455 -1.328)
        (xy -7.416 -1.396)
        (xy -7.358 -1.449)
        (xy -7.288 -1.484)
        (xy -7.21 -1.495)
        (xy -7.128 -1.48)
      )

      (stroke (width 0.00186) (type solid)) (fill solid) (layer "F.Mask"))
    (fp_rect (start -12.319 -5.689) (end 12.319 5.329)
      (stroke (width 0.05) (type default)) (fill none) (layer "F.CrtYd"))
  )

  (footprint "antmicro-footprints:oshw-logo" (layer "F.Cu")
    (at 100.6 147.3)
    (descr "OSHW Logo")
    (tags "OSHW Logo")
    (property "Author" "Antmicro")
    (property "License" "Apache-2.0")
    (property "MPN" "")
    (property "Manufacturer" "")
    (property "Public" "False")
    (property "Sheetfile" "ecp5-dc-scm.kicad_sch")
    (property "Sheetname" "")
    (property "ki_description" "Mechanical part")
    (attr exclude_from_pos_files allow_soldermask_bridges)
    (fp_text reference "N2" (at -3.08 -4.76) (layer "F.SilkS") hide
        (effects (font (size 0.7 0.7) (thickness 0.127)))
    )
    (fp_text value "oshw_logo" (at 3.43 -4.88) (layer "F.SilkS") hide
        (effects (font (size 1.524 1.524) (thickness 0.3)))
    )
    (fp_text user "${REFERENCE}" (at -3.081 5.204) (layer "F.Fab") hide
        (effects (font (size 0.7 0.7) (thickness 0.15)) (justify left bottom))
    )
    (fp_text user "License: Apache-2.0" (at -3.081 7.604) (layer "F.Fab") hide
        (effects (font (size 0.7 0.7) (thickness 0.15)) (justify left bottom))
    )
    (fp_text user "Author: Antmicro" (at -3.081 6.404) (layer "F.Fab") hide
        (effects (font (size 0.7 0.7) (thickness 0.15)) (justify left bottom))
    )
    (fp_poly
      (pts
        (xy -0.843 2.558)
        (xy -0.815 2.564)
        (xy -0.794 2.572)
        (xy -0.773 2.581)
        (xy -0.759 2.589)
        (xy -0.738 2.603)
        (xy -0.783 2.658)
        (xy -0.8 2.677)
        (xy -0.814 2.694)
        (xy -0.825 2.706)
        (xy -0.831 2.712)
        (xy -0.832 2.712)
        (xy -0.837 2.71)
        (xy -0.847 2.703)
        (xy -0.849 2.702)
        (xy -0.874 2.69)
        (xy -0.904 2.684)
        (xy -0.935 2.685)
        (xy -0.942 2.686)
        (xy -0.975 2.698)
        (xy -1.001 2.717)
        (xy -1.02 2.741)
        (xy -1.034 2.766)
        (xy -1.039 3.197)
        (xy -1.164 3.2)
        (xy -1.164 2.565)
        (xy -1.037 2.565)
        (xy -1.037 2.626)
        (xy -1.009 2.604)
        (xy -0.972 2.579)
        (xy -0.931 2.563)
        (xy -0.887 2.556)
        (xy -0.843 2.558)
      )

      (stroke (width 0.01) (type solid)) (fill solid) (layer "F.Cu"))
    (fp_poly
      (pts
        (xy 1.889 1.554)
        (xy 1.907 1.559)
        (xy 1.927 1.566)
        (xy 1.948 1.574)
        (xy 1.966 1.583)
        (xy 1.979 1.592)
        (xy 1.984 1.597)
        (xy 1.982 1.604)
        (xy 1.974 1.616)
        (xy 1.962 1.633)
        (xy 1.946 1.652)
        (xy 1.945 1.654)
        (xy 1.929 1.673)
        (xy 1.915 1.689)
        (xy 1.906 1.7)
        (xy 1.901 1.706)
        (xy 1.896 1.705)
        (xy 1.885 1.7)
        (xy 1.873 1.695)
        (xy 1.84 1.683)
        (xy 1.808 1.68)
        (xy 1.776 1.685)
        (xy 1.747 1.698)
        (xy 1.723 1.717)
        (xy 1.704 1.742)
        (xy 1.696 1.763)
        (xy 1.695 1.772)
        (xy 1.694 1.79)
        (xy 1.693 1.817)
        (xy 1.692 1.85)
        (xy 1.692 1.89)
        (xy 1.691 1.934)
        (xy 1.691 1.983)
        (xy 1.691 2.194)
        (xy 1.559 2.194)
        (xy 1.559 1.559)
        (xy 1.691 1.559)
        (xy 1.691 1.626)
        (xy 1.71 1.607)
        (xy 1.739 1.585)
        (xy 1.775 1.568)
        (xy 1.814 1.556)
        (xy 1.855 1.552)
        (xy 1.889 1.554)
      )

      (stroke (width 0.01) (type solid)) (fill solid) (layer "F.Cu"))
    (fp_poly
      (pts
        (xy -0.837 1.56)
        (xy -0.797 1.576)
        (xy -0.761 1.6)
        (xy -0.73 1.63)
        (xy -0.706 1.667)
        (xy -0.69 1.709)
        (xy -0.687 1.721)
        (xy -0.685 1.734)
        (xy -0.684 1.757)
        (xy -0.683 1.79)
        (xy -0.682 1.833)
        (xy -0.681 1.884)
        (xy -0.681 1.945)
        (xy -0.681 1.971)
        (xy -0.681 2.194)
        (xy -0.808 2.194)
        (xy -0.809 1.984)
        (xy -0.811 1.774)
        (xy -0.826 1.744)
        (xy -0.845 1.716)
        (xy -0.868 1.697)
        (xy -0.897 1.686)
        (xy -0.925 1.682)
        (xy -0.947 1.682)
        (xy -0.967 1.684)
        (xy -0.979 1.686)
        (xy -1.001 1.698)
        (xy -1.023 1.716)
        (xy -1.041 1.738)
        (xy -1.049 1.752)
        (xy -1.052 1.758)
        (xy -1.054 1.765)
        (xy -1.056 1.773)
        (xy -1.057 1.783)
        (xy -1.058 1.797)
        (xy -1.059 1.815)
        (xy -1.06 1.839)
        (xy -1.06 1.869)
        (xy -1.061 1.907)
        (xy -1.061 1.953)
        (xy -1.061 1.985)
        (xy -1.063 2.194)
        (xy -1.189 2.194)
        (xy -1.189 1.559)
        (xy -1.062 1.559)
        (xy -1.062 1.625)
        (xy -1.033 1.602)
        (xy -1.001 1.579)
        (xy -0.969 1.564)
        (xy -0.934 1.555)
        (xy -0.927 1.554)
        (xy -0.881 1.553)
        (xy -0.837 1.56)
      )

      (stroke (width 0.01) (type solid)) (fill solid) (layer "F.Cu"))
    (fp_poly
      (pts
        (xy 1.042 1.769)
        (xy 1.043 1.979)
        (xy 1.059 2.009)
        (xy 1.077 2.036)
        (xy 1.1 2.056)
        (xy 1.129 2.067)
        (xy 1.159 2.071)
        (xy 1.193 2.07)
        (xy 1.221 2.063)
        (xy 1.245 2.047)
        (xy 1.258 2.034)
        (xy 1.266 2.025)
        (xy 1.273 2.016)
        (xy 1.278 2.008)
        (xy 1.282 1.997)
        (xy 1.286 1.985)
        (xy 1.288 1.969)
        (xy 1.29 1.948)
        (xy 1.291 1.922)
        (xy 1.292 1.89)
        (xy 1.293 1.85)
        (xy 1.293 1.801)
        (xy 1.294 1.766)
        (xy 1.295 1.559)
        (xy 1.422 1.559)
        (xy 1.422 2.194)
        (xy 1.295 2.194)
        (xy 1.295 2.161)
        (xy 1.295 2.144)
        (xy 1.293 2.132)
        (xy 1.292 2.128)
        (xy 1.287 2.131)
        (xy 1.278 2.14)
        (xy 1.271 2.147)
        (xy 1.256 2.159)
        (xy 1.236 2.171)
        (xy 1.219 2.181)
        (xy 1.202 2.188)
        (xy 1.186 2.193)
        (xy 1.17 2.196)
        (xy 1.148 2.197)
        (xy 1.135 2.198)
        (xy 1.107 2.198)
        (xy 1.087 2.197)
        (xy 1.07 2.194)
        (xy 1.059 2.19)
        (xy 1.036 2.181)
        (xy 1.019 2.172)
        (xy 1.003 2.161)
        (xy 0.985 2.146)
        (xy 0.981 2.141)
        (xy 0.952 2.107)
        (xy 0.931 2.068)
        (xy 0.92 2.033)
        (xy 0.918 2.019)
        (xy 0.917 1.996)
        (xy 0.916 1.963)
        (xy 0.915 1.92)
        (xy 0.914 1.869)
        (xy 0.914 1.808)
        (xy 0.914 1.782)
        (xy 0.914 1.559)
        (xy 1.04 1.559)
        (xy 1.042 1.769)
      )

      (stroke (width 0.01) (type solid)) (fill solid) (layer "F.Cu"))
    (fp_poly
      (pts
        (xy 1.753 2.563)
        (xy 1.768 2.568)
        (xy 1.787 2.577)
        (xy 1.804 2.586)
        (xy 1.818 2.595)
        (xy 1.826 2.602)
        (xy 1.827 2.606)
        (xy 1.824 2.611)
        (xy 1.815 2.621)
        (xy 1.803 2.636)
        (xy 1.789 2.654)
        (xy 1.775 2.671)
        (xy 1.761 2.688)
        (xy 1.749 2.701)
        (xy 1.742 2.71)
        (xy 1.739 2.712)
        (xy 1.735 2.71)
        (xy 1.724 2.704)
        (xy 1.713 2.698)
        (xy 1.697 2.69)
        (xy 1.682 2.686)
        (xy 1.664 2.685)
        (xy 1.653 2.685)
        (xy 1.618 2.688)
        (xy 1.59 2.699)
        (xy 1.566 2.718)
        (xy 1.561 2.723)
        (xy 1.554 2.732)
        (xy 1.548 2.74)
        (xy 1.544 2.748)
        (xy 1.54 2.758)
        (xy 1.537 2.769)
        (xy 1.534 2.785)
        (xy 1.533 2.804)
        (xy 1.532 2.829)
        (xy 1.531 2.861)
        (xy 1.53 2.899)
        (xy 1.53 2.947)
        (xy 1.53 2.988)
        (xy 1.528 3.2)
        (xy 1.468 3.2)
        (xy 1.444 3.2)
        (xy 1.425 3.199)
        (xy 1.411 3.198)
        (xy 1.405 3.197)
        (xy 1.404 3.191)
        (xy 1.404 3.176)
        (xy 1.403 3.153)
        (xy 1.403 3.122)
        (xy 1.402 3.085)
        (xy 1.402 3.042)
        (xy 1.402 2.993)
        (xy 1.402 2.941)
        (xy 1.402 2.886)
        (xy 1.402 2.565)
        (xy 1.529 2.565)
        (xy 1.529 2.595)
        (xy 1.529 2.611)
        (xy 1.53 2.623)
        (xy 1.532 2.626)
        (xy 1.537 2.623)
        (xy 1.547 2.615)
        (xy 1.554 2.608)
        (xy 1.588 2.584)
        (xy 1.627 2.567)
        (xy 1.669 2.558)
        (xy 1.712 2.556)
        (xy 1.753 2.563)
      )

      (stroke (width 0.01) (type solid)) (fill solid) (layer "F.Cu"))
    (fp_poly
      (pts
        (xy 2.316 1.557)
        (xy 2.365 1.57)
        (xy 2.41 1.593)
        (xy 2.453 1.625)
        (xy 2.46 1.631)
        (xy 2.491 1.661)
        (xy 2.466 1.684)
        (xy 2.448 1.699)
        (xy 2.43 1.715)
        (xy 2.419 1.725)
        (xy 2.397 1.743)
        (xy 2.376 1.724)
        (xy 2.345 1.701)
        (xy 2.312 1.687)
        (xy 2.274 1.681)
        (xy 2.265 1.681)
        (xy 2.226 1.684)
        (xy 2.195 1.693)
        (xy 2.167 1.708)
        (xy 2.159 1.715)
        (xy 2.136 1.741)
        (xy 2.118 1.776)
        (xy 2.107 1.817)
        (xy 2.103 1.866)
        (xy 2.103 1.876)
        (xy 2.106 1.926)
        (xy 2.116 1.97)
        (xy 2.132 2.006)
        (xy 2.155 2.034)
        (xy 2.184 2.055)
        (xy 2.219 2.067)
        (xy 2.259 2.072)
        (xy 2.274 2.071)
        (xy 2.309 2.066)
        (xy 2.339 2.056)
        (xy 2.366 2.038)
        (xy 2.377 2.028)
        (xy 2.386 2.02)
        (xy 2.393 2.016)
        (xy 2.4 2.015)
        (xy 2.409 2.018)
        (xy 2.42 2.027)
        (xy 2.436 2.041)
        (xy 2.456 2.059)
        (xy 2.491 2.092)
        (xy 2.476 2.108)
        (xy 2.449 2.132)
        (xy 2.416 2.155)
        (xy 2.38 2.174)
        (xy 2.35 2.186)
        (xy 2.327 2.193)
        (xy 2.306 2.197)
        (xy 2.283 2.199)
        (xy 2.259 2.199)
        (xy 2.233 2.198)
        (xy 2.209 2.196)
        (xy 2.189 2.193)
        (xy 2.182 2.191)
        (xy 2.133 2.173)
        (xy 2.089 2.146)
        (xy 2.053 2.112)
        (xy 2.023 2.071)
        (xy 2.012 2.051)
        (xy 2 2.023)
        (xy 1.991 1.999)
        (xy 1.984 1.975)
        (xy 1.981 1.948)
        (xy 1.979 1.917)
        (xy 1.978 1.879)
        (xy 1.978 1.877)
        (xy 1.979 1.838)
        (xy 1.98 1.806)
        (xy 1.984 1.78)
        (xy 1.99 1.756)
        (xy 1.999 1.731)
        (xy 2.011 1.704)
        (xy 2.012 1.701)
        (xy 2.039 1.657)
        (xy 2.072 1.62)
        (xy 2.111 1.591)
        (xy 2.156 1.57)
        (xy 2.207 1.557)
        (xy 2.263 1.552)
        (xy 2.316 1.557)
      )

      (stroke (width 0.01) (type solid)) (fill solid) (layer "F.Cu"))
    (fp_poly
      (pts
        (xy -1.494 1.56)
        (xy -1.447 1.576)
        (xy -1.405 1.6)
        (xy -1.368 1.633)
        (xy -1.341 1.668)
        (xy -1.326 1.692)
        (xy -1.316 1.716)
        (xy -1.308 1.743)
        (xy -1.302 1.774)
        (xy -1.299 1.811)
        (xy -1.297 1.845)
        (xy -1.294 1.925)
        (xy -1.692 1.925)
        (xy -1.692 1.942)
        (xy -1.687 1.977)
        (xy -1.673 2.011)
        (xy -1.65 2.039)
        (xy -1.626 2.059)
        (xy -1.601 2.071)
        (xy -1.572 2.078)
        (xy -1.537 2.079)
        (xy -1.497 2.074)
        (xy -1.458 2.06)
        (xy -1.422 2.036)
        (xy -1.421 2.036)
        (xy -1.402 2.021)
        (xy -1.359 2.057)
        (xy -1.342 2.072)
        (xy -1.327 2.085)
        (xy -1.317 2.094)
        (xy -1.314 2.098)
        (xy -1.316 2.103)
        (xy -1.324 2.113)
        (xy -1.338 2.126)
        (xy -1.354 2.139)
        (xy -1.372 2.152)
        (xy -1.389 2.163)
        (xy -1.399 2.168)
        (xy -1.421 2.178)
        (xy -1.445 2.187)
        (xy -1.461 2.191)
        (xy -1.488 2.196)
        (xy -1.522 2.199)
        (xy -1.557 2.199)
        (xy -1.591 2.196)
        (xy -1.62 2.192)
        (xy -1.629 2.19)
        (xy -1.677 2.171)
        (xy -1.718 2.146)
        (xy -1.752 2.114)
        (xy -1.779 2.074)
        (xy -1.8 2.026)
        (xy -1.802 2.02)
        (xy -1.81 1.989)
        (xy -1.815 1.951)
        (xy -1.818 1.908)
        (xy -1.819 1.865)
        (xy -1.818 1.823)
        (xy -1.816 1.804)
        (xy -1.692 1.804)
        (xy -1.692 1.818)
        (xy -1.428 1.818)
        (xy -1.428 1.801)
        (xy -1.432 1.775)
        (xy -1.442 1.748)
        (xy -1.457 1.722)
        (xy -1.469 1.707)
        (xy -1.495 1.688)
        (xy -1.526 1.676)
        (xy -1.56 1.672)
        (xy -1.593 1.676)
        (xy -1.619 1.685)
        (xy -1.646 1.704)
        (xy -1.668 1.73)
        (xy -1.683 1.76)
        (xy -1.691 1.792)
        (xy -1.692 1.804)
        (xy -1.816 1.804)
        (xy -1.814 1.786)
        (xy -1.812 1.777)
        (xy -1.797 1.724)
        (xy -1.775 1.676)
        (xy -1.747 1.636)
        (xy -1.713 1.603)
        (xy -1.673 1.578)
        (xy -1.629 1.561)
        (xy -1.597 1.554)
        (xy -1.544 1.552)
        (xy -1.494 1.56)
      )

      (stroke (width 0.01) (type solid)) (fill solid) (layer "F.Cu"))
    (fp_poly
      (pts
        (xy 2.835 1.557)
        (xy 2.883 1.57)
        (xy 2.926 1.592)
        (xy 2.964 1.621)
        (xy 2.996 1.657)
        (xy 3.021 1.699)
        (xy 3.038 1.747)
        (xy 3.04 1.757)
        (xy 3.043 1.776)
        (xy 3.045 1.802)
        (xy 3.047 1.832)
        (xy 3.047 1.858)
        (xy 3.047 1.925)
        (xy 2.65 1.925)
        (xy 2.653 1.951)
        (xy 2.663 1.991)
        (xy 2.68 2.024)
        (xy 2.703 2.049)
        (xy 2.733 2.067)
        (xy 2.77 2.077)
        (xy 2.801 2.079)
        (xy 2.845 2.075)
        (xy 2.883 2.063)
        (xy 2.916 2.042)
        (xy 2.92 2.039)
        (xy 2.929 2.031)
        (xy 2.935 2.026)
        (xy 2.941 2.025)
        (xy 2.949 2.027)
        (xy 2.959 2.034)
        (xy 2.974 2.047)
        (xy 2.994 2.064)
        (xy 3.01 2.078)
        (xy 3.023 2.088)
        (xy 3.03 2.095)
        (xy 3.032 2.096)
        (xy 3.03 2.1)
        (xy 3.022 2.11)
        (xy 3.01 2.122)
        (xy 3.009 2.123)
        (xy 2.98 2.147)
        (xy 2.945 2.169)
        (xy 2.906 2.185)
        (xy 2.887 2.191)
        (xy 2.861 2.196)
        (xy 2.828 2.198)
        (xy 2.793 2.198)
        (xy 2.759 2.197)
        (xy 2.729 2.193)
        (xy 2.721 2.191)
        (xy 2.675 2.175)
        (xy 2.634 2.15)
        (xy 2.599 2.118)
        (xy 2.569 2.077)
        (xy 2.547 2.029)
        (xy 2.536 1.996)
        (xy 2.532 1.973)
        (xy 2.529 1.942)
        (xy 2.527 1.906)
        (xy 2.527 1.869)
        (xy 2.528 1.832)
        (xy 2.529 1.818)
        (xy 2.65 1.818)
        (xy 2.922 1.818)
        (xy 2.918 1.799)
        (xy 2.908 1.758)
        (xy 2.891 1.725)
        (xy 2.869 1.7)
        (xy 2.84 1.683)
        (xy 2.826 1.678)
        (xy 2.788 1.672)
        (xy 2.753 1.675)
        (xy 2.722 1.687)
        (xy 2.695 1.706)
        (xy 2.674 1.734)
        (xy 2.659 1.768)
        (xy 2.654 1.794)
        (xy 2.65 1.818)
        (xy 2.529 1.818)
        (xy 2.53 1.798)
        (xy 2.534 1.769)
        (xy 2.536 1.76)
        (xy 2.554 1.707)
        (xy 2.578 1.662)
        (xy 2.609 1.624)
        (xy 2.645 1.593)
        (xy 2.687 1.571)
        (xy 2.734 1.557)
        (xy 2.783 1.553)
        (xy 2.835 1.557)
      )

      (stroke (width 0.01) (type solid)) (fill solid) (layer "F.Cu"))
    (fp_poly
      (pts
        (xy -2.733 1.557)
        (xy -2.685 1.57)
        (xy -2.642 1.592)
        (xy -2.604 1.622)
        (xy -2.581 1.649)
        (xy -2.562 1.676)
        (xy -2.548 1.706)
        (xy -2.537 1.739)
        (xy -2.53 1.777)
        (xy -2.527 1.821)
        (xy -2.526 1.873)
        (xy -2.527 1.907)
        (xy -2.529 1.956)
        (xy -2.534 1.997)
        (xy -2.542 2.031)
        (xy -2.553 2.06)
        (xy -2.567 2.086)
        (xy -2.587 2.111)
        (xy -2.603 2.129)
        (xy -2.637 2.158)
        (xy -2.673 2.178)
        (xy -2.714 2.192)
        (xy -2.76 2.198)
        (xy -2.789 2.199)
        (xy -2.813 2.198)
        (xy -2.835 2.196)
        (xy -2.852 2.194)
        (xy -2.857 2.194)
        (xy -2.898 2.179)
        (xy -2.937 2.155)
        (xy -2.97 2.126)
        (xy -2.993 2.101)
        (xy -3.011 2.077)
        (xy -3.024 2.051)
        (xy -3.034 2.022)
        (xy -3.041 1.988)
        (xy -3.045 1.947)
        (xy -3.047 1.91)
        (xy -3.047 1.882)
        (xy -2.919 1.882)
        (xy -2.919 1.968)
        (xy -2.903 2.001)
        (xy -2.885 2.031)
        (xy -2.863 2.051)
        (xy -2.837 2.064)
        (xy -2.804 2.07)
        (xy -2.779 2.07)
        (xy -2.755 2.069)
        (xy -2.737 2.065)
        (xy -2.722 2.058)
        (xy -2.717 2.055)
        (xy -2.697 2.041)
        (xy -2.681 2.025)
        (xy -2.67 2.004)
        (xy -2.662 1.978)
        (xy -2.657 1.945)
        (xy -2.654 1.903)
        (xy -2.654 1.899)
        (xy -2.653 1.848)
        (xy -2.656 1.806)
        (xy -2.662 1.772)
        (xy -2.673 1.744)
        (xy -2.687 1.722)
        (xy -2.707 1.705)
        (xy -2.723 1.695)
        (xy -2.755 1.684)
        (xy -2.788 1.68)
        (xy -2.821 1.684)
        (xy -2.851 1.695)
        (xy -2.877 1.713)
        (xy -2.892 1.729)
        (xy -2.901 1.745)
        (xy -2.908 1.76)
        (xy -2.913 1.778)
        (xy -2.916 1.8)
        (xy -2.918 1.828)
        (xy -2.919 1.864)
        (xy -2.919 1.882)
        (xy -3.047 1.882)
        (xy -3.048 1.844)
        (xy -3.043 1.786)
        (xy -3.034 1.736)
        (xy -3.021 1.695)
        (xy -3.004 1.664)
        (xy -2.972 1.624)
        (xy -2.935 1.594)
        (xy -2.893 1.571)
        (xy -2.846 1.558)
        (xy -2.794 1.553)
        (xy -2.787 1.553)
        (xy -2.733 1.557)
      )

      (stroke (width 0.01) (type solid)) (fill solid) (layer "F.Cu"))
    (fp_poly
      (pts
        (xy 2.148 2.561)
        (xy 2.193 2.574)
        (xy 2.235 2.595)
        (xy 2.273 2.623)
        (xy 2.304 2.657)
        (xy 2.326 2.691)
        (xy 2.338 2.718)
        (xy 2.346 2.745)
        (xy 2.352 2.774)
        (xy 2.355 2.808)
        (xy 2.357 2.85)
        (xy 2.357 2.858)
        (xy 2.357 2.931)
        (xy 1.96 2.931)
        (xy 1.963 2.955)
        (xy 1.973 2.993)
        (xy 1.991 3.026)
        (xy 2.015 3.053)
        (xy 2.039 3.069)
        (xy 2.057 3.076)
        (xy 2.08 3.08)
        (xy 2.103 3.082)
        (xy 2.144 3.081)
        (xy 2.18 3.071)
        (xy 2.214 3.054)
        (xy 2.227 3.045)
        (xy 2.24 3.035)
        (xy 2.25 3.029)
        (xy 2.253 3.027)
        (xy 2.258 3.03)
        (xy 2.269 3.039)
        (xy 2.284 3.05)
        (xy 2.3 3.064)
        (xy 2.315 3.078)
        (xy 2.329 3.09)
        (xy 2.338 3.099)
        (xy 2.341 3.103)
        (xy 2.337 3.11)
        (xy 2.327 3.121)
        (xy 2.312 3.134)
        (xy 2.294 3.148)
        (xy 2.276 3.161)
        (xy 2.259 3.171)
        (xy 2.252 3.175)
        (xy 2.204 3.192)
        (xy 2.152 3.202)
        (xy 2.098 3.204)
        (xy 2.046 3.198)
        (xy 2.032 3.195)
        (xy 1.984 3.178)
        (xy 1.943 3.154)
        (xy 1.909 3.123)
        (xy 1.881 3.084)
        (xy 1.859 3.037)
        (xy 1.847 3.003)
        (xy 1.841 2.972)
        (xy 1.838 2.934)
        (xy 1.836 2.893)
        (xy 1.837 2.851)
        (xy 1.839 2.824)
        (xy 1.96 2.824)
        (xy 2.23 2.824)
        (xy 2.23 2.813)
        (xy 2.225 2.783)
        (xy 2.214 2.753)
        (xy 2.196 2.725)
        (xy 2.175 2.702)
        (xy 2.151 2.686)
        (xy 2.128 2.68)
        (xy 2.101 2.677)
        (xy 2.072 2.678)
        (xy 2.051 2.683)
        (xy 2.023 2.696)
        (xy 2 2.717)
        (xy 1.981 2.746)
        (xy 1.968 2.779)
        (xy 1.963 2.8)
        (xy 1.96 2.824)
        (xy 1.839 2.824)
        (xy 1.839 2.811)
        (xy 1.844 2.776)
        (xy 1.848 2.76)
        (xy 1.866 2.708)
        (xy 1.889 2.663)
        (xy 1.919 2.627)
        (xy 1.954 2.598)
        (xy 1.996 2.575)
        (xy 2.007 2.571)
        (xy 2.054 2.559)
        (xy 2.101 2.556)
        (xy 2.148 2.561)
      )

      (stroke (width 0.01) (type solid)) (fill solid) (layer "F.Cu"))
    (fp_poly
      (pts
        (xy -0.229 3.2)
        (xy -0.354 3.197)
        (xy -0.355 3.165)
        (xy -0.357 3.133)
        (xy -0.374 3.148)
        (xy -0.411 3.175)
        (xy -0.453 3.193)
        (xy -0.497 3.203)
        (xy -0.542 3.204)
        (xy -0.585 3.195)
        (xy -0.586 3.195)
        (xy -0.621 3.181)
        (xy -0.651 3.16)
        (xy -0.673 3.141)
        (xy -0.689 3.123)
        (xy -0.702 3.106)
        (xy -0.712 3.086)
        (xy -0.72 3.064)
        (xy -0.726 3.038)
        (xy -0.73 3.007)
        (xy -0.732 2.968)
        (xy -0.733 2.922)
        (xy -0.733 2.88)
        (xy -0.602 2.88)
        (xy -0.602 2.915)
        (xy -0.602 2.942)
        (xy -0.601 2.962)
        (xy -0.6 2.977)
        (xy -0.598 2.988)
        (xy -0.596 2.998)
        (xy -0.592 3.007)
        (xy -0.591 3.01)
        (xy -0.574 3.039)
        (xy -0.552 3.059)
        (xy -0.525 3.071)
        (xy -0.492 3.076)
        (xy -0.472 3.076)
        (xy -0.442 3.072)
        (xy -0.418 3.063)
        (xy -0.398 3.048)
        (xy -0.382 3.029)
        (xy -0.371 3.004)
        (xy -0.363 2.972)
        (xy -0.358 2.933)
        (xy -0.356 2.885)
        (xy -0.356 2.88)
        (xy -0.358 2.828)
        (xy -0.363 2.785)
        (xy -0.373 2.75)
        (xy -0.387 2.724)
        (xy -0.406 2.704)
        (xy -0.43 2.692)
        (xy -0.46 2.686)
        (xy -0.483 2.685)
        (xy -0.517 2.687)
        (xy -0.544 2.696)
        (xy -0.565 2.711)
        (xy -0.583 2.734)
        (xy -0.591 2.751)
        (xy -0.595 2.76)
        (xy -0.598 2.769)
        (xy -0.6 2.779)
        (xy -0.601 2.793)
        (xy -0.602 2.811)
        (xy -0.602 2.836)
        (xy -0.602 2.869)
        (xy -0.602 2.88)
        (xy -0.733 2.88)
        (xy -0.733 2.827)
        (xy -0.732 2.783)
        (xy -0.729 2.746)
        (xy -0.725 2.716)
        (xy -0.719 2.691)
        (xy -0.71 2.67)
        (xy -0.699 2.651)
        (xy -0.685 2.633)
        (xy -0.668 2.616)
        (xy -0.668 2.615)
        (xy -0.632 2.587)
        (xy -0.592 2.567)
        (xy -0.55 2.557)
        (xy -0.506 2.556)
        (xy -0.463 2.564)
        (xy -0.421 2.582)
        (xy -0.411 2.587)
        (xy -0.394 2.598)
        (xy -0.377 2.61)
        (xy -0.373 2.614)
        (xy -0.356 2.627)
        (xy -0.356 2.306)
        (xy -0.229 2.306)
        (xy -0.229 3.2)
      )

      (stroke (width 0.01) (type solid)) (fill solid) (layer "F.Cu"))
    (fp_poly
      (pts
        (xy 0.605 1.558)
        (xy 0.651 1.574)
        (xy 0.694 1.598)
        (xy 0.728 1.627)
        (xy 0.75 1.652)
        (xy 0.768 1.678)
        (xy 0.781 1.707)
        (xy 0.791 1.739)
        (xy 0.797 1.777)
        (xy 0.801 1.822)
        (xy 0.802 1.876)
        (xy 0.802 1.877)
        (xy 0.801 1.929)
        (xy 0.798 1.973)
        (xy 0.792 2.009)
        (xy 0.784 2.04)
        (xy 0.774 2.062)
        (xy 0.748 2.103)
        (xy 0.715 2.139)
        (xy 0.675 2.167)
        (xy 0.632 2.187)
        (xy 0.626 2.189)
        (xy 0.599 2.195)
        (xy 0.567 2.198)
        (xy 0.532 2.199)
        (xy 0.499 2.197)
        (xy 0.471 2.193)
        (xy 0.466 2.192)
        (xy 0.428 2.177)
        (xy 0.391 2.155)
        (xy 0.359 2.129)
        (xy 0.354 2.123)
        (xy 0.332 2.098)
        (xy 0.316 2.073)
        (xy 0.303 2.047)
        (xy 0.294 2.017)
        (xy 0.287 1.983)
        (xy 0.284 1.943)
        (xy 0.282 1.894)
        (xy 0.282 1.877)
        (xy 0.409 1.877)
        (xy 0.41 1.918)
        (xy 0.412 1.95)
        (xy 0.416 1.976)
        (xy 0.423 1.997)
        (xy 0.432 2.015)
        (xy 0.445 2.03)
        (xy 0.451 2.037)
        (xy 0.471 2.054)
        (xy 0.491 2.064)
        (xy 0.514 2.07)
        (xy 0.543 2.072)
        (xy 0.569 2.07)
        (xy 0.59 2.065)
        (xy 0.601 2.06)
        (xy 0.625 2.047)
        (xy 0.642 2.031)
        (xy 0.656 2.009)
        (xy 0.661 1.998)
        (xy 0.665 1.989)
        (xy 0.668 1.98)
        (xy 0.67 1.969)
        (xy 0.671 1.954)
        (xy 0.672 1.935)
        (xy 0.673 1.909)
        (xy 0.673 1.877)
        (xy 0.673 1.842)
        (xy 0.672 1.817)
        (xy 0.671 1.798)
        (xy 0.67 1.784)
        (xy 0.668 1.773)
        (xy 0.665 1.764)
        (xy 0.661 1.755)
        (xy 0.647 1.73)
        (xy 0.632 1.712)
        (xy 0.612 1.698)
        (xy 0.601 1.693)
        (xy 0.569 1.683)
        (xy 0.535 1.681)
        (xy 0.501 1.686)
        (xy 0.471 1.7)
        (xy 0.447 1.719)
        (xy 0.434 1.736)
        (xy 0.424 1.753)
        (xy 0.417 1.774)
        (xy 0.412 1.8)
        (xy 0.41 1.833)
        (xy 0.409 1.873)
        (xy 0.409 1.877)
        (xy 0.282 1.877)
        (xy 0.283 1.824)
        (xy 0.286 1.78)
        (xy 0.292 1.742)
        (xy 0.301 1.711)
        (xy 0.313 1.683)
        (xy 0.33 1.657)
        (xy 0.35 1.633)
        (xy 0.351 1.632)
        (xy 0.385 1.601)
        (xy 0.42 1.578)
        (xy 0.46 1.563)
        (xy 0.505 1.554)
        (xy 0.555 1.551)
        (xy 0.605 1.558)
      )

      (stroke (width 0.01) (type solid)) (fill solid) (layer "F.Cu"))
    (fp_poly
      (pts
        (xy 0.004 1.556)
        (xy 0.054 1.566)
        (xy 0.102 1.582)
        (xy 0.146 1.605)
        (xy 0.154 1.61)
        (xy 0.193 1.636)
        (xy 0.178 1.655)
        (xy 0.166 1.668)
        (xy 0.152 1.686)
        (xy 0.138 1.7)
        (xy 0.114 1.727)
        (xy 0.07 1.705)
        (xy 0.032 1.688)
        (xy -0.007 1.677)
        (xy -0.044 1.672)
        (xy -0.079 1.672)
        (xy -0.11 1.678)
        (xy -0.136 1.69)
        (xy -0.154 1.707)
        (xy -0.162 1.724)
        (xy -0.164 1.745)
        (xy -0.164 1.761)
        (xy -0.159 1.772)
        (xy -0.15 1.782)
        (xy -0.149 1.783)
        (xy -0.139 1.791)
        (xy -0.128 1.797)
        (xy -0.114 1.802)
        (xy -0.095 1.805)
        (xy -0.07 1.808)
        (xy -0.037 1.811)
        (xy -0.02 1.813)
        (xy 0.027 1.817)
        (xy 0.065 1.823)
        (xy 0.096 1.832)
        (xy 0.122 1.842)
        (xy 0.14 1.854)
        (xy 0.166 1.879)
        (xy 0.186 1.91)
        (xy 0.2 1.947)
        (xy 0.206 1.987)
        (xy 0.206 2.018)
        (xy 0.198 2.06)
        (xy 0.181 2.097)
        (xy 0.155 2.129)
        (xy 0.122 2.156)
        (xy 0.08 2.177)
        (xy 0.042 2.189)
        (xy 0.005 2.196)
        (xy -0.038 2.199)
        (xy -0.083 2.198)
        (xy -0.125 2.194)
        (xy -0.153 2.189)
        (xy -0.177 2.181)
        (xy -0.204 2.171)
        (xy -0.229 2.16)
        (xy -0.232 2.159)
        (xy -0.251 2.148)
        (xy -0.272 2.136)
        (xy -0.292 2.122)
        (xy -0.309 2.109)
        (xy -0.323 2.098)
        (xy -0.33 2.09)
        (xy -0.331 2.088)
        (xy -0.327 2.084)
        (xy -0.318 2.073)
        (xy -0.304 2.059)
        (xy -0.288 2.043)
        (xy -0.246 2)
        (xy -0.221 2.021)
        (xy -0.184 2.047)
        (xy -0.145 2.065)
        (xy -0.102 2.075)
        (xy -0.053 2.079)
        (xy -0.049 2.079)
        (xy -0.023 2.079)
        (xy -0.004 2.078)
        (xy 0.011 2.074)
        (xy 0.025 2.069)
        (xy 0.029 2.068)
        (xy 0.054 2.052)
        (xy 0.071 2.033)
        (xy 0.079 2.01)
        (xy 0.078 1.986)
        (xy 0.074 1.975)
        (xy 0.068 1.964)
        (xy 0.06 1.956)
        (xy 0.048 1.949)
        (xy 0.031 1.944)
        (xy 0.007 1.939)
        (xy -0.024 1.935)
        (xy -0.052 1.932)
        (xy -0.089 1.929)
        (xy -0.119 1.925)
        (xy -0.142 1.921)
        (xy -0.16 1.917)
        (xy -0.176 1.912)
        (xy -0.192 1.906)
        (xy -0.201 1.901)
        (xy -0.235 1.879)
        (xy -0.262 1.85)
        (xy -0.28 1.816)
        (xy -0.29 1.776)
        (xy -0.292 1.75)
        (xy -0.291 1.727)
        (xy -0.289 1.705)
        (xy -0.286 1.689)
        (xy -0.286 1.688)
        (xy -0.273 1.659)
        (xy -0.253 1.63)
        (xy -0.229 1.604)
        (xy -0.221 1.599)
        (xy -0.185 1.577)
        (xy -0.143 1.562)
        (xy -0.096 1.554)
        (xy -0.047 1.552)
        (xy 0.004 1.556)
      )

      (stroke (width 0.01) (type solid)) (fill solid) (layer "F.Cu"))
    (fp_poly
      (pts
        (xy 1.038 2.556)
        (xy 1.091 2.563)
        (xy 1.137 2.576)
        (xy 1.177 2.595)
        (xy 1.209 2.62)
        (xy 1.234 2.65)
        (xy 1.242 2.665)
        (xy 1.247 2.677)
        (xy 1.251 2.691)
        (xy 1.255 2.708)
        (xy 1.258 2.727)
        (xy 1.26 2.751)
        (xy 1.262 2.78)
        (xy 1.263 2.815)
        (xy 1.263 2.858)
        (xy 1.264 2.908)
        (xy 1.263 2.967)
        (xy 1.263 2.989)
        (xy 1.262 3.197)
        (xy 1.135 3.197)
        (xy 1.133 3.171)
        (xy 1.132 3.144)
        (xy 1.119 3.159)
        (xy 1.096 3.179)
        (xy 1.065 3.193)
        (xy 1.026 3.202)
        (xy 0.98 3.204)
        (xy 0.976 3.204)
        (xy 0.955 3.204)
        (xy 0.937 3.203)
        (xy 0.925 3.202)
        (xy 0.924 3.201)
        (xy 0.879 3.189)
        (xy 0.839 3.17)
        (xy 0.806 3.144)
        (xy 0.781 3.113)
        (xy 0.763 3.077)
        (xy 0.753 3.037)
        (xy 0.753 3.005)
        (xy 0.873 3.005)
        (xy 0.874 3.023)
        (xy 0.878 3.035)
        (xy 0.887 3.047)
        (xy 0.89 3.05)
        (xy 0.903 3.063)
        (xy 0.917 3.072)
        (xy 0.935 3.078)
        (xy 0.957 3.081)
        (xy 0.986 3.082)
        (xy 1.013 3.082)
        (xy 1.043 3.081)
        (xy 1.065 3.079)
        (xy 1.08 3.077)
        (xy 1.091 3.073)
        (xy 1.096 3.071)
        (xy 1.112 3.058)
        (xy 1.123 3.039)
        (xy 1.13 3.012)
        (xy 1.132 2.977)
        (xy 1.132 2.975)
        (xy 1.132 2.931)
        (xy 1.035 2.931)
        (xy 0.999 2.931)
        (xy 0.973 2.931)
        (xy 0.953 2.932)
        (xy 0.939 2.934)
        (xy 0.928 2.936)
        (xy 0.919 2.939)
        (xy 0.916 2.94)
        (xy 0.893 2.954)
        (xy 0.88 2.971)
        (xy 0.874 2.994)
        (xy 0.873 3.005)
        (xy 0.753 3.005)
        (xy 0.753 2.994)
        (xy 0.761 2.951)
        (xy 0.768 2.931)
        (xy 0.776 2.915)
        (xy 0.786 2.901)
        (xy 0.802 2.884)
        (xy 0.804 2.882)
        (xy 0.82 2.867)
        (xy 0.835 2.854)
        (xy 0.85 2.845)
        (xy 0.867 2.838)
        (xy 0.887 2.833)
        (xy 0.912 2.829)
        (xy 0.943 2.827)
        (xy 0.982 2.826)
        (xy 1.015 2.825)
        (xy 1.133 2.823)
        (xy 1.132 2.771)
        (xy 1.131 2.746)
        (xy 1.129 2.73)
        (xy 1.127 2.719)
        (xy 1.123 2.711)
        (xy 1.117 2.705)
        (xy 1.098 2.691)
        (xy 1.07 2.682)
        (xy 1.032 2.677)
        (xy 1.006 2.677)
        (xy 0.972 2.678)
        (xy 0.945 2.682)
        (xy 0.924 2.688)
        (xy 0.907 2.699)
        (xy 0.9 2.706)
        (xy 0.882 2.723)
        (xy 0.834 2.686)
        (xy 0.816 2.672)
        (xy 0.801 2.66)
        (xy 0.79 2.652)
        (xy 0.787 2.648)
        (xy 0.791 2.639)
        (xy 0.801 2.626)
        (xy 0.816 2.612)
        (xy 0.832 2.6)
        (xy 0.864 2.581)
        (xy 0.902 2.568)
        (xy 0.946 2.559)
        (xy 0.98 2.556)
        (xy 1.038 2.556)
      )

      (stroke (width 0.01) (type solid)) (fill solid) (layer "F.Cu"))
    (fp_poly
      (pts
        (xy -1.521 2.559)
        (xy -1.485 2.562)
        (xy -1.454 2.568)
        (xy -1.427 2.577)
        (xy -1.401 2.589)
        (xy -1.371 2.61)
        (xy -1.345 2.639)
        (xy -1.325 2.67)
        (xy -1.321 2.679)
        (xy -1.309 2.71)
        (xy -1.309 3.197)
        (xy -1.433 3.2)
        (xy -1.433 3.172)
        (xy -1.434 3.157)
        (xy -1.435 3.147)
        (xy -1.436 3.144)
        (xy -1.44 3.147)
        (xy -1.449 3.156)
        (xy -1.453 3.161)
        (xy -1.472 3.178)
        (xy -1.496 3.19)
        (xy -1.526 3.198)
        (xy -1.563 3.202)
        (xy -1.578 3.203)
        (xy -1.603 3.203)
        (xy -1.627 3.203)
        (xy -1.647 3.201)
        (xy -1.656 3.2)
        (xy -1.686 3.191)
        (xy -1.717 3.176)
        (xy -1.746 3.159)
        (xy -1.765 3.143)
        (xy -1.79 3.111)
        (xy -1.807 3.075)
        (xy -1.816 3.037)
        (xy -1.817 2.998)
        (xy -1.817 2.997)
        (xy -1.697 2.997)
        (xy -1.696 3.02)
        (xy -1.687 3.042)
        (xy -1.67 3.06)
        (xy -1.668 3.062)
        (xy -1.654 3.07)
        (xy -1.64 3.076)
        (xy -1.624 3.08)
        (xy -1.602 3.081)
        (xy -1.574 3.082)
        (xy -1.558 3.082)
        (xy -1.529 3.081)
        (xy -1.508 3.08)
        (xy -1.494 3.078)
        (xy -1.483 3.075)
        (xy -1.474 3.07)
        (xy -1.458 3.058)
        (xy -1.447 3.041)
        (xy -1.44 3.017)
        (xy -1.435 2.985)
        (xy -1.435 2.977)
        (xy -1.432 2.931)
        (xy -1.533 2.931)
        (xy -1.568 2.931)
        (xy -1.595 2.931)
        (xy -1.615 2.932)
        (xy -1.63 2.934)
        (xy -1.641 2.936)
        (xy -1.65 2.938)
        (xy -1.655 2.941)
        (xy -1.676 2.955)
        (xy -1.69 2.974)
        (xy -1.697 2.997)
        (xy -1.817 2.997)
        (xy -1.811 2.96)
        (xy -1.797 2.924)
        (xy -1.775 2.892)
        (xy -1.747 2.864)
        (xy -1.715 2.845)
        (xy -1.7 2.838)
        (xy -1.685 2.833)
        (xy -1.668 2.83)
        (xy -1.648 2.827)
        (xy -1.623 2.825)
        (xy -1.591 2.824)
        (xy -1.551 2.824)
        (xy -1.54 2.824)
        (xy -1.432 2.824)
        (xy -1.434 2.776)
        (xy -1.436 2.747)
        (xy -1.441 2.726)
        (xy -1.448 2.711)
        (xy -1.46 2.699)
        (xy -1.474 2.689)
        (xy -1.483 2.685)
        (xy -1.492 2.682)
        (xy -1.505 2.68)
        (xy -1.524 2.68)
        (xy -1.55 2.679)
        (xy -1.56 2.679)
        (xy -1.594 2.68)
        (xy -1.62 2.682)
        (xy -1.639 2.686)
        (xy -1.654 2.692)
        (xy -1.666 2.701)
        (xy -1.675 2.711)
        (xy -1.686 2.724)
        (xy -1.735 2.686)
        (xy -1.754 2.672)
        (xy -1.769 2.659)
        (xy -1.78 2.65)
        (xy -1.784 2.646)
        (xy -1.78 2.64)
        (xy -1.77 2.629)
        (xy -1.756 2.616)
        (xy -1.74 2.604)
        (xy -1.724 2.592)
        (xy -1.711 2.584)
        (xy -1.71 2.583)
        (xy -1.688 2.574)
        (xy -1.668 2.566)
        (xy -1.647 2.562)
        (xy -1.623 2.559)
        (xy -1.593 2.558)
        (xy -1.565 2.558)
        (xy -1.521 2.559)
      )

      (stroke (width 0.01) (type solid)) (fill solid) (layer "F.Cu"))
    (fp_poly
      (pts
        (xy 0.035 2.777)
        (xy 0.047 2.822)
        (xy 0.059 2.864)
        (xy 0.069 2.903)
        (xy 0.078 2.936)
        (xy 0.086 2.963)
        (xy 0.092 2.984)
        (xy 0.095 2.996)
        (xy 0.096 2.999)
        (xy 0.098 2.999)
        (xy 0.103 2.991)
        (xy 0.109 2.975)
        (xy 0.118 2.95)
        (xy 0.129 2.917)
        (xy 0.143 2.874)
        (xy 0.152 2.849)
        (xy 0.165 2.807)
        (xy 0.179 2.766)
        (xy 0.192 2.726)
        (xy 0.204 2.689)
        (xy 0.214 2.658)
        (xy 0.221 2.634)
        (xy 0.224 2.627)
        (xy 0.244 2.565)
        (xy 0.338 2.565)
        (xy 0.406 2.774)
        (xy 0.42 2.819)
        (xy 0.434 2.861)
        (xy 0.446 2.899)
        (xy 0.457 2.932)
        (xy 0.466 2.96)
        (xy 0.473 2.981)
        (xy 0.477 2.993)
        (xy 0.478 2.997)
        (xy 0.48 2.998)
        (xy 0.482 2.996)
        (xy 0.485 2.99)
        (xy 0.49 2.978)
        (xy 0.495 2.96)
        (xy 0.502 2.936)
        (xy 0.511 2.905)
        (xy 0.523 2.865)
        (xy 0.536 2.817)
        (xy 0.543 2.789)
        (xy 0.556 2.744)
        (xy 0.568 2.701)
        (xy 0.578 2.663)
        (xy 0.587 2.629)
        (xy 0.595 2.602)
        (xy 0.601 2.582)
        (xy 0.605 2.57)
        (xy 0.606 2.567)
        (xy 0.611 2.566)
        (xy 0.625 2.566)
        (xy 0.645 2.566)
        (xy 0.669 2.566)
        (xy 0.673 2.566)
        (xy 0.739 2.567)
        (xy 0.656 2.827)
        (xy 0.64 2.878)
        (xy 0.624 2.928)
        (xy 0.609 2.976)
        (xy 0.595 3.02)
        (xy 0.582 3.06)
        (xy 0.571 3.094)
        (xy 0.563 3.121)
        (xy 0.557 3.139)
        (xy 0.556 3.143)
        (xy 0.538 3.2)
        (xy 0.425 3.197)
        (xy 0.358 2.975)
        (xy 0.341 2.917)
        (xy 0.327 2.87)
        (xy 0.315 2.831)
        (xy 0.305 2.801)
        (xy 0.297 2.78)
        (xy 0.292 2.766)
        (xy 0.289 2.761)
        (xy 0.288 2.761)
        (xy 0.286 2.768)
        (xy 0.281 2.783)
        (xy 0.274 2.806)
        (xy 0.265 2.836)
        (xy 0.254 2.871)
        (xy 0.242 2.911)
        (xy 0.23 2.953)
        (xy 0.223 2.976)
        (xy 0.21 3.02)
        (xy 0.197 3.062)
        (xy 0.186 3.099)
        (xy 0.177 3.132)
        (xy 0.169 3.158)
        (xy 0.163 3.177)
        (xy 0.16 3.189)
        (xy 0.159 3.191)
        (xy 0.157 3.195)
        (xy 0.151 3.198)
        (xy 0.141 3.199)
        (xy 0.124 3.2)
        (xy 0.101 3.2)
        (xy 0.073 3.199)
        (xy 0.055 3.198)
        (xy 0.045 3.196)
        (xy 0.043 3.194)
        (xy 0.041 3.188)
        (xy 0.036 3.173)
        (xy 0.029 3.15)
        (xy 0.019 3.121)
        (xy 0.008 3.084)
        (xy -0.006 3.043)
        (xy -0.02 2.996)
        (xy -0.036 2.946)
        (xy -0.053 2.893)
        (xy -0.057 2.883)
        (xy -0.074 2.83)
        (xy -0.09 2.779)
        (xy -0.105 2.732)
        (xy -0.119 2.689)
        (xy -0.131 2.652)
        (xy -0.141 2.621)
        (xy -0.148 2.596)
        (xy -0.154 2.58)
        (xy -0.156 2.572)
        (xy -0.156 2.569)
        (xy -0.151 2.567)
        (xy -0.14 2.566)
        (xy -0.123 2.565)
        (xy -0.096 2.565)
        (xy -0.091 2.565)
        (xy -0.023 2.565)
        (xy 0.035 2.777)
      )

      (stroke (width 0.01) (type solid)) (fill solid) (layer "F.Cu"))
    (fp_poly
      (pts
        (xy -2.065 1.559)
        (xy -2.024 1.576)
        (xy -1.986 1.601)
        (xy -1.973 1.612)
        (xy -1.957 1.63)
        (xy -1.943 1.649)
        (xy -1.932 1.668)
        (xy -1.924 1.69)
        (xy -1.918 1.716)
        (xy -1.914 1.747)
        (xy -1.911 1.785)
        (xy -1.91 1.831)
        (xy -1.91 1.877)
        (xy -1.91 1.93)
        (xy -1.912 1.974)
        (xy -1.914 2.011)
        (xy -1.919 2.041)
        (xy -1.925 2.067)
        (xy -1.934 2.088)
        (xy -1.945 2.107)
        (xy -1.959 2.125)
        (xy -1.972 2.139)
        (xy -1.993 2.157)
        (xy -2.018 2.173)
        (xy -2.031 2.18)
        (xy -2.047 2.188)
        (xy -2.06 2.192)
        (xy -2.074 2.195)
        (xy -2.091 2.196)
        (xy -2.114 2.197)
        (xy -2.122 2.197)
        (xy -2.147 2.196)
        (xy -2.165 2.195)
        (xy -2.179 2.193)
        (xy -2.191 2.189)
        (xy -2.205 2.183)
        (xy -2.21 2.18)
        (xy -2.231 2.169)
        (xy -2.251 2.156)
        (xy -2.265 2.146)
        (xy -2.286 2.127)
        (xy -2.286 2.627)
        (xy -2.266 2.608)
        (xy -2.248 2.595)
        (xy -2.227 2.582)
        (xy -2.217 2.577)
        (xy -2.173 2.562)
        (xy -2.129 2.556)
        (xy -2.086 2.559)
        (xy -2.045 2.57)
        (xy -2.007 2.589)
        (xy -1.974 2.616)
        (xy -1.946 2.648)
        (xy -1.926 2.687)
        (xy -1.919 2.707)
        (xy -1.917 2.715)
        (xy -1.915 2.724)
        (xy -1.914 2.737)
        (xy -1.913 2.753)
        (xy -1.912 2.774)
        (xy -1.911 2.8)
        (xy -1.911 2.833)
        (xy -1.911 2.874)
        (xy -1.911 2.923)
        (xy -1.911 2.967)
        (xy -1.911 3.2)
        (xy -2.035 3.197)
        (xy -2.038 2.984)
        (xy -2.038 2.932)
        (xy -2.039 2.889)
        (xy -2.039 2.854)
        (xy -2.04 2.826)
        (xy -2.041 2.805)
        (xy -2.042 2.788)
        (xy -2.043 2.776)
        (xy -2.045 2.767)
        (xy -2.046 2.76)
        (xy -2.049 2.755)
        (xy -2.051 2.75)
        (xy -2.072 2.721)
        (xy -2.098 2.701)
        (xy -2.128 2.688)
        (xy -2.161 2.683)
        (xy -2.195 2.687)
        (xy -2.22 2.697)
        (xy -2.24 2.71)
        (xy -2.259 2.729)
        (xy -2.274 2.75)
        (xy -2.278 2.757)
        (xy -2.28 2.765)
        (xy -2.281 2.781)
        (xy -2.283 2.806)
        (xy -2.284 2.839)
        (xy -2.285 2.881)
        (xy -2.286 2.933)
        (xy -2.286 2.984)
        (xy -2.289 3.197)
        (xy -2.413 3.2)
        (xy -2.413 1.877)
        (xy -2.286 1.877)
        (xy -2.285 1.926)
        (xy -2.281 1.966)
        (xy -2.274 1.998)
        (xy -2.262 2.024)
        (xy -2.247 2.043)
        (xy -2.228 2.058)
        (xy -2.215 2.064)
        (xy -2.194 2.07)
        (xy -2.168 2.072)
        (xy -2.141 2.071)
        (xy -2.117 2.066)
        (xy -2.106 2.063)
        (xy -2.079 2.044)
        (xy -2.058 2.019)
        (xy -2.05 2.001)
        (xy -2.045 1.984)
        (xy -2.042 1.959)
        (xy -2.04 1.929)
        (xy -2.038 1.895)
        (xy -2.038 1.861)
        (xy -2.039 1.829)
        (xy -2.041 1.8)
        (xy -2.044 1.777)
        (xy -2.045 1.772)
        (xy -2.057 1.738)
        (xy -2.073 1.712)
        (xy -2.094 1.695)
        (xy -2.122 1.684)
        (xy -2.156 1.681)
        (xy -2.159 1.681)
        (xy -2.192 1.683)
        (xy -2.22 1.691)
        (xy -2.243 1.705)
        (xy -2.26 1.725)
        (xy -2.273 1.753)
        (xy -2.281 1.788)
        (xy -2.285 1.832)
        (xy -2.286 1.877)
        (xy -2.413 1.877)
        (xy -2.413 1.559)
        (xy -2.286 1.559)
        (xy -2.286 1.62)
        (xy -2.26 1.6)
        (xy -2.225 1.577)
        (xy -2.19 1.563)
        (xy -2.154 1.554)
        (xy -2.109 1.552)
        (xy -2.065 1.559)
      )

      (stroke (width 0.01) (type solid)) (fill solid) (layer "F.Cu"))
    (fp_poly
      (pts
        (xy 0.063 -3.201)
        (xy 0.118 -3.201)
        (xy 0.164 -3.201)
        (xy 0.202 -3.2)
        (xy 0.233 -3.2)
        (xy 0.258 -3.2)
        (xy 0.277 -3.199)
        (xy 0.292 -3.198)
        (xy 0.302 -3.197)
        (xy 0.309 -3.196)
        (xy 0.314 -3.195)
        (xy 0.317 -3.193)
        (xy 0.319 -3.192)
        (xy 0.321 -3.189)
        (xy 0.324 -3.183)
        (xy 0.327 -3.174)
        (xy 0.33 -3.161)
        (xy 0.334 -3.144)
        (xy 0.339 -3.12)
        (xy 0.345 -3.091)
        (xy 0.352 -3.054)
        (xy 0.361 -3.01)
        (xy 0.371 -2.958)
        (xy 0.382 -2.897)
        (xy 0.385 -2.878)
        (xy 0.395 -2.824)
        (xy 0.405 -2.772)
        (xy 0.414 -2.724)
        (xy 0.423 -2.68)
        (xy 0.43 -2.642)
        (xy 0.437 -2.61)
        (xy 0.442 -2.586)
        (xy 0.446 -2.569)
        (xy 0.448 -2.562)
        (xy 0.456 -2.55)
        (xy 0.464 -2.544)
        (xy 0.476 -2.539)
        (xy 0.495 -2.53)
        (xy 0.521 -2.519)
        (xy 0.552 -2.506)
        (xy 0.587 -2.492)
        (xy 0.624 -2.477)
        (xy 0.664 -2.461)
        (xy 0.704 -2.445)
        (xy 0.743 -2.43)
        (xy 0.78 -2.415)
        (xy 0.814 -2.402)
        (xy 0.843 -2.391)
        (xy 0.868 -2.382)
        (xy 0.885 -2.376)
        (xy 0.895 -2.373)
        (xy 0.896 -2.373)
        (xy 0.911 -2.376)
        (xy 0.931 -2.386)
        (xy 0.948 -2.397)
        (xy 0.962 -2.406)
        (xy 0.983 -2.421)
        (xy 1.011 -2.44)
        (xy 1.043 -2.462)
        (xy 1.079 -2.487)
        (xy 1.118 -2.513)
        (xy 1.158 -2.541)
        (xy 1.198 -2.568)
        (xy 1.238 -2.595)
        (xy 1.275 -2.621)
        (xy 1.309 -2.644)
        (xy 1.338 -2.665)
        (xy 1.362 -2.681)
        (xy 1.377 -2.691)
        (xy 1.398 -2.705)
        (xy 1.418 -2.717)
        (xy 1.433 -2.725)
        (xy 1.442 -2.728)
        (xy 1.443 -2.728)
        (xy 1.448 -2.726)
        (xy 1.456 -2.72)
        (xy 1.468 -2.71)
        (xy 1.486 -2.694)
        (xy 1.508 -2.673)
        (xy 1.535 -2.647)
        (xy 1.568 -2.614)
        (xy 1.608 -2.575)
        (xy 1.654 -2.53)
        (xy 1.675 -2.509)
        (xy 1.721 -2.462)
        (xy 1.761 -2.422)
        (xy 1.794 -2.388)
        (xy 1.822 -2.36)
        (xy 1.844 -2.337)
        (xy 1.862 -2.318)
        (xy 1.875 -2.304)
        (xy 1.884 -2.293)
        (xy 1.89 -2.284)
        (xy 1.893 -2.279)
        (xy 1.894 -2.275)
        (xy 1.892 -2.269)
        (xy 1.886 -2.257)
        (xy 1.875 -2.239)
        (xy 1.86 -2.215)
        (xy 1.839 -2.183)
        (xy 1.814 -2.145)
        (xy 1.783 -2.1)
        (xy 1.747 -2.046)
        (xy 1.721 -2.009)
        (xy 1.69 -1.964)
        (xy 1.661 -1.921)
        (xy 1.634 -1.88)
        (xy 1.609 -1.844)
        (xy 1.588 -1.811)
        (xy 1.57 -1.785)
        (xy 1.557 -1.764)
        (xy 1.549 -1.75)
        (xy 1.546 -1.743)
        (xy 1.547 -1.735)
        (xy 1.552 -1.719)
        (xy 1.56 -1.696)
        (xy 1.571 -1.667)
        (xy 1.585 -1.634)
        (xy 1.6 -1.597)
        (xy 1.616 -1.557)
        (xy 1.633 -1.516)
        (xy 1.651 -1.476)
        (xy 1.668 -1.436)
        (xy 1.685 -1.398)
        (xy 1.701 -1.363)
        (xy 1.715 -1.333)
        (xy 1.727 -1.309)
        (xy 1.736 -1.291)
        (xy 1.742 -1.281)
        (xy 1.744 -1.279)
        (xy 1.751 -1.277)
        (xy 1.767 -1.273)
        (xy 1.791 -1.268)
        (xy 1.822 -1.261)
        (xy 1.86 -1.254)
        (xy 1.903 -1.245)
        (xy 1.951 -1.236)
        (xy 2.002 -1.226)
        (xy 2.049 -1.217)
        (xy 2.103 -1.207)
        (xy 2.154 -1.198)
        (xy 2.201 -1.188)
        (xy 2.244 -1.18)
        (xy 2.281 -1.173)
        (xy 2.311 -1.166)
        (xy 2.335 -1.161)
        (xy 2.35 -1.157)
        (xy 2.355 -1.156)
        (xy 2.367 -1.148)
        (xy 2.367 -0.834)
        (xy 2.367 -0.768)
        (xy 2.367 -0.712)
        (xy 2.367 -0.664)
        (xy 2.366 -0.625)
        (xy 2.366 -0.592)
        (xy 2.365 -0.566)
        (xy 2.364 -0.546)
        (xy 2.363 -0.531)
        (xy 2.361 -0.52)
        (xy 2.358 -0.512)
        (xy 2.355 -0.507)
        (xy 2.352 -0.504)
        (xy 2.348 -0.503)
        (xy 2.343 -0.501)
        (xy 2.34 -0.501)
        (xy 2.333 -0.499)
        (xy 2.317 -0.496)
        (xy 2.293 -0.492)
        (xy 2.261 -0.486)
        (xy 2.224 -0.479)
        (xy 2.181 -0.471)
        (xy 2.134 -0.462)
        (xy 2.084 -0.453)
        (xy 2.054 -0.448)
        (xy 2.002 -0.438)
        (xy 1.953 -0.429)
        (xy 1.907 -0.42)
        (xy 1.866 -0.412)
        (xy 1.831 -0.404)
        (xy 1.802 -0.398)
        (xy 1.78 -0.394)
        (xy 1.767 -0.391)
        (xy 1.764 -0.39)
        (xy 1.76 -0.387)
        (xy 1.757 -0.384)
        (xy 1.753 -0.379)
        (xy 1.748 -0.371)
        (xy 1.742 -0.36)
        (xy 1.735 -0.344)
        (xy 1.726 -0.324)
        (xy 1.715 -0.297)
        (xy 1.701 -0.264)
        (xy 1.685 -0.223)
        (xy 1.665 -0.174)
        (xy 1.653 -0.145)
        (xy 1.63 -0.086)
        (xy 1.61 -0.037)
        (xy 1.594 0.005)
        (xy 1.582 0.038)
        (xy 1.572 0.064)
        (xy 1.566 0.084)
        (xy 1.562 0.097)
        (xy 1.561 0.104)
        (xy 1.562 0.105)
        (xy 1.565 0.111)
        (xy 1.574 0.125)
        (xy 1.587 0.146)
        (xy 1.604 0.173)
        (xy 1.626 0.205)
        (xy 1.65 0.241)
        (xy 1.677 0.281)
        (xy 1.706 0.324)
        (xy 1.729 0.358)
        (xy 1.768 0.413)
        (xy 1.8 0.461)
        (xy 1.827 0.502)
        (xy 1.85 0.535)
        (xy 1.867 0.562)
        (xy 1.88 0.583)
        (xy 1.889 0.598)
        (xy 1.893 0.608)
        (xy 1.894 0.612)
        (xy 1.893 0.616)
        (xy 1.89 0.622)
        (xy 1.885 0.63)
        (xy 1.876 0.64)
        (xy 1.863 0.655)
        (xy 1.846 0.673)
        (xy 1.825 0.695)
        (xy 1.798 0.723)
        (xy 1.765 0.756)
        (xy 1.727 0.795)
        (xy 1.682 0.839)
        (xy 1.635 0.886)
        (xy 1.595 0.926)
        (xy 1.561 0.96)
        (xy 1.532 0.989)
        (xy 1.508 1.012)
        (xy 1.488 1.03)
        (xy 1.473 1.044)
        (xy 1.461 1.054)
        (xy 1.452 1.061)
        (xy 1.445 1.065)
        (xy 1.44 1.066)
        (xy 1.438 1.066)
        (xy 1.433 1.064)
        (xy 1.421 1.055)
        (xy 1.401 1.043)
        (xy 1.376 1.026)
        (xy 1.345 1.005)
        (xy 1.31 0.981)
        (xy 1.27 0.954)
        (xy 1.228 0.925)
        (xy 1.193 0.901)
        (xy 1.138 0.864)
        (xy 1.089 0.83)
        (xy 1.046 0.802)
        (xy 1.01 0.778)
        (xy 0.981 0.759)
        (xy 0.96 0.746)
        (xy 0.946 0.738)
        (xy 0.94 0.736)
        (xy 0.932 0.738)
        (xy 0.917 0.745)
        (xy 0.895 0.755)
        (xy 0.869 0.768)
        (xy 0.84 0.783)
        (xy 0.816 0.795)
        (xy 0.781 0.814)
        (xy 0.753 0.828)
        (xy 0.732 0.838)
        (xy 0.717 0.845)
        (xy 0.707 0.849)
        (xy 0.699 0.85)
        (xy 0.694 0.849)
        (xy 0.691 0.847)
        (xy 0.687 0.84)
        (xy 0.682 0.829)
        (xy 0.674 0.814)
        (xy 0.665 0.793)
        (xy 0.653 0.767)
        (xy 0.639 0.735)
        (xy 0.623 0.696)
        (xy 0.604 0.651)
        (xy 0.582 0.598)
        (xy 0.556 0.538)
        (xy 0.528 0.469)
        (xy 0.496 0.391)
        (xy 0.47 0.329)
        (xy 0.436 0.247)
        (xy 0.406 0.173)
        (xy 0.379 0.108)
        (xy 0.355 0.05)
        (xy 0.335 0)
        (xy 0.317 -0.043)
        (xy 0.303 -0.079)
        (xy 0.291 -0.11)
        (xy 0.281 -0.135)
        (xy 0.273 -0.155)
        (xy 0.268 -0.171)
        (xy 0.264 -0.183)
        (xy 0.262 -0.191)
        (xy 0.262 -0.196)
        (xy 0.262 -0.198)
        (xy 0.269 -0.207)
        (xy 0.283 -0.219)
        (xy 0.302 -0.233)
        (xy 0.303 -0.234)
        (xy 0.354 -0.268)
        (xy 0.398 -0.3)
        (xy 0.435 -0.331)
        (xy 0.469 -0.363)
        (xy 0.5 -0.397)
        (xy 0.507 -0.405)
        (xy 0.556 -0.472)
        (xy 0.596 -0.543)
        (xy 0.627 -0.619)
        (xy 0.643 -0.672)
        (xy 0.651 -0.718)
        (xy 0.657 -0.77)
        (xy 0.66 -0.824)
        (xy 0.659 -0.878)
        (xy 0.654 -0.927)
        (xy 0.652 -0.936)
        (xy 0.634 -1.015)
        (xy 0.607 -1.09)
        (xy 0.571 -1.161)
        (xy 0.528 -1.227)
        (xy 0.477 -1.287)
        (xy 0.419 -1.341)
        (xy 0.355 -1.387)
        (xy 0.285 -1.426)
        (xy 0.21 -1.456)
        (xy 0.205 -1.458)
        (xy 0.131 -1.477)
        (xy 0.054 -1.487)
        (xy -0.025 -1.489)
        (xy -0.103 -1.482)
        (xy -0.178 -1.466)
        (xy -0.206 -1.458)
        (xy -0.281 -1.428)
        (xy -0.351 -1.39)
        (xy -0.416 -1.344)
        (xy -0.474 -1.29)
        (xy -0.526 -1.23)
        (xy -0.571 -1.164)
        (xy -0.607 -1.093)
        (xy -0.63 -1.034)
        (xy -0.649 -0.96)
        (xy -0.659 -0.883)
        (xy -0.661 -0.804)
        (xy -0.654 -0.726)
        (xy -0.638 -0.651)
        (xy -0.63 -0.623)
        (xy -0.618 -0.591)
        (xy -0.602 -0.554)
        (xy -0.584 -0.518)
        (xy -0.566 -0.485)
        (xy -0.553 -0.463)
        (xy -0.509 -0.407)
        (xy -0.457 -0.352)
        (xy -0.397 -0.299)
        (xy -0.33 -0.25)
        (xy -0.289 -0.224)
        (xy -0.273 -0.212)
        (xy -0.263 -0.2)
        (xy -0.262 -0.197)
        (xy -0.263 -0.19)
        (xy -0.268 -0.175)
        (xy -0.277 -0.151)
        (xy -0.288 -0.121)
        (xy -0.302 -0.084)
        (xy -0.319 -0.042)
        (xy -0.338 0.005)
        (xy -0.358 0.056)
        (xy -0.381 0.111)
        (xy -0.404 0.168)
        (xy -0.428 0.228)
        (xy -0.453 0.288)
        (xy -0.478 0.349)
        (xy -0.504 0.41)
        (xy -0.529 0.47)
        (xy -0.553 0.527)
        (xy -0.576 0.583)
        (xy -0.598 0.635)
        (xy -0.619 0.683)
        (xy -0.638 0.727)
        (xy -0.655 0.765)
        (xy -0.669 0.797)
        (xy -0.68 0.822)
        (xy -0.689 0.839)
        (xy -0.694 0.848)
        (xy -0.695 0.849)
        (xy -0.699 0.85)
        (xy -0.706 0.849)
        (xy -0.717 0.845)
        (xy -0.732 0.839)
        (xy -0.752 0.829)
        (xy -0.779 0.815)
        (xy -0.814 0.797)
        (xy -0.817 0.795)
        (xy -0.848 0.779)
        (xy -0.877 0.764)
        (xy -0.902 0.752)
        (xy -0.922 0.743)
        (xy -0.936 0.737)
        (xy -0.941 0.736)
        (xy -0.949 0.739)
        (xy -0.964 0.748)
        (xy -0.987 0.761)
        (xy -1.015 0.78)
        (xy -1.05 0.803)
        (xy -1.072 0.818)
        (xy -1.138 0.863)
        (xy -1.195 0.903)
        (xy -1.245 0.937)
        (xy -1.289 0.966)
        (xy -1.325 0.991)
        (xy -1.356 1.012)
        (xy -1.381 1.029)
        (xy -1.401 1.042)
        (xy -1.416 1.052)
        (xy -1.427 1.059)
        (xy -1.435 1.064)
        (xy -1.439 1.066)
        (xy -1.44 1.066)
        (xy -1.449 1.064)
        (xy -1.453 1.061)
        (xy -1.458 1.057)
        (xy -1.47 1.046)
        (xy -1.487 1.029)
        (xy -1.509 1.007)
        (xy -1.537 0.98)
        (xy -1.568 0.95)
        (xy -1.602 0.915)
        (xy -1.639 0.879)
        (xy -1.678 0.84)
        (xy -1.678 0.839)
        (xy -1.726 0.792)
        (xy -1.767 0.751)
        (xy -1.801 0.716)
        (xy -1.829 0.687)
        (xy -1.852 0.663)
        (xy -1.869 0.644)
        (xy -1.882 0.63)
        (xy -1.89 0.62)
        (xy -1.894 0.613)
        (xy -1.895 0.61)
        (xy -1.892 0.603)
        (xy -1.884 0.588)
        (xy -1.87 0.565)
        (xy -1.85 0.536)
        (xy -1.826 0.499)
        (xy -1.797 0.455)
        (xy -1.763 0.405)
        (xy -1.73 0.358)
        (xy -1.7 0.313)
        (xy -1.671 0.271)
        (xy -1.645 0.232)
        (xy -1.621 0.197)
        (xy -1.601 0.166)
        (xy -1.584 0.141)
        (xy -1.572 0.121)
        (xy -1.565 0.109)
        (xy -1.563 0.105)
        (xy -1.563 0.099)
        (xy -1.566 0.087)
        (xy -1.572 0.07)
        (xy -1.58 0.045)
        (xy -1.592 0.013)
        (xy -1.607 -0.026)
        (xy -1.626 -0.074)
        (xy -1.648 -0.13)
        (xy -1.654 -0.145)
        (xy -1.676 -0.199)
        (xy -1.695 -0.245)
        (xy -1.71 -0.282)
        (xy -1.723 -0.313)
        (xy -1.733 -0.337)
        (xy -1.741 -0.356)
        (xy -1.748 -0.369)
        (xy -1.753 -0.379)
        (xy -1.758 -0.385)
        (xy -1.761 -0.388)
        (xy -1.763 -0.389)
        (xy -1.767 -0.39)
        (xy -1.774 -0.392)
        (xy -1.784 -0.395)
        (xy -1.799 -0.398)
        (xy -1.818 -0.402)
        (xy -1.843 -0.407)
        (xy -1.873 -0.413)
        (xy -1.91 -0.42)
        (xy -1.954 -0.429)
        (xy -2.005 -0.438)
        (xy -2.065 -0.449)
        (xy -2.133 -0.462)
        (xy -2.211 -0.477)
        (xy -2.22 -0.478)
        (xy -2.26 -0.486)
        (xy -2.29 -0.491)
        (xy -2.313 -0.496)
        (xy -2.33 -0.499)
        (xy -2.341 -0.502)
        (xy -2.349 -0.504)
        (xy -2.353 -0.506)
        (xy -2.356 -0.508)
        (xy -2.359 -0.51)
        (xy -2.36 -0.511)
        (xy -2.361 -0.514)
        (xy -2.363 -0.518)
        (xy -2.364 -0.526)
        (xy -2.365 -0.536)
        (xy -2.366 -0.551)
        (xy -2.366 -0.571)
        (xy -2.367 -0.597)
        (xy -2.367 -0.629)
        (xy -2.368 -0.668)
        (xy -2.368 -0.715)
        (xy -2.368 -0.771)
        (xy -2.368 -0.834)
        (xy -2.368 -1.148)
        (xy -2.356 -1.155)
        (xy -2.349 -1.158)
        (xy -2.333 -1.162)
        (xy -2.309 -1.167)
        (xy -2.278 -1.173)
        (xy -2.24 -1.181)
        (xy -2.197 -1.189)
        (xy -2.149 -1.198)
        (xy -2.098 -1.208)
        (xy -2.051 -1.217)
        (xy -1.996 -1.227)
        (xy -1.945 -1.237)
        (xy -1.897 -1.246)
        (xy -1.854 -1.254)
        (xy -1.817 -1.262)
        (xy -1.787 -1.268)
        (xy -1.764 -1.273)
        (xy -1.75 -1.277)
        (xy -1.745 -1.279)
        (xy -1.741 -1.285)
        (xy -1.733 -1.3)
        (xy -1.722 -1.322)
        (xy -1.709 -1.35)
        (xy -1.694 -1.382)
        (xy -1.677 -1.419)
        (xy -1.66 -1.458)
        (xy -1.642 -1.498)
        (xy -1.625 -1.539)
        (xy -1.608 -1.58)
        (xy -1.592 -1.618)
        (xy -1.578 -1.653)
        (xy -1.565 -1.684)
        (xy -1.556 -1.709)
        (xy -1.549 -1.729)
        (xy -1.546 -1.74)
        (xy -1.546 -1.742)
        (xy -1.549 -1.749)
        (xy -1.558 -1.763)
        (xy -1.571 -1.784)
        (xy -1.588 -1.811)
        (xy -1.61 -1.843)
        (xy -1.634 -1.88)
        (xy -1.661 -1.92)
        (xy -1.691 -1.963)
        (xy -1.722 -2.008)
        (xy -1.762 -2.067)
        (xy -1.796 -2.117)
        (xy -1.825 -2.16)
        (xy -1.848 -2.196)
        (xy -1.867 -2.225)
        (xy -1.881 -2.247)
        (xy -1.89 -2.262)
        (xy -1.895 -2.272)
        (xy -1.895 -2.275)
        (xy -1.894 -2.279)
        (xy -1.891 -2.285)
        (xy -1.884 -2.293)
        (xy -1.875 -2.305)
        (xy -1.861 -2.32)
        (xy -1.843 -2.339)
        (xy -1.82 -2.363)
        (xy -1.792 -2.392)
        (xy -1.758 -2.426)
        (xy -1.718 -2.466)
        (xy -1.676 -2.509)
        (xy -1.627 -2.557)
        (xy -1.585 -2.599)
        (xy -1.549 -2.634)
        (xy -1.52 -2.663)
        (xy -1.495 -2.686)
        (xy -1.476 -2.704)
        (xy -1.462 -2.716)
        (xy -1.452 -2.724)
        (xy -1.446 -2.728)
        (xy -1.444 -2.728)
        (xy -1.437 -2.726)
        (xy -1.423 -2.717)
        (xy -1.401 -2.703)
        (xy -1.372 -2.685)
        (xy -1.337 -2.661)
        (xy -1.295 -2.634)
        (xy -1.248 -2.602)
        (xy -1.196 -2.566)
        (xy -1.173 -2.551)
        (xy -1.118 -2.513)
        (xy -1.071 -2.481)
        (xy -1.031 -2.454)
        (xy -0.998 -2.432)
        (xy -0.97 -2.413)
        (xy -0.948 -2.399)
        (xy -0.931 -2.389)
        (xy -0.917 -2.381)
        (xy -0.907 -2.376)
        (xy -0.901 -2.373)
        (xy -0.897 -2.373)
        (xy -0.888 -2.375)
        (xy -0.87 -2.38)
        (xy -0.845 -2.39)
        (xy -0.813 -2.402)
        (xy -0.774 -2.417)
        (xy -0.73 -2.434)
        (xy -0.681 -2.454)
        (xy -0.629 -2.475)
        (xy -0.586 -2.493)
        (xy -0.55 -2.508)
        (xy -0.522 -2.52)
        (xy -0.499 -2.529)
        (xy -0.482 -2.537)
        (xy -0.47 -2.543)
        (xy -0.461 -2.548)
        (xy -0.455 -2.551)
        (xy -0.452 -2.554)
        (xy -0.449 -2.557)
        (xy -0.448 -2.56)
        (xy -0.447 -2.566)
        (xy -0.443 -2.582)
        (xy -0.438 -2.605)
        (xy -0.432 -2.637)
        (xy -0.425 -2.674)
        (xy -0.417 -2.717)
        (xy -0.407 -2.765)
        (xy -0.398 -2.817)
        (xy -0.388 -2.871)
        (xy -0.387 -2.876)
        (xy -0.375 -2.94)
        (xy -0.364 -2.995)
        (xy -0.356 -3.042)
        (xy -0.348 -3.081)
        (xy -0.342 -3.112)
        (xy -0.337 -3.137)
        (xy -0.332 -3.157)
        (xy -0.328 -3.171)
        (xy -0.325 -3.181)
        (xy -0.323 -3.188)
        (xy -0.32 -3.191)
        (xy -0.32 -3.192)
        (xy -0.317 -3.194)
        (xy -0.313 -3.195)
        (xy -0.307 -3.197)
        (xy -0.298 -3.198)
        (xy -0.286 -3.199)
        (xy -0.269 -3.199)
        (xy -0.247 -3.2)
        (xy -0.219 -3.2)
        (xy -0.184 -3.201)
        (xy -0.142 -3.201)
        (xy -0.092 -3.201)
        (xy -0.033 -3.201)
        (xy -0.001 -3.201)
        (xy 0.063 -3.201)
      )

      (stroke (width 0.01) (type solid)) (fill solid) (layer "F.Cu"))
    (fp_poly
      (pts
        (xy -0.843 2.558)
        (xy -0.815 2.564)
        (xy -0.794 2.572)
        (xy -0.773 2.581)
        (xy -0.759 2.589)
        (xy -0.738 2.603)
        (xy -0.783 2.658)
        (xy -0.8 2.677)
        (xy -0.814 2.694)
        (xy -0.825 2.706)
        (xy -0.831 2.712)
        (xy -0.832 2.712)
        (xy -0.837 2.71)
        (xy -0.847 2.703)
        (xy -0.849 2.702)
        (xy -0.874 2.69)
        (xy -0.904 2.684)
        (xy -0.935 2.685)
        (xy -0.942 2.686)
        (xy -0.975 2.698)
        (xy -1.001 2.717)
        (xy -1.02 2.741)
        (xy -1.034 2.766)
        (xy -1.039 3.197)
        (xy -1.164 3.2)
        (xy -1.164 2.565)
        (xy -1.037 2.565)
        (xy -1.037 2.626)
        (xy -1.009 2.604)
        (xy -0.972 2.579)
        (xy -0.931 2.563)
        (xy -0.887 2.556)
        (xy -0.843 2.558)
      )

      (stroke (width 0.01) (type solid)) (fill solid) (layer "F.Mask"))
    (fp_poly
      (pts
        (xy 1.889 1.554)
        (xy 1.907 1.559)
        (xy 1.927 1.566)
        (xy 1.948 1.574)
        (xy 1.966 1.583)
        (xy 1.979 1.592)
        (xy 1.984 1.597)
        (xy 1.982 1.604)
        (xy 1.974 1.616)
        (xy 1.962 1.633)
        (xy 1.946 1.652)
        (xy 1.945 1.654)
        (xy 1.929 1.673)
        (xy 1.915 1.689)
        (xy 1.906 1.7)
        (xy 1.901 1.706)
        (xy 1.896 1.705)
        (xy 1.885 1.7)
        (xy 1.873 1.695)
        (xy 1.84 1.683)
        (xy 1.808 1.68)
        (xy 1.776 1.685)
        (xy 1.747 1.698)
        (xy 1.723 1.717)
        (xy 1.704 1.742)
        (xy 1.696 1.763)
        (xy 1.695 1.772)
        (xy 1.694 1.79)
        (xy 1.693 1.817)
        (xy 1.692 1.85)
        (xy 1.692 1.89)
        (xy 1.691 1.934)
        (xy 1.691 1.983)
        (xy 1.691 2.194)
        (xy 1.559 2.194)
        (xy 1.559 1.559)
        (xy 1.691 1.559)
        (xy 1.691 1.626)
        (xy 1.71 1.607)
        (xy 1.739 1.585)
        (xy 1.775 1.568)
        (xy 1.814 1.556)
        (xy 1.855 1.552)
        (xy 1.889 1.554)
      )

      (stroke (width 0.01) (type solid)) (fill solid) (layer "F.Mask"))
    (fp_poly
      (pts
        (xy -0.837 1.56)
        (xy -0.797 1.576)
        (xy -0.761 1.6)
        (xy -0.73 1.63)
        (xy -0.706 1.667)
        (xy -0.69 1.709)
        (xy -0.687 1.721)
        (xy -0.685 1.734)
        (xy -0.684 1.757)
        (xy -0.683 1.79)
        (xy -0.682 1.833)
        (xy -0.681 1.884)
        (xy -0.681 1.945)
        (xy -0.681 1.971)
        (xy -0.681 2.194)
        (xy -0.808 2.194)
        (xy -0.809 1.984)
        (xy -0.811 1.774)
        (xy -0.826 1.744)
        (xy -0.845 1.716)
        (xy -0.868 1.697)
        (xy -0.897 1.686)
        (xy -0.925 1.682)
        (xy -0.947 1.682)
        (xy -0.967 1.684)
        (xy -0.979 1.686)
        (xy -1.001 1.698)
        (xy -1.023 1.716)
        (xy -1.041 1.738)
        (xy -1.049 1.752)
        (xy -1.052 1.758)
        (xy -1.054 1.765)
        (xy -1.056 1.773)
        (xy -1.057 1.783)
        (xy -1.058 1.797)
        (xy -1.059 1.815)
        (xy -1.06 1.839)
        (xy -1.06 1.869)
        (xy -1.061 1.907)
        (xy -1.061 1.953)
        (xy -1.061 1.985)
        (xy -1.063 2.194)
        (xy -1.189 2.194)
        (xy -1.189 1.559)
        (xy -1.062 1.559)
        (xy -1.062 1.625)
        (xy -1.033 1.602)
        (xy -1.001 1.579)
        (xy -0.969 1.564)
        (xy -0.934 1.555)
        (xy -0.927 1.554)
        (xy -0.881 1.553)
        (xy -0.837 1.56)
      )

      (stroke (width 0.01) (type solid)) (fill solid) (layer "F.Mask"))
    (fp_poly
      (pts
        (xy 1.042 1.769)
        (xy 1.043 1.979)
        (xy 1.059 2.009)
        (xy 1.077 2.036)
        (xy 1.1 2.056)
        (xy 1.129 2.067)
        (xy 1.159 2.071)
        (xy 1.193 2.07)
        (xy 1.221 2.063)
        (xy 1.245 2.047)
        (xy 1.258 2.034)
        (xy 1.266 2.025)
        (xy 1.273 2.016)
        (xy 1.278 2.008)
        (xy 1.282 1.997)
        (xy 1.286 1.985)
        (xy 1.288 1.969)
        (xy 1.29 1.948)
        (xy 1.291 1.922)
        (xy 1.292 1.89)
        (xy 1.293 1.85)
        (xy 1.293 1.801)
        (xy 1.294 1.766)
        (xy 1.295 1.559)
        (xy 1.422 1.559)
        (xy 1.422 2.194)
        (xy 1.295 2.194)
        (xy 1.295 2.161)
        (xy 1.295 2.144)
        (xy 1.293 2.132)
        (xy 1.292 2.128)
        (xy 1.287 2.131)
        (xy 1.278 2.14)
        (xy 1.271 2.147)
        (xy 1.256 2.159)
        (xy 1.236 2.171)
        (xy 1.219 2.181)
        (xy 1.202 2.188)
        (xy 1.186 2.193)
        (xy 1.17 2.196)
        (xy 1.148 2.197)
        (xy 1.135 2.198)
        (xy 1.107 2.198)
        (xy 1.087 2.197)
        (xy 1.07 2.194)
        (xy 1.059 2.19)
        (xy 1.036 2.181)
        (xy 1.019 2.172)
        (xy 1.003 2.161)
        (xy 0.985 2.146)
        (xy 0.981 2.141)
        (xy 0.952 2.107)
        (xy 0.931 2.068)
        (xy 0.92 2.033)
        (xy 0.918 2.019)
        (xy 0.917 1.996)
        (xy 0.916 1.963)
        (xy 0.915 1.92)
        (xy 0.914 1.869)
        (xy 0.914 1.808)
        (xy 0.914 1.782)
        (xy 0.914 1.559)
        (xy 1.04 1.559)
        (xy 1.042 1.769)
      )

      (stroke (width 0.01) (type solid)) (fill solid) (layer "F.Mask"))
    (fp_poly
      (pts
        (xy 1.753 2.563)
        (xy 1.768 2.568)
        (xy 1.787 2.577)
        (xy 1.804 2.586)
        (xy 1.818 2.595)
        (xy 1.826 2.602)
        (xy 1.827 2.606)
        (xy 1.824 2.611)
        (xy 1.815 2.621)
        (xy 1.803 2.636)
        (xy 1.789 2.654)
        (xy 1.775 2.671)
        (xy 1.761 2.688)
        (xy 1.749 2.701)
        (xy 1.742 2.71)
        (xy 1.739 2.712)
        (xy 1.735 2.71)
        (xy 1.724 2.704)
        (xy 1.713 2.698)
        (xy 1.697 2.69)
        (xy 1.682 2.686)
        (xy 1.664 2.685)
        (xy 1.653 2.685)
        (xy 1.618 2.688)
        (xy 1.59 2.699)
        (xy 1.566 2.718)
        (xy 1.561 2.723)
        (xy 1.554 2.732)
        (xy 1.548 2.74)
        (xy 1.544 2.748)
        (xy 1.54 2.758)
        (xy 1.537 2.769)
        (xy 1.534 2.785)
        (xy 1.533 2.804)
        (xy 1.532 2.829)
        (xy 1.531 2.861)
        (xy 1.53 2.899)
        (xy 1.53 2.947)
        (xy 1.53 2.988)
        (xy 1.528 3.2)
        (xy 1.468 3.2)
        (xy 1.444 3.2)
        (xy 1.425 3.199)
        (xy 1.411 3.198)
        (xy 1.405 3.197)
        (xy 1.404 3.191)
        (xy 1.404 3.176)
        (xy 1.403 3.153)
        (xy 1.403 3.122)
        (xy 1.402 3.085)
        (xy 1.402 3.042)
        (xy 1.402 2.993)
        (xy 1.402 2.941)
        (xy 1.402 2.886)
        (xy 1.402 2.565)
        (xy 1.529 2.565)
        (xy 1.529 2.595)
        (xy 1.529 2.611)
        (xy 1.53 2.623)
        (xy 1.532 2.626)
        (xy 1.537 2.623)
        (xy 1.547 2.615)
        (xy 1.554 2.608)
        (xy 1.588 2.584)
        (xy 1.627 2.567)
        (xy 1.669 2.558)
        (xy 1.712 2.556)
        (xy 1.753 2.563)
      )

      (stroke (width 0.01) (type solid)) (fill solid) (layer "F.Mask"))
    (fp_poly
      (pts
        (xy 2.316 1.557)
        (xy 2.365 1.57)
        (xy 2.41 1.593)
        (xy 2.453 1.625)
        (xy 2.46 1.631)
        (xy 2.491 1.661)
        (xy 2.466 1.684)
        (xy 2.448 1.699)
        (xy 2.43 1.715)
        (xy 2.419 1.725)
        (xy 2.397 1.743)
        (xy 2.376 1.724)
        (xy 2.345 1.701)
        (xy 2.312 1.687)
        (xy 2.274 1.681)
        (xy 2.265 1.681)
        (xy 2.226 1.684)
        (xy 2.195 1.693)
        (xy 2.167 1.708)
        (xy 2.159 1.715)
        (xy 2.136 1.741)
        (xy 2.118 1.776)
        (xy 2.107 1.817)
        (xy 2.103 1.866)
        (xy 2.103 1.876)
        (xy 2.106 1.926)
        (xy 2.116 1.97)
        (xy 2.132 2.006)
        (xy 2.155 2.034)
        (xy 2.184 2.055)
        (xy 2.219 2.067)
        (xy 2.259 2.072)
        (xy 2.274 2.071)
        (xy 2.309 2.066)
        (xy 2.339 2.056)
        (xy 2.366 2.038)
        (xy 2.377 2.028)
        (xy 2.386 2.02)
        (xy 2.393 2.016)
        (xy 2.4 2.015)
        (xy 2.409 2.018)
        (xy 2.42 2.027)
        (xy 2.436 2.041)
        (xy 2.456 2.059)
        (xy 2.491 2.092)
        (xy 2.476 2.108)
        (xy 2.449 2.132)
        (xy 2.416 2.155)
        (xy 2.38 2.174)
        (xy 2.35 2.186)
        (xy 2.327 2.193)
        (xy 2.306 2.197)
        (xy 2.283 2.199)
        (xy 2.259 2.199)
        (xy 2.233 2.198)
        (xy 2.209 2.196)
        (xy 2.189 2.193)
        (xy 2.182 2.191)
        (xy 2.133 2.173)
        (xy 2.089 2.146)
        (xy 2.053 2.112)
        (xy 2.023 2.071)
        (xy 2.012 2.051)
        (xy 2 2.023)
        (xy 1.991 1.999)
        (xy 1.984 1.975)
        (xy 1.981 1.948)
        (xy 1.979 1.917)
        (xy 1.978 1.879)
        (xy 1.978 1.877)
        (xy 1.979 1.838)
        (xy 1.98 1.806)
        (xy 1.984 1.78)
        (xy 1.99 1.756)
        (xy 1.999 1.731)
        (xy 2.011 1.704)
        (xy 2.012 1.701)
        (xy 2.039 1.657)
        (xy 2.072 1.62)
        (xy 2.111 1.591)
        (xy 2.156 1.57)
        (xy 2.207 1.557)
        (xy 2.263 1.552)
        (xy 2.316 1.557)
      )

      (stroke (width 0.01) (type solid)) (fill solid) (layer "F.Mask"))
    (fp_poly
      (pts
        (xy -1.494 1.56)
        (xy -1.447 1.576)
        (xy -1.405 1.6)
        (xy -1.368 1.633)
        (xy -1.341 1.668)
        (xy -1.326 1.692)
        (xy -1.316 1.716)
        (xy -1.308 1.743)
        (xy -1.302 1.774)
        (xy -1.299 1.811)
        (xy -1.297 1.845)
        (xy -1.294 1.925)
        (xy -1.692 1.925)
        (xy -1.692 1.942)
        (xy -1.687 1.977)
        (xy -1.673 2.011)
        (xy -1.65 2.039)
        (xy -1.626 2.059)
        (xy -1.601 2.071)
        (xy -1.572 2.078)
        (xy -1.537 2.079)
        (xy -1.497 2.074)
        (xy -1.458 2.06)
        (xy -1.422 2.036)
        (xy -1.421 2.036)
        (xy -1.402 2.021)
        (xy -1.359 2.057)
        (xy -1.342 2.072)
        (xy -1.327 2.085)
        (xy -1.317 2.094)
        (xy -1.314 2.098)
        (xy -1.316 2.103)
        (xy -1.324 2.113)
        (xy -1.338 2.126)
        (xy -1.354 2.139)
        (xy -1.372 2.152)
        (xy -1.389 2.163)
        (xy -1.399 2.168)
        (xy -1.421 2.178)
        (xy -1.445 2.187)
        (xy -1.461 2.191)
        (xy -1.488 2.196)
        (xy -1.522 2.199)
        (xy -1.557 2.199)
        (xy -1.591 2.196)
        (xy -1.62 2.192)
        (xy -1.629 2.19)
        (xy -1.677 2.171)
        (xy -1.718 2.146)
        (xy -1.752 2.114)
        (xy -1.779 2.074)
        (xy -1.8 2.026)
        (xy -1.802 2.02)
        (xy -1.81 1.989)
        (xy -1.815 1.951)
        (xy -1.818 1.908)
        (xy -1.819 1.865)
        (xy -1.818 1.823)
        (xy -1.816 1.804)
        (xy -1.692 1.804)
        (xy -1.692 1.818)
        (xy -1.428 1.818)
        (xy -1.428 1.801)
        (xy -1.432 1.775)
        (xy -1.442 1.748)
        (xy -1.457 1.722)
        (xy -1.469 1.707)
        (xy -1.495 1.688)
        (xy -1.526 1.676)
        (xy -1.56 1.672)
        (xy -1.593 1.676)
        (xy -1.619 1.685)
        (xy -1.646 1.704)
        (xy -1.668 1.73)
        (xy -1.683 1.76)
        (xy -1.691 1.792)
        (xy -1.692 1.804)
        (xy -1.816 1.804)
        (xy -1.814 1.786)
        (xy -1.812 1.777)
        (xy -1.797 1.724)
        (xy -1.775 1.676)
        (xy -1.747 1.636)
        (xy -1.713 1.603)
        (xy -1.673 1.578)
        (xy -1.629 1.561)
        (xy -1.597 1.554)
        (xy -1.544 1.552)
        (xy -1.494 1.56)
      )

      (stroke (width 0.01) (type solid)) (fill solid) (layer "F.Mask"))
    (fp_poly
      (pts
        (xy 2.835 1.557)
        (xy 2.883 1.57)
        (xy 2.926 1.592)
        (xy 2.964 1.621)
        (xy 2.996 1.657)
        (xy 3.021 1.699)
        (xy 3.038 1.747)
        (xy 3.04 1.757)
        (xy 3.043 1.776)
        (xy 3.045 1.802)
        (xy 3.047 1.832)
        (xy 3.047 1.858)
        (xy 3.047 1.925)
        (xy 2.65 1.925)
        (xy 2.653 1.951)
        (xy 2.663 1.991)
        (xy 2.68 2.024)
        (xy 2.703 2.049)
        (xy 2.733 2.067)
        (xy 2.77 2.077)
        (xy 2.801 2.079)
        (xy 2.845 2.075)
        (xy 2.883 2.063)
        (xy 2.916 2.042)
        (xy 2.92 2.039)
        (xy 2.929 2.031)
        (xy 2.935 2.026)
        (xy 2.941 2.025)
        (xy 2.949 2.027)
        (xy 2.959 2.034)
        (xy 2.974 2.047)
        (xy 2.994 2.064)
        (xy 3.01 2.078)
        (xy 3.023 2.088)
        (xy 3.03 2.095)
        (xy 3.032 2.096)
        (xy 3.03 2.1)
        (xy 3.022 2.11)
        (xy 3.01 2.122)
        (xy 3.009 2.123)
        (xy 2.98 2.147)
        (xy 2.945 2.169)
        (xy 2.906 2.185)
        (xy 2.887 2.191)
        (xy 2.861 2.196)
        (xy 2.828 2.198)
        (xy 2.793 2.198)
        (xy 2.759 2.197)
        (xy 2.729 2.193)
        (xy 2.721 2.191)
        (xy 2.675 2.175)
        (xy 2.634 2.15)
        (xy 2.599 2.118)
        (xy 2.569 2.077)
        (xy 2.547 2.029)
        (xy 2.536 1.996)
        (xy 2.532 1.973)
        (xy 2.529 1.942)
        (xy 2.527 1.906)
        (xy 2.527 1.869)
        (xy 2.528 1.832)
        (xy 2.529 1.818)
        (xy 2.65 1.818)
        (xy 2.922 1.818)
        (xy 2.918 1.799)
        (xy 2.908 1.758)
        (xy 2.891 1.725)
        (xy 2.869 1.7)
        (xy 2.84 1.683)
        (xy 2.826 1.678)
        (xy 2.788 1.672)
        (xy 2.753 1.675)
        (xy 2.722 1.687)
        (xy 2.695 1.706)
        (xy 2.674 1.734)
        (xy 2.659 1.768)
        (xy 2.654 1.794)
        (xy 2.65 1.818)
        (xy 2.529 1.818)
        (xy 2.53 1.798)
        (xy 2.534 1.769)
        (xy 2.536 1.76)
        (xy 2.554 1.707)
        (xy 2.578 1.662)
        (xy 2.609 1.624)
        (xy 2.645 1.593)
        (xy 2.687 1.571)
        (xy 2.734 1.557)
        (xy 2.783 1.553)
        (xy 2.835 1.557)
      )

      (stroke (width 0.01) (type solid)) (fill solid) (layer "F.Mask"))
    (fp_poly
      (pts
        (xy -2.733 1.557)
        (xy -2.685 1.57)
        (xy -2.642 1.592)
        (xy -2.604 1.622)
        (xy -2.581 1.649)
        (xy -2.562 1.676)
        (xy -2.548 1.706)
        (xy -2.537 1.739)
        (xy -2.53 1.777)
        (xy -2.527 1.821)
        (xy -2.526 1.873)
        (xy -2.527 1.907)
        (xy -2.529 1.956)
        (xy -2.534 1.997)
        (xy -2.542 2.031)
        (xy -2.553 2.06)
        (xy -2.567 2.086)
        (xy -2.587 2.111)
        (xy -2.603 2.129)
        (xy -2.637 2.158)
        (xy -2.673 2.178)
        (xy -2.714 2.192)
        (xy -2.76 2.198)
        (xy -2.789 2.199)
        (xy -2.813 2.198)
        (xy -2.835 2.196)
        (xy -2.852 2.194)
        (xy -2.857 2.194)
        (xy -2.898 2.179)
        (xy -2.937 2.155)
        (xy -2.97 2.126)
        (xy -2.993 2.101)
        (xy -3.011 2.077)
        (xy -3.024 2.051)
        (xy -3.034 2.022)
        (xy -3.041 1.988)
        (xy -3.045 1.947)
        (xy -3.047 1.91)
        (xy -3.047 1.882)
        (xy -2.919 1.882)
        (xy -2.919 1.968)
        (xy -2.903 2.001)
        (xy -2.885 2.031)
        (xy -2.863 2.051)
        (xy -2.837 2.064)
        (xy -2.804 2.07)
        (xy -2.779 2.07)
        (xy -2.755 2.069)
        (xy -2.737 2.065)
        (xy -2.722 2.058)
        (xy -2.717 2.055)
        (xy -2.697 2.041)
        (xy -2.681 2.025)
        (xy -2.67 2.004)
        (xy -2.662 1.978)
        (xy -2.657 1.945)
        (xy -2.654 1.903)
        (xy -2.654 1.899)
        (xy -2.653 1.848)
        (xy -2.656 1.806)
        (xy -2.662 1.772)
        (xy -2.673 1.744)
        (xy -2.687 1.722)
        (xy -2.707 1.705)
        (xy -2.723 1.695)
        (xy -2.755 1.684)
        (xy -2.788 1.68)
        (xy -2.821 1.684)
        (xy -2.851 1.695)
        (xy -2.877 1.713)
        (xy -2.892 1.729)
        (xy -2.901 1.745)
        (xy -2.908 1.76)
        (xy -2.913 1.778)
        (xy -2.916 1.8)
        (xy -2.918 1.828)
        (xy -2.919 1.864)
        (xy -2.919 1.882)
        (xy -3.047 1.882)
        (xy -3.048 1.844)
        (xy -3.043 1.786)
        (xy -3.034 1.736)
        (xy -3.021 1.695)
        (xy -3.004 1.664)
        (xy -2.972 1.624)
        (xy -2.935 1.594)
        (xy -2.893 1.571)
        (xy -2.846 1.558)
        (xy -2.794 1.553)
        (xy -2.787 1.553)
        (xy -2.733 1.557)
      )

      (stroke (width 0.01) (type solid)) (fill solid) (layer "F.Mask"))
    (fp_poly
      (pts
        (xy 2.148 2.561)
        (xy 2.193 2.574)
        (xy 2.235 2.595)
        (xy 2.273 2.623)
        (xy 2.304 2.657)
        (xy 2.326 2.691)
        (xy 2.338 2.718)
        (xy 2.346 2.745)
        (xy 2.352 2.774)
        (xy 2.355 2.808)
        (xy 2.357 2.85)
        (xy 2.357 2.858)
        (xy 2.357 2.931)
        (xy 1.96 2.931)
        (xy 1.963 2.955)
        (xy 1.973 2.993)
        (xy 1.991 3.026)
        (xy 2.015 3.053)
        (xy 2.039 3.069)
        (xy 2.057 3.076)
        (xy 2.08 3.08)
        (xy 2.103 3.082)
        (xy 2.144 3.081)
        (xy 2.18 3.071)
        (xy 2.214 3.054)
        (xy 2.227 3.045)
        (xy 2.24 3.035)
        (xy 2.25 3.029)
        (xy 2.253 3.027)
        (xy 2.258 3.03)
        (xy 2.269 3.039)
        (xy 2.284 3.05)
        (xy 2.3 3.064)
        (xy 2.315 3.078)
        (xy 2.329 3.09)
        (xy 2.338 3.099)
        (xy 2.341 3.103)
        (xy 2.337 3.11)
        (xy 2.327 3.121)
        (xy 2.312 3.134)
        (xy 2.294 3.148)
        (xy 2.276 3.161)
        (xy 2.259 3.171)
        (xy 2.252 3.175)
        (xy 2.204 3.192)
        (xy 2.152 3.202)
        (xy 2.098 3.204)
        (xy 2.046 3.198)
        (xy 2.032 3.195)
        (xy 1.984 3.178)
        (xy 1.943 3.154)
        (xy 1.909 3.123)
        (xy 1.881 3.084)
        (xy 1.859 3.037)
        (xy 1.847 3.003)
        (xy 1.841 2.972)
        (xy 1.838 2.934)
        (xy 1.836 2.893)
        (xy 1.837 2.851)
        (xy 1.839 2.824)
        (xy 1.96 2.824)
        (xy 2.23 2.824)
        (xy 2.23 2.813)
        (xy 2.225 2.783)
        (xy 2.214 2.753)
        (xy 2.196 2.725)
        (xy 2.175 2.702)
        (xy 2.151 2.686)
        (xy 2.128 2.68)
        (xy 2.101 2.677)
        (xy 2.072 2.678)
        (xy 2.051 2.683)
        (xy 2.023 2.696)
        (xy 2 2.717)
        (xy 1.981 2.746)
        (xy 1.968 2.779)
        (xy 1.963 2.8)
        (xy 1.96 2.824)
        (xy 1.839 2.824)
        (xy 1.839 2.811)
        (xy 1.844 2.776)
        (xy 1.848 2.76)
        (xy 1.866 2.708)
        (xy 1.889 2.663)
        (xy 1.919 2.627)
        (xy 1.954 2.598)
        (xy 1.996 2.575)
        (xy 2.007 2.571)
        (xy 2.054 2.559)
        (xy 2.101 2.556)
        (xy 2.148 2.561)
      )

      (stroke (width 0.01) (type solid)) (fill solid) (layer "F.Mask"))
    (fp_poly
      (pts
        (xy -0.229 3.2)
        (xy -0.354 3.197)
        (xy -0.355 3.165)
        (xy -0.357 3.133)
        (xy -0.374 3.148)
        (xy -0.411 3.175)
        (xy -0.453 3.193)
        (xy -0.497 3.203)
        (xy -0.542 3.204)
        (xy -0.585 3.195)
        (xy -0.586 3.195)
        (xy -0.621 3.181)
        (xy -0.651 3.16)
        (xy -0.673 3.141)
        (xy -0.689 3.123)
        (xy -0.702 3.106)
        (xy -0.712 3.086)
        (xy -0.72 3.064)
        (xy -0.726 3.038)
        (xy -0.73 3.007)
        (xy -0.732 2.968)
        (xy -0.733 2.922)
        (xy -0.733 2.88)
        (xy -0.602 2.88)
        (xy -0.602 2.915)
        (xy -0.602 2.942)
        (xy -0.601 2.962)
        (xy -0.6 2.977)
        (xy -0.598 2.988)
        (xy -0.596 2.998)
        (xy -0.592 3.007)
        (xy -0.591 3.01)
        (xy -0.574 3.039)
        (xy -0.552 3.059)
        (xy -0.525 3.071)
        (xy -0.492 3.076)
        (xy -0.472 3.076)
        (xy -0.442 3.072)
        (xy -0.418 3.063)
        (xy -0.398 3.048)
        (xy -0.382 3.029)
        (xy -0.371 3.004)
        (xy -0.363 2.972)
        (xy -0.358 2.933)
        (xy -0.356 2.885)
        (xy -0.356 2.88)
        (xy -0.358 2.828)
        (xy -0.363 2.785)
        (xy -0.373 2.75)
        (xy -0.387 2.724)
        (xy -0.406 2.704)
        (xy -0.43 2.692)
        (xy -0.46 2.686)
        (xy -0.483 2.685)
        (xy -0.517 2.687)
        (xy -0.544 2.696)
        (xy -0.565 2.711)
        (xy -0.583 2.734)
        (xy -0.591 2.751)
        (xy -0.595 2.76)
        (xy -0.598 2.769)
        (xy -0.6 2.779)
        (xy -0.601 2.793)
        (xy -0.602 2.811)
        (xy -0.602 2.836)
        (xy -0.602 2.869)
        (xy -0.602 2.88)
        (xy -0.733 2.88)
        (xy -0.733 2.827)
        (xy -0.732 2.783)
        (xy -0.729 2.746)
        (xy -0.725 2.716)
        (xy -0.719 2.691)
        (xy -0.71 2.67)
        (xy -0.699 2.651)
        (xy -0.685 2.633)
        (xy -0.668 2.616)
        (xy -0.668 2.615)
        (xy -0.632 2.587)
        (xy -0.592 2.567)
        (xy -0.55 2.557)
        (xy -0.506 2.556)
        (xy -0.463 2.564)
        (xy -0.421 2.582)
        (xy -0.411 2.587)
        (xy -0.394 2.598)
        (xy -0.377 2.61)
        (xy -0.373 2.614)
        (xy -0.356 2.627)
        (xy -0.356 2.306)
        (xy -0.229 2.306)
        (xy -0.229 3.2)
      )

      (stroke (width 0.01) (type solid)) (fill solid) (layer "F.Mask"))
    (fp_poly
      (pts
        (xy 0.605 1.558)
        (xy 0.651 1.574)
        (xy 0.694 1.598)
        (xy 0.728 1.627)
        (xy 0.75 1.652)
        (xy 0.768 1.678)
        (xy 0.781 1.707)
        (xy 0.791 1.739)
        (xy 0.797 1.777)
        (xy 0.801 1.822)
        (xy 0.802 1.876)
        (xy 0.802 1.877)
        (xy 0.801 1.929)
        (xy 0.798 1.973)
        (xy 0.792 2.009)
        (xy 0.784 2.04)
        (xy 0.774 2.062)
        (xy 0.748 2.103)
        (xy 0.715 2.139)
        (xy 0.675 2.167)
        (xy 0.632 2.187)
        (xy 0.626 2.189)
        (xy 0.599 2.195)
        (xy 0.567 2.198)
        (xy 0.532 2.199)
        (xy 0.499 2.197)
        (xy 0.471 2.193)
        (xy 0.466 2.192)
        (xy 0.428 2.177)
        (xy 0.391 2.155)
        (xy 0.359 2.129)
        (xy 0.354 2.123)
        (xy 0.332 2.098)
        (xy 0.316 2.073)
        (xy 0.303 2.047)
        (xy 0.294 2.017)
        (xy 0.287 1.983)
        (xy 0.284 1.943)
        (xy 0.282 1.894)
        (xy 0.282 1.877)
        (xy 0.409 1.877)
        (xy 0.41 1.918)
        (xy 0.412 1.95)
        (xy 0.416 1.976)
        (xy 0.423 1.997)
        (xy 0.432 2.015)
        (xy 0.445 2.03)
        (xy 0.451 2.037)
        (xy 0.471 2.054)
        (xy 0.491 2.064)
        (xy 0.514 2.07)
        (xy 0.543 2.072)
        (xy 0.569 2.07)
        (xy 0.59 2.065)
        (xy 0.601 2.06)
        (xy 0.625 2.047)
        (xy 0.642 2.031)
        (xy 0.656 2.009)
        (xy 0.661 1.998)
        (xy 0.665 1.989)
        (xy 0.668 1.98)
        (xy 0.67 1.969)
        (xy 0.671 1.954)
        (xy 0.672 1.935)
        (xy 0.673 1.909)
        (xy 0.673 1.877)
        (xy 0.673 1.842)
        (xy 0.672 1.817)
        (xy 0.671 1.798)
        (xy 0.67 1.784)
        (xy 0.668 1.773)
        (xy 0.665 1.764)
        (xy 0.661 1.755)
        (xy 0.647 1.73)
        (xy 0.632 1.712)
        (xy 0.612 1.698)
        (xy 0.601 1.693)
        (xy 0.569 1.683)
        (xy 0.535 1.681)
        (xy 0.501 1.686)
        (xy 0.471 1.7)
        (xy 0.447 1.719)
        (xy 0.434 1.736)
        (xy 0.424 1.753)
        (xy 0.417 1.774)
        (xy 0.412 1.8)
        (xy 0.41 1.833)
        (xy 0.409 1.873)
        (xy 0.409 1.877)
        (xy 0.282 1.877)
        (xy 0.283 1.824)
        (xy 0.286 1.78)
        (xy 0.292 1.742)
        (xy 0.301 1.711)
        (xy 0.313 1.683)
        (xy 0.33 1.657)
        (xy 0.35 1.633)
        (xy 0.351 1.632)
        (xy 0.385 1.601)
        (xy 0.42 1.578)
        (xy 0.46 1.563)
        (xy 0.505 1.554)
        (xy 0.555 1.551)
        (xy 0.605 1.558)
      )

      (stroke (width 0.01) (type solid)) (fill solid) (layer "F.Mask"))
    (fp_poly
      (pts
        (xy 0.004 1.556)
        (xy 0.054 1.566)
        (xy 0.102 1.582)
        (xy 0.146 1.605)
        (xy 0.154 1.61)
        (xy 0.193 1.636)
        (xy 0.178 1.655)
        (xy 0.166 1.668)
        (xy 0.152 1.686)
        (xy 0.138 1.7)
        (xy 0.114 1.727)
        (xy 0.07 1.705)
        (xy 0.032 1.688)
        (xy -0.007 1.677)
        (xy -0.044 1.672)
        (xy -0.079 1.672)
        (xy -0.11 1.678)
        (xy -0.136 1.69)
        (xy -0.154 1.707)
        (xy -0.162 1.724)
        (xy -0.164 1.745)
        (xy -0.164 1.761)
        (xy -0.159 1.772)
        (xy -0.15 1.782)
        (xy -0.149 1.783)
        (xy -0.139 1.791)
        (xy -0.128 1.797)
        (xy -0.114 1.802)
        (xy -0.095 1.805)
        (xy -0.07 1.808)
        (xy -0.037 1.811)
        (xy -0.02 1.813)
        (xy 0.027 1.817)
        (xy 0.065 1.823)
        (xy 0.096 1.832)
        (xy 0.122 1.842)
        (xy 0.14 1.854)
        (xy 0.166 1.879)
        (xy 0.186 1.91)
        (xy 0.2 1.947)
        (xy 0.206 1.987)
        (xy 0.206 2.018)
        (xy 0.198 2.06)
        (xy 0.181 2.097)
        (xy 0.155 2.129)
        (xy 0.122 2.156)
        (xy 0.08 2.177)
        (xy 0.042 2.189)
        (xy 0.005 2.196)
        (xy -0.038 2.199)
        (xy -0.083 2.198)
        (xy -0.125 2.194)
        (xy -0.153 2.189)
        (xy -0.177 2.181)
        (xy -0.204 2.171)
        (xy -0.229 2.16)
        (xy -0.232 2.159)
        (xy -0.251 2.148)
        (xy -0.272 2.136)
        (xy -0.292 2.122)
        (xy -0.309 2.109)
        (xy -0.323 2.098)
        (xy -0.33 2.09)
        (xy -0.331 2.088)
        (xy -0.327 2.084)
        (xy -0.318 2.073)
        (xy -0.304 2.059)
        (xy -0.288 2.043)
        (xy -0.246 2)
        (xy -0.221 2.021)
        (xy -0.184 2.047)
        (xy -0.145 2.065)
        (xy -0.102 2.075)
        (xy -0.053 2.079)
        (xy -0.049 2.079)
        (xy -0.023 2.079)
        (xy -0.004 2.078)
        (xy 0.011 2.074)
        (xy 0.025 2.069)
        (xy 0.029 2.068)
        (xy 0.054 2.052)
        (xy 0.071 2.033)
        (xy 0.079 2.01)
        (xy 0.078 1.986)
        (xy 0.074 1.975)
        (xy 0.068 1.964)
        (xy 0.06 1.956)
        (xy 0.048 1.949)
        (xy 0.031 1.944)
        (xy 0.007 1.939)
        (xy -0.024 1.935)
        (xy -0.052 1.932)
        (xy -0.089 1.929)
        (xy -0.119 1.925)
        (xy -0.142 1.921)
        (xy -0.16 1.917)
        (xy -0.176 1.912)
        (xy -0.192 1.906)
        (xy -0.201 1.901)
        (xy -0.235 1.879)
        (xy -0.262 1.85)
        (xy -0.28 1.816)
        (xy -0.29 1.776)
        (xy -0.292 1.75)
        (xy -0.291 1.727)
        (xy -0.289 1.705)
        (xy -0.286 1.689)
        (xy -0.286 1.688)
        (xy -0.273 1.659)
        (xy -0.253 1.63)
        (xy -0.229 1.604)
        (xy -0.221 1.599)
        (xy -0.185 1.577)
        (xy -0.143 1.562)
        (xy -0.096 1.554)
        (xy -0.047 1.552)
        (xy 0.004 1.556)
      )

      (stroke (width 0.01) (type solid)) (fill solid) (layer "F.Mask"))
    (fp_poly
      (pts
        (xy 1.038 2.556)
        (xy 1.091 2.563)
        (xy 1.137 2.576)
        (xy 1.177 2.595)
        (xy 1.209 2.62)
        (xy 1.234 2.65)
        (xy 1.242 2.665)
        (xy 1.247 2.677)
        (xy 1.251 2.691)
        (xy 1.255 2.708)
        (xy 1.258 2.727)
        (xy 1.26 2.751)
        (xy 1.262 2.78)
        (xy 1.263 2.815)
        (xy 1.263 2.858)
        (xy 1.264 2.908)
        (xy 1.263 2.967)
        (xy 1.263 2.989)
        (xy 1.262 3.197)
        (xy 1.135 3.197)
        (xy 1.133 3.171)
        (xy 1.132 3.144)
        (xy 1.119 3.159)
        (xy 1.096 3.179)
        (xy 1.065 3.193)
        (xy 1.026 3.202)
        (xy 0.98 3.204)
        (xy 0.976 3.204)
        (xy 0.955 3.204)
        (xy 0.937 3.203)
        (xy 0.925 3.202)
        (xy 0.924 3.201)
        (xy 0.879 3.189)
        (xy 0.839 3.17)
        (xy 0.806 3.144)
        (xy 0.781 3.113)
        (xy 0.763 3.077)
        (xy 0.753 3.037)
        (xy 0.753 3.005)
        (xy 0.873 3.005)
        (xy 0.874 3.023)
        (xy 0.878 3.035)
        (xy 0.887 3.047)
        (xy 0.89 3.05)
        (xy 0.903 3.063)
        (xy 0.917 3.072)
        (xy 0.935 3.078)
        (xy 0.957 3.081)
        (xy 0.986 3.082)
        (xy 1.013 3.082)
        (xy 1.043 3.081)
        (xy 1.065 3.079)
        (xy 1.08 3.077)
        (xy 1.091 3.073)
        (xy 1.096 3.071)
        (xy 1.112 3.058)
        (xy 1.123 3.039)
        (xy 1.13 3.012)
        (xy 1.132 2.977)
        (xy 1.132 2.975)
        (xy 1.132 2.931)
        (xy 1.035 2.931)
        (xy 0.999 2.931)
        (xy 0.973 2.931)
        (xy 0.953 2.932)
        (xy 0.939 2.934)
        (xy 0.928 2.936)
        (xy 0.919 2.939)
        (xy 0.916 2.94)
        (xy 0.893 2.954)
        (xy 0.88 2.971)
        (xy 0.874 2.994)
        (xy 0.873 3.005)
        (xy 0.753 3.005)
        (xy 0.753 2.994)
        (xy 0.761 2.951)
        (xy 0.768 2.931)
        (xy 0.776 2.915)
        (xy 0.786 2.901)
        (xy 0.802 2.884)
        (xy 0.804 2.882)
        (xy 0.82 2.867)
        (xy 0.835 2.854)
        (xy 0.85 2.845)
        (xy 0.867 2.838)
        (xy 0.887 2.833)
        (xy 0.912 2.829)
        (xy 0.943 2.827)
        (xy 0.982 2.826)
        (xy 1.015 2.825)
        (xy 1.133 2.823)
        (xy 1.132 2.771)
        (xy 1.131 2.746)
        (xy 1.129 2.73)
        (xy 1.127 2.719)
        (xy 1.123 2.711)
        (xy 1.117 2.705)
        (xy 1.098 2.691)
        (xy 1.07 2.682)
        (xy 1.032 2.677)
        (xy 1.006 2.677)
        (xy 0.972 2.678)
        (xy 0.945 2.682)
        (xy 0.924 2.688)
        (xy 0.907 2.699)
        (xy 0.9 2.706)
        (xy 0.882 2.723)
        (xy 0.834 2.686)
        (xy 0.816 2.672)
        (xy 0.801 2.66)
        (xy 0.79 2.652)
        (xy 0.787 2.648)
        (xy 0.791 2.639)
        (xy 0.801 2.626)
        (xy 0.816 2.612)
        (xy 0.832 2.6)
        (xy 0.864 2.581)
        (xy 0.902 2.568)
        (xy 0.946 2.559)
        (xy 0.98 2.556)
        (xy 1.038 2.556)
      )

      (stroke (width 0.01) (type solid)) (fill solid) (layer "F.Mask"))
    (fp_poly
      (pts
        (xy -1.521 2.559)
        (xy -1.485 2.562)
        (xy -1.454 2.568)
        (xy -1.427 2.577)
        (xy -1.401 2.589)
        (xy -1.371 2.61)
        (xy -1.345 2.639)
        (xy -1.325 2.67)
        (xy -1.321 2.679)
        (xy -1.309 2.71)
        (xy -1.309 3.197)
        (xy -1.433 3.2)
        (xy -1.433 3.172)
        (xy -1.434 3.157)
        (xy -1.435 3.147)
        (xy -1.436 3.144)
        (xy -1.44 3.147)
        (xy -1.449 3.156)
        (xy -1.453 3.161)
        (xy -1.472 3.178)
        (xy -1.496 3.19)
        (xy -1.526 3.198)
        (xy -1.563 3.202)
        (xy -1.578 3.203)
        (xy -1.603 3.203)
        (xy -1.627 3.203)
        (xy -1.647 3.201)
        (xy -1.656 3.2)
        (xy -1.686 3.191)
        (xy -1.717 3.176)
        (xy -1.746 3.159)
        (xy -1.765 3.143)
        (xy -1.79 3.111)
        (xy -1.807 3.075)
        (xy -1.816 3.037)
        (xy -1.817 2.998)
        (xy -1.817 2.997)
        (xy -1.697 2.997)
        (xy -1.696 3.02)
        (xy -1.687 3.042)
        (xy -1.67 3.06)
        (xy -1.668 3.062)
        (xy -1.654 3.07)
        (xy -1.64 3.076)
        (xy -1.624 3.08)
        (xy -1.602 3.081)
        (xy -1.574 3.082)
        (xy -1.558 3.082)
        (xy -1.529 3.081)
        (xy -1.508 3.08)
        (xy -1.494 3.078)
        (xy -1.483 3.075)
        (xy -1.474 3.07)
        (xy -1.458 3.058)
        (xy -1.447 3.041)
        (xy -1.44 3.017)
        (xy -1.435 2.985)
        (xy -1.435 2.977)
        (xy -1.432 2.931)
        (xy -1.533 2.931)
        (xy -1.568 2.931)
        (xy -1.595 2.931)
        (xy -1.615 2.932)
        (xy -1.63 2.934)
        (xy -1.641 2.936)
        (xy -1.65 2.938)
        (xy -1.655 2.941)
        (xy -1.676 2.955)
        (xy -1.69 2.974)
        (xy -1.697 2.997)
        (xy -1.817 2.997)
        (xy -1.811 2.96)
        (xy -1.797 2.924)
        (xy -1.775 2.892)
        (xy -1.747 2.864)
        (xy -1.715 2.845)
        (xy -1.7 2.838)
        (xy -1.685 2.833)
        (xy -1.668 2.83)
        (xy -1.648 2.827)
        (xy -1.623 2.825)
        (xy -1.591 2.824)
        (xy -1.551 2.824)
        (xy -1.54 2.824)
        (xy -1.432 2.824)
        (xy -1.434 2.776)
        (xy -1.436 2.747)
        (xy -1.441 2.726)
        (xy -1.448 2.711)
        (xy -1.46 2.699)
        (xy -1.474 2.689)
        (xy -1.483 2.685)
        (xy -1.492 2.682)
        (xy -1.505 2.68)
        (xy -1.524 2.68)
        (xy -1.55 2.679)
        (xy -1.56 2.679)
        (xy -1.594 2.68)
        (xy -1.62 2.682)
        (xy -1.639 2.686)
        (xy -1.654 2.692)
        (xy -1.666 2.701)
        (xy -1.675 2.711)
        (xy -1.686 2.724)
        (xy -1.735 2.686)
        (xy -1.754 2.672)
        (xy -1.769 2.659)
        (xy -1.78 2.65)
        (xy -1.784 2.646)
        (xy -1.78 2.64)
        (xy -1.77 2.629)
        (xy -1.756 2.616)
        (xy -1.74 2.604)
        (xy -1.724 2.592)
        (xy -1.711 2.584)
        (xy -1.71 2.583)
        (xy -1.688 2.574)
        (xy -1.668 2.566)
        (xy -1.647 2.562)
        (xy -1.623 2.559)
        (xy -1.593 2.558)
        (xy -1.565 2.558)
        (xy -1.521 2.559)
      )

      (stroke (width 0.01) (type solid)) (fill solid) (layer "F.Mask"))
    (fp_poly
      (pts
        (xy 0.035 2.777)
        (xy 0.047 2.822)
        (xy 0.059 2.864)
        (xy 0.069 2.903)
        (xy 0.078 2.936)
        (xy 0.086 2.963)
        (xy 0.092 2.984)
        (xy 0.095 2.996)
        (xy 0.096 2.999)
        (xy 0.098 2.999)
        (xy 0.103 2.991)
        (xy 0.109 2.975)
        (xy 0.118 2.95)
        (xy 0.129 2.917)
        (xy 0.143 2.874)
        (xy 0.152 2.849)
        (xy 0.165 2.807)
        (xy 0.179 2.766)
        (xy 0.192 2.726)
        (xy 0.204 2.689)
        (xy 0.214 2.658)
        (xy 0.221 2.634)
        (xy 0.224 2.627)
        (xy 0.244 2.565)
        (xy 0.338 2.565)
        (xy 0.406 2.774)
        (xy 0.42 2.819)
        (xy 0.434 2.861)
        (xy 0.446 2.899)
        (xy 0.457 2.932)
        (xy 0.466 2.96)
        (xy 0.473 2.981)
        (xy 0.477 2.993)
        (xy 0.478 2.997)
        (xy 0.48 2.998)
        (xy 0.482 2.996)
        (xy 0.485 2.99)
        (xy 0.49 2.978)
        (xy 0.495 2.96)
        (xy 0.502 2.936)
        (xy 0.511 2.905)
        (xy 0.523 2.865)
        (xy 0.536 2.817)
        (xy 0.543 2.789)
        (xy 0.556 2.744)
        (xy 0.568 2.701)
        (xy 0.578 2.663)
        (xy 0.587 2.629)
        (xy 0.595 2.602)
        (xy 0.601 2.582)
        (xy 0.605 2.57)
        (xy 0.606 2.567)
        (xy 0.611 2.566)
        (xy 0.625 2.566)
        (xy 0.645 2.566)
        (xy 0.669 2.566)
        (xy 0.673 2.566)
        (xy 0.739 2.567)
        (xy 0.656 2.827)
        (xy 0.64 2.878)
        (xy 0.624 2.928)
        (xy 0.609 2.976)
        (xy 0.595 3.02)
        (xy 0.582 3.06)
        (xy 0.571 3.094)
        (xy 0.563 3.121)
        (xy 0.557 3.139)
        (xy 0.556 3.143)
        (xy 0.538 3.2)
        (xy 0.425 3.197)
        (xy 0.358 2.975)
        (xy 0.341 2.917)
        (xy 0.327 2.87)
        (xy 0.315 2.831)
        (xy 0.305 2.801)
        (xy 0.297 2.78)
        (xy 0.292 2.766)
        (xy 0.289 2.761)
        (xy 0.288 2.761)
        (xy 0.286 2.768)
        (xy 0.281 2.783)
        (xy 0.274 2.806)
        (xy 0.265 2.836)
        (xy 0.254 2.871)
        (xy 0.242 2.911)
        (xy 0.23 2.953)
        (xy 0.223 2.976)
        (xy 0.21 3.02)
        (xy 0.197 3.062)
        (xy 0.186 3.099)
        (xy 0.177 3.132)
        (xy 0.169 3.158)
        (xy 0.163 3.177)
        (xy 0.16 3.189)
        (xy 0.159 3.191)
        (xy 0.157 3.195)
        (xy 0.151 3.198)
        (xy 0.141 3.199)
        (xy 0.124 3.2)
        (xy 0.101 3.2)
        (xy 0.073 3.199)
        (xy 0.055 3.198)
        (xy 0.045 3.196)
        (xy 0.043 3.194)
        (xy 0.041 3.188)
        (xy 0.036 3.173)
        (xy 0.029 3.15)
        (xy 0.019 3.121)
        (xy 0.008 3.084)
        (xy -0.006 3.043)
        (xy -0.02 2.996)
        (xy -0.036 2.946)
        (xy -0.053 2.893)
        (xy -0.057 2.883)
        (xy -0.074 2.83)
        (xy -0.09 2.779)
        (xy -0.105 2.732)
        (xy -0.119 2.689)
        (xy -0.131 2.652)
        (xy -0.141 2.621)
        (xy -0.148 2.596)
        (xy -0.154 2.58)
        (xy -0.156 2.572)
        (xy -0.156 2.569)
        (xy -0.151 2.567)
        (xy -0.14 2.566)
        (xy -0.123 2.565)
        (xy -0.096 2.565)
        (xy -0.091 2.565)
        (xy -0.023 2.565)
        (xy 0.035 2.777)
      )

      (stroke (width 0.01) (type solid)) (fill solid) (layer "F.Mask"))
    (fp_poly
      (pts
        (xy -2.065 1.559)
        (xy -2.024 1.576)
        (xy -1.986 1.601)
        (xy -1.973 1.612)
        (xy -1.957 1.63)
        (xy -1.943 1.649)
        (xy -1.932 1.668)
        (xy -1.924 1.69)
        (xy -1.918 1.716)
        (xy -1.914 1.747)
        (xy -1.911 1.785)
        (xy -1.91 1.831)
        (xy -1.91 1.877)
        (xy -1.91 1.93)
        (xy -1.912 1.974)
        (xy -1.914 2.011)
        (xy -1.919 2.041)
        (xy -1.925 2.067)
        (xy -1.934 2.088)
        (xy -1.945 2.107)
        (xy -1.959 2.125)
        (xy -1.972 2.139)
        (xy -1.993 2.157)
        (xy -2.018 2.173)
        (xy -2.031 2.18)
        (xy -2.047 2.188)
        (xy -2.06 2.192)
        (xy -2.074 2.195)
        (xy -2.091 2.196)
        (xy -2.114 2.197)
        (xy -2.122 2.197)
        (xy -2.147 2.196)
        (xy -2.165 2.195)
        (xy -2.179 2.193)
        (xy -2.191 2.189)
        (xy -2.205 2.183)
        (xy -2.21 2.18)
        (xy -2.231 2.169)
        (xy -2.251 2.156)
        (xy -2.265 2.146)
        (xy -2.286 2.127)
        (xy -2.286 2.627)
        (xy -2.266 2.608)
        (xy -2.248 2.595)
        (xy -2.227 2.582)
        (xy -2.217 2.577)
        (xy -2.173 2.562)
        (xy -2.129 2.556)
        (xy -2.086 2.559)
        (xy -2.045 2.57)
        (xy -2.007 2.589)
        (xy -1.974 2.616)
        (xy -1.946 2.648)
        (xy -1.926 2.687)
        (xy -1.919 2.707)
        (xy -1.917 2.715)
        (xy -1.915 2.724)
        (xy -1.914 2.737)
        (xy -1.913 2.753)
        (xy -1.912 2.774)
        (xy -1.911 2.8)
        (xy -1.911 2.833)
        (xy -1.911 2.874)
        (xy -1.911 2.923)
        (xy -1.911 2.967)
        (xy -1.911 3.2)
        (xy -2.035 3.197)
        (xy -2.038 2.984)
        (xy -2.038 2.932)
        (xy -2.039 2.889)
        (xy -2.039 2.854)
        (xy -2.04 2.826)
        (xy -2.041 2.805)
        (xy -2.042 2.788)
        (xy -2.043 2.776)
        (xy -2.045 2.767)
        (xy -2.046 2.76)
        (xy -2.049 2.755)
        (xy -2.051 2.75)
        (xy -2.072 2.721)
        (xy -2.098 2.701)
        (xy -2.128 2.688)
        (xy -2.161 2.683)
        (xy -2.195 2.687)
        (xy -2.22 2.697)
        (xy -2.24 2.71)
        (xy -2.259 2.729)
        (xy -2.274 2.75)
        (xy -2.278 2.757)
        (xy -2.28 2.765)
        (xy -2.281 2.781)
        (xy -2.283 2.806)
        (xy -2.284 2.839)
        (xy -2.285 2.881)
        (xy -2.286 2.933)
        (xy -2.286 2.984)
        (xy -2.289 3.197)
        (xy -2.413 3.2)
        (xy -2.413 1.877)
        (xy -2.286 1.877)
        (xy -2.285 1.926)
        (xy -2.281 1.966)
        (xy -2.274 1.998)
        (xy -2.262 2.024)
        (xy -2.247 2.043)
        (xy -2.228 2.058)
        (xy -2.215 2.064)
        (xy -2.194 2.07)
        (xy -2.168 2.072)
        (xy -2.141 2.071)
        (xy -2.117 2.066)
        (xy -2.106 2.063)
        (xy -2.079 2.044)
        (xy -2.058 2.019)
        (xy -2.05 2.001)
        (xy -2.045 1.984)
        (xy -2.042 1.959)
        (xy -2.04 1.929)
        (xy -2.038 1.895)
        (xy -2.038 1.861)
        (xy -2.039 1.829)
        (xy -2.041 1.8)
        (xy -2.044 1.777)
        (xy -2.045 1.772)
        (xy -2.057 1.738)
        (xy -2.073 1.712)
        (xy -2.094 1.695)
        (xy -2.122 1.684)
        (xy -2.156 1.681)
        (xy -2.159 1.681)
        (xy -2.192 1.683)
        (xy -2.22 1.691)
        (xy -2.243 1.705)
        (xy -2.26 1.725)
        (xy -2.273 1.753)
        (xy -2.281 1.788)
        (xy -2.285 1.832)
        (xy -2.286 1.877)
        (xy -2.413 1.877)
        (xy -2.413 1.559)
        (xy -2.286 1.559)
        (xy -2.286 1.62)
        (xy -2.26 1.6)
        (xy -2.225 1.577)
        (xy -2.19 1.563)
        (xy -2.154 1.554)
        (xy -2.109 1.552)
        (xy -2.065 1.559)
      )

      (stroke (width 0.01) (type solid)) (fill solid) (layer "F.Mask"))
    (fp_poly
      (pts
        (xy 0.063 -3.201)
        (xy 0.118 -3.201)
        (xy 0.164 -3.201)
        (xy 0.202 -3.2)
        (xy 0.233 -3.2)
        (xy 0.258 -3.2)
        (xy 0.277 -3.199)
        (xy 0.292 -3.198)
        (xy 0.302 -3.197)
        (xy 0.309 -3.196)
        (xy 0.314 -3.195)
        (xy 0.317 -3.193)
        (xy 0.319 -3.192)
        (xy 0.321 -3.189)
        (xy 0.324 -3.183)
        (xy 0.327 -3.174)
        (xy 0.33 -3.161)
        (xy 0.334 -3.144)
        (xy 0.339 -3.12)
        (xy 0.345 -3.091)
        (xy 0.352 -3.054)
        (xy 0.361 -3.01)
        (xy 0.371 -2.958)
        (xy 0.382 -2.897)
        (xy 0.385 -2.878)
        (xy 0.395 -2.824)
        (xy 0.405 -2.772)
        (xy 0.414 -2.724)
        (xy 0.423 -2.68)
        (xy 0.43 -2.642)
        (xy 0.437 -2.61)
        (xy 0.442 -2.586)
        (xy 0.446 -2.569)
        (xy 0.448 -2.562)
        (xy 0.456 -2.55)
        (xy 0.464 -2.544)
        (xy 0.476 -2.539)
        (xy 0.495 -2.53)
        (xy 0.521 -2.519)
        (xy 0.552 -2.506)
        (xy 0.587 -2.492)
        (xy 0.624 -2.477)
        (xy 0.664 -2.461)
        (xy 0.704 -2.445)
        (xy 0.743 -2.43)
        (xy 0.78 -2.415)
        (xy 0.814 -2.402)
        (xy 0.843 -2.391)
        (xy 0.868 -2.382)
        (xy 0.885 -2.376)
        (xy 0.895 -2.373)
        (xy 0.896 -2.373)
        (xy 0.911 -2.376)
        (xy 0.931 -2.386)
        (xy 0.948 -2.397)
        (xy 0.962 -2.406)
        (xy 0.983 -2.421)
        (xy 1.011 -2.44)
        (xy 1.043 -2.462)
        (xy 1.079 -2.487)
        (xy 1.118 -2.513)
        (xy 1.158 -2.541)
        (xy 1.198 -2.568)
        (xy 1.238 -2.595)
        (xy 1.275 -2.621)
        (xy 1.309 -2.644)
        (xy 1.338 -2.665)
        (xy 1.362 -2.681)
        (xy 1.377 -2.691)
        (xy 1.398 -2.705)
        (xy 1.418 -2.717)
        (xy 1.433 -2.725)
        (xy 1.442 -2.728)
        (xy 1.443 -2.728)
        (xy 1.448 -2.726)
        (xy 1.456 -2.72)
        (xy 1.468 -2.71)
        (xy 1.486 -2.694)
        (xy 1.508 -2.673)
        (xy 1.535 -2.647)
        (xy 1.568 -2.614)
        (xy 1.608 -2.575)
        (xy 1.654 -2.53)
        (xy 1.675 -2.509)
        (xy 1.721 -2.462)
        (xy 1.761 -2.422)
        (xy 1.794 -2.388)
        (xy 1.822 -2.36)
        (xy 1.844 -2.337)
        (xy 1.862 -2.318)
        (xy 1.875 -2.304)
        (xy 1.884 -2.293)
        (xy 1.89 -2.284)
        (xy 1.893 -2.279)
        (xy 1.894 -2.275)
        (xy 1.892 -2.269)
        (xy 1.886 -2.257)
        (xy 1.875 -2.239)
        (xy 1.86 -2.215)
        (xy 1.839 -2.183)
        (xy 1.814 -2.145)
        (xy 1.783 -2.1)
        (xy 1.747 -2.046)
        (xy 1.721 -2.009)
        (xy 1.69 -1.964)
        (xy 1.661 -1.921)
        (xy 1.634 -1.88)
        (xy 1.609 -1.844)
        (xy 1.588 -1.811)
        (xy 1.57 -1.785)
        (xy 1.557 -1.764)
        (xy 1.549 -1.75)
        (xy 1.546 -1.743)
        (xy 1.547 -1.735)
        (xy 1.552 -1.719)
        (xy 1.56 -1.696)
        (xy 1.571 -1.667)
        (xy 1.585 -1.634)
        (xy 1.6 -1.597)
        (xy 1.616 -1.557)
        (xy 1.633 -1.516)
        (xy 1.651 -1.476)
        (xy 1.668 -1.436)
        (xy 1.685 -1.398)
        (xy 1.701 -1.363)
        (xy 1.715 -1.333)
        (xy 1.727 -1.309)
        (xy 1.736 -1.291)
        (xy 1.742 -1.281)
        (xy 1.744 -1.279)
        (xy 1.751 -1.277)
        (xy 1.767 -1.273)
        (xy 1.791 -1.268)
        (xy 1.822 -1.261)
        (xy 1.86 -1.254)
        (xy 1.903 -1.245)
        (xy 1.951 -1.236)
        (xy 2.002 -1.226)
        (xy 2.049 -1.217)
        (xy 2.103 -1.207)
        (xy 2.154 -1.198)
        (xy 2.201 -1.188)
        (xy 2.244 -1.18)
        (xy 2.281 -1.173)
        (xy 2.311 -1.166)
        (xy 2.335 -1.161)
        (xy 2.35 -1.157)
        (xy 2.355 -1.156)
        (xy 2.367 -1.148)
        (xy 2.367 -0.834)
        (xy 2.367 -0.768)
        (xy 2.367 -0.712)
        (xy 2.367 -0.664)
        (xy 2.366 -0.625)
        (xy 2.366 -0.592)
        (xy 2.365 -0.566)
        (xy 2.364 -0.546)
        (xy 2.363 -0.531)
        (xy 2.361 -0.52)
        (xy 2.358 -0.512)
        (xy 2.355 -0.507)
        (xy 2.352 -0.504)
        (xy 2.348 -0.503)
        (xy 2.343 -0.501)
        (xy 2.34 -0.501)
        (xy 2.333 -0.499)
        (xy 2.317 -0.496)
        (xy 2.293 -0.492)
        (xy 2.261 -0.486)
        (xy 2.224 -0.479)
        (xy 2.181 -0.471)
        (xy 2.134 -0.462)
        (xy 2.084 -0.453)
        (xy 2.054 -0.448)
        (xy 2.002 -0.438)
        (xy 1.953 -0.429)
        (xy 1.907 -0.42)
        (xy 1.866 -0.412)
        (xy 1.831 -0.404)
        (xy 1.802 -0.398)
        (xy 1.78 -0.394)
        (xy 1.767 -0.391)
        (xy 1.764 -0.39)
        (xy 1.76 -0.387)
        (xy 1.757 -0.384)
        (xy 1.753 -0.379)
        (xy 1.748 -0.371)
        (xy 1.742 -0.36)
        (xy 1.735 -0.344)
        (xy 1.726 -0.324)
        (xy 1.715 -0.297)
        (xy 1.701 -0.264)
        (xy 1.685 -0.223)
        (xy 1.665 -0.174)
        (xy 1.653 -0.145)
        (xy 1.63 -0.086)
        (xy 1.61 -0.037)
        (xy 1.594 0.005)
        (xy 1.582 0.038)
        (xy 1.572 0.064)
        (xy 1.566 0.084)
        (xy 1.562 0.097)
        (xy 1.561 0.104)
        (xy 1.562 0.105)
        (xy 1.565 0.111)
        (xy 1.574 0.125)
        (xy 1.587 0.146)
        (xy 1.604 0.173)
        (xy 1.626 0.205)
        (xy 1.65 0.241)
        (xy 1.677 0.281)
        (xy 1.706 0.324)
        (xy 1.729 0.358)
        (xy 1.768 0.413)
        (xy 1.8 0.461)
        (xy 1.827 0.502)
        (xy 1.85 0.535)
        (xy 1.867 0.562)
        (xy 1.88 0.583)
        (xy 1.889 0.598)
        (xy 1.893 0.608)
        (xy 1.894 0.612)
        (xy 1.893 0.616)
        (xy 1.89 0.622)
        (xy 1.885 0.63)
        (xy 1.876 0.64)
        (xy 1.863 0.655)
        (xy 1.846 0.673)
        (xy 1.825 0.695)
        (xy 1.798 0.723)
        (xy 1.765 0.756)
        (xy 1.727 0.795)
        (xy 1.682 0.839)
        (xy 1.635 0.886)
        (xy 1.595 0.926)
        (xy 1.561 0.96)
        (xy 1.532 0.989)
        (xy 1.508 1.012)
        (xy 1.488 1.03)
        (xy 1.473 1.044)
        (xy 1.461 1.054)
        (xy 1.452 1.061)
        (xy 1.445 1.065)
        (xy 1.44 1.066)
        (xy 1.438 1.066)
        (xy 1.433 1.064)
        (xy 1.421 1.055)
        (xy 1.401 1.043)
        (xy 1.376 1.026)
        (xy 1.345 1.005)
        (xy 1.31 0.981)
        (xy 1.27 0.954)
        (xy 1.228 0.925)
        (xy 1.193 0.901)
        (xy 1.138 0.864)
        (xy 1.089 0.83)
        (xy 1.046 0.802)
        (xy 1.01 0.778)
        (xy 0.981 0.759)
        (xy 0.96 0.746)
        (xy 0.946 0.738)
        (xy 0.94 0.736)
        (xy 0.932 0.738)
        (xy 0.917 0.745)
        (xy 0.895 0.755)
        (xy 0.869 0.768)
        (xy 0.84 0.783)
        (xy 0.816 0.795)
        (xy 0.781 0.814)
        (xy 0.753 0.828)
        (xy 0.732 0.838)
        (xy 0.717 0.845)
        (xy 0.707 0.849)
        (xy 0.699 0.85)
        (xy 0.694 0.849)
        (xy 0.691 0.847)
        (xy 0.687 0.84)
        (xy 0.682 0.829)
        (xy 0.674 0.814)
        (xy 0.665 0.793)
        (xy 0.653 0.767)
        (xy 0.639 0.735)
        (xy 0.623 0.696)
        (xy 0.604 0.651)
        (xy 0.582 0.598)
        (xy 0.556 0.538)
        (xy 0.528 0.469)
        (xy 0.496 0.391)
        (xy 0.47 0.329)
        (xy 0.436 0.247)
        (xy 0.406 0.173)
        (xy 0.379 0.108)
        (xy 0.355 0.05)
        (xy 0.335 0)
        (xy 0.317 -0.043)
        (xy 0.303 -0.079)
        (xy 0.291 -0.11)
        (xy 0.281 -0.135)
        (xy 0.273 -0.155)
        (xy 0.268 -0.171)
        (xy 0.264 -0.183)
        (xy 0.262 -0.191)
        (xy 0.262 -0.196)
        (xy 0.262 -0.198)
        (xy 0.269 -0.207)
        (xy 0.283 -0.219)
        (xy 0.302 -0.233)
        (xy 0.303 -0.234)
        (xy 0.354 -0.268)
        (xy 0.398 -0.3)
        (xy 0.435 -0.331)
        (xy 0.469 -0.363)
        (xy 0.5 -0.397)
        (xy 0.507 -0.405)
        (xy 0.556 -0.472)
        (xy 0.596 -0.543)
        (xy 0.627 -0.619)
        (xy 0.643 -0.672)
        (xy 0.651 -0.718)
        (xy 0.657 -0.77)
        (xy 0.66 -0.824)
        (xy 0.659 -0.878)
        (xy 0.654 -0.927)
        (xy 0.652 -0.936)
        (xy 0.634 -1.015)
        (xy 0.607 -1.09)
        (xy 0.571 -1.161)
        (xy 0.528 -1.227)
        (xy 0.477 -1.287)
        (xy 0.419 -1.341)
        (xy 0.355 -1.387)
        (xy 0.285 -1.426)
        (xy 0.21 -1.456)
        (xy 0.205 -1.458)
        (xy 0.131 -1.477)
        (xy 0.054 -1.487)
        (xy -0.025 -1.489)
        (xy -0.103 -1.482)
        (xy -0.178 -1.466)
        (xy -0.206 -1.458)
        (xy -0.281 -1.428)
        (xy -0.351 -1.39)
        (xy -0.416 -1.344)
        (xy -0.474 -1.29)
        (xy -0.526 -1.23)
        (xy -0.571 -1.164)
        (xy -0.607 -1.093)
        (xy -0.63 -1.034)
        (xy -0.649 -0.96)
        (xy -0.659 -0.883)
        (xy -0.661 -0.804)
        (xy -0.654 -0.726)
        (xy -0.638 -0.651)
        (xy -0.63 -0.623)
        (xy -0.618 -0.591)
        (xy -0.602 -0.554)
        (xy -0.584 -0.518)
        (xy -0.566 -0.485)
        (xy -0.553 -0.463)
        (xy -0.509 -0.407)
        (xy -0.457 -0.352)
        (xy -0.397 -0.299)
        (xy -0.33 -0.25)
        (xy -0.289 -0.224)
        (xy -0.273 -0.212)
        (xy -0.263 -0.2)
        (xy -0.262 -0.197)
        (xy -0.263 -0.19)
        (xy -0.268 -0.175)
        (xy -0.277 -0.151)
        (xy -0.288 -0.121)
        (xy -0.302 -0.084)
        (xy -0.319 -0.042)
        (xy -0.338 0.005)
        (xy -0.358 0.056)
        (xy -0.381 0.111)
        (xy -0.404 0.168)
        (xy -0.428 0.228)
        (xy -0.453 0.288)
        (xy -0.478 0.349)
        (xy -0.504 0.41)
        (xy -0.529 0.47)
        (xy -0.553 0.527)
        (xy -0.576 0.583)
        (xy -0.598 0.635)
        (xy -0.619 0.683)
        (xy -0.638 0.727)
        (xy -0.655 0.765)
        (xy -0.669 0.797)
        (xy -0.68 0.822)
        (xy -0.689 0.839)
        (xy -0.694 0.848)
        (xy -0.695 0.849)
        (xy -0.699 0.85)
        (xy -0.706 0.849)
        (xy -0.717 0.845)
        (xy -0.732 0.839)
        (xy -0.752 0.829)
        (xy -0.779 0.815)
        (xy -0.814 0.797)
        (xy -0.817 0.795)
        (xy -0.848 0.779)
        (xy -0.877 0.764)
        (xy -0.902 0.752)
        (xy -0.922 0.743)
        (xy -0.936 0.737)
        (xy -0.941 0.736)
        (xy -0.949 0.739)
        (xy -0.964 0.748)
        (xy -0.987 0.761)
        (xy -1.015 0.78)
        (xy -1.05 0.803)
        (xy -1.072 0.818)
        (xy -1.138 0.863)
        (xy -1.195 0.903)
        (xy -1.245 0.937)
        (xy -1.289 0.966)
        (xy -1.325 0.991)
        (xy -1.356 1.012)
        (xy -1.381 1.029)
        (xy -1.401 1.042)
        (xy -1.416 1.052)
        (xy -1.427 1.059)
        (xy -1.435 1.064)
        (xy -1.439 1.066)
        (xy -1.44 1.066)
        (xy -1.449 1.064)
        (xy -1.453 1.061)
        (xy -1.458 1.057)
        (xy -1.47 1.046)
        (xy -1.487 1.029)
        (xy -1.509 1.007)
        (xy -1.537 0.98)
        (xy -1.568 0.95)
        (xy -1.602 0.915)
        (xy -1.639 0.879)
        (xy -1.678 0.84)
        (xy -1.678 0.839)
        (xy -1.726 0.792)
        (xy -1.767 0.751)
        (xy -1.801 0.716)
        (xy -1.829 0.687)
        (xy -1.852 0.663)
        (xy -1.869 0.644)
        (xy -1.882 0.63)
        (xy -1.89 0.62)
        (xy -1.894 0.613)
        (xy -1.895 0.61)
        (xy -1.892 0.603)
        (xy -1.884 0.588)
        (xy -1.87 0.565)
        (xy -1.85 0.536)
        (xy -1.826 0.499)
        (xy -1.797 0.455)
        (xy -1.763 0.405)
        (xy -1.73 0.358)
        (xy -1.7 0.313)
        (xy -1.671 0.271)
        (xy -1.645 0.232)
        (xy -1.621 0.197)
        (xy -1.601 0.166)
        (xy -1.584 0.141)
        (xy -1.572 0.121)
        (xy -1.565 0.109)
        (xy -1.563 0.105)
        (xy -1.563 0.099)
        (xy -1.566 0.087)
        (xy -1.572 0.07)
        (xy -1.58 0.045)
        (xy -1.592 0.013)
        (xy -1.607 -0.026)
        (xy -1.626 -0.074)
        (xy -1.648 -0.13)
        (xy -1.654 -0.145)
        (xy -1.676 -0.199)
        (xy -1.695 -0.245)
        (xy -1.71 -0.282)
        (xy -1.723 -0.313)
        (xy -1.733 -0.337)
        (xy -1.741 -0.356)
        (xy -1.748 -0.369)
        (xy -1.753 -0.379)
        (xy -1.758 -0.385)
        (xy -1.761 -0.388)
        (xy -1.763 -0.389)
        (xy -1.767 -0.39)
        (xy -1.774 -0.392)
        (xy -1.784 -0.395)
        (xy -1.799 -0.398)
        (xy -1.818 -0.402)
        (xy -1.843 -0.407)
        (xy -1.873 -0.413)
        (xy -1.91 -0.42)
        (xy -1.954 -0.429)
        (xy -2.005 -0.438)
        (xy -2.065 -0.449)
        (xy -2.133 -0.462)
        (xy -2.211 -0.477)
        (xy -2.22 -0.478)
        (xy -2.26 -0.486)
        (xy -2.29 -0.491)
        (xy -2.313 -0.496)
        (xy -2.33 -0.499)
        (xy -2.341 -0.502)
        (xy -2.349 -0.504)
        (xy -2.353 -0.506)
        (xy -2.356 -0.508)
        (xy -2.359 -0.51)
        (xy -2.36 -0.511)
        (xy -2.361 -0.514)
        (xy -2.363 -0.518)
        (xy -2.364 -0.526)
        (xy -2.365 -0.536)
        (xy -2.366 -0.551)
        (xy -2.366 -0.571)
        (xy -2.367 -0.597)
        (xy -2.367 -0.629)
        (xy -2.368 -0.668)
        (xy -2.368 -0.715)
        (xy -2.368 -0.771)
        (xy -2.368 -0.834)
        (xy -2.368 -1.148)
        (xy -2.356 -1.155)
        (xy -2.349 -1.158)
        (xy -2.333 -1.162)
        (xy -2.309 -1.167)
        (xy -2.278 -1.173)
        (xy -2.24 -1.181)
        (xy -2.197 -1.189)
        (xy -2.149 -1.198)
        (xy -2.098 -1.208)
        (xy -2.051 -1.217)
        (xy -1.996 -1.227)
        (xy -1.945 -1.237)
        (xy -1.897 -1.246)
        (xy -1.854 -1.254)
        (xy -1.817 -1.262)
        (xy -1.787 -1.268)
        (xy -1.764 -1.273)
        (xy -1.75 -1.277)
        (xy -1.745 -1.279)
        (xy -1.741 -1.285)
        (xy -1.733 -1.3)
        (xy -1.722 -1.322)
        (xy -1.709 -1.35)
        (xy -1.694 -1.382)
        (xy -1.677 -1.419)
        (xy -1.66 -1.458)
        (xy -1.642 -1.498)
        (xy -1.625 -1.539)
        (xy -1.608 -1.58)
        (xy -1.592 -1.618)
        (xy -1.578 -1.653)
        (xy -1.565 -1.684)
        (xy -1.556 -1.709)
        (xy -1.549 -1.729)
        (xy -1.546 -1.74)
        (xy -1.546 -1.742)
        (xy -1.549 -1.749)
        (xy -1.558 -1.763)
        (xy -1.571 -1.784)
        (xy -1.588 -1.811)
        (xy -1.61 -1.843)
        (xy -1.634 -1.88)
        (xy -1.661 -1.92)
        (xy -1.691 -1.963)
        (xy -1.722 -2.008)
        (xy -1.762 -2.067)
        (xy -1.796 -2.117)
        (xy -1.825 -2.16)
        (xy -1.848 -2.196)
        (xy -1.867 -2.225)
        (xy -1.881 -2.247)
        (xy -1.89 -2.262)
        (xy -1.895 -2.272)
        (xy -1.895 -2.275)
        (xy -1.894 -2.279)
        (xy -1.891 -2.285)
        (xy -1.884 -2.293)
        (xy -1.875 -2.305)
        (xy -1.861 -2.32)
        (xy -1.843 -2.339)
        (xy -1.82 -2.363)
        (xy -1.792 -2.392)
        (xy -1.758 -2.426)
        (xy -1.718 -2.466)
        (xy -1.676 -2.509)
        (xy -1.627 -2.557)
        (xy -1.585 -2.599)
        (xy -1.549 -2.634)
        (xy -1.52 -2.663)
        (xy -1.495 -2.686)
        (xy -1.476 -2.704)
        (xy -1.462 -2.716)
        (xy -1.452 -2.724)
        (xy -1.446 -2.728)
        (xy -1.444 -2.728)
        (xy -1.437 -2.726)
        (xy -1.423 -2.717)
        (xy -1.401 -2.703)
        (xy -1.372 -2.685)
        (xy -1.337 -2.661)
        (xy -1.295 -2.634)
        (xy -1.248 -2.602)
        (xy -1.196 -2.566)
        (xy -1.173 -2.551)
        (xy -1.118 -2.513)
        (xy -1.071 -2.481)
        (xy -1.031 -2.454)
        (xy -0.998 -2.432)
        (xy -0.97 -2.413)
        (xy -0.948 -2.399)
        (xy -0.931 -2.389)
        (xy -0.917 -2.381)
        (xy -0.907 -2.376)
        (xy -0.901 -2.373)
        (xy -0.897 -2.373)
        (xy -0.888 -2.375)
        (xy -0.87 -2.38)
        (xy -0.845 -2.39)
        (xy -0.813 -2.402)
        (xy -0.774 -2.417)
        (xy -0.73 -2.434)
        (xy -0.681 -2.454)
        (xy -0.629 -2.475)
        (xy -0.586 -2.493)
        (xy -0.55 -2.508)
        (xy -0.522 -2.52)
        (xy -0.499 -2.529)
        (xy -0.482 -2.537)
        (xy -0.47 -2.543)
        (xy -0.461 -2.548)
        (xy -0.455 -2.551)
        (xy -0.452 -2.554)
        (xy -0.449 -2.557)
        (xy -0.448 -2.56)
        (xy -0.447 -2.566)
        (xy -0.443 -2.582)
        (xy -0.438 -2.605)
        (xy -0.432 -2.637)
        (xy -0.425 -2.674)
        (xy -0.417 -2.717)
        (xy -0.407 -2.765)
        (xy -0.398 -2.817)
        (xy -0.388 -2.871)
        (xy -0.387 -2.876)
        (xy -0.375 -2.94)
        (xy -0.364 -2.995)
        (xy -0.356 -3.042)
        (xy -0.348 -3.081)
        (xy -0.342 -3.112)
        (xy -0.337 -3.137)
        (xy -0.332 -3.157)
        (xy -0.328 -3.171)
        (xy -0.325 -3.181)
        (xy -0.323 -3.188)
        (xy -0.32 -3.191)
        (xy -0.32 -3.192)
        (xy -0.317 -3.194)
        (xy -0.313 -3.195)
        (xy -0.307 -3.197)
        (xy -0.298 -3.198)
        (xy -0.286 -3.199)
        (xy -0.269 -3.199)
        (xy -0.247 -3.2)
        (xy -0.219 -3.2)
        (xy -0.184 -3.201)
        (xy -0.142 -3.201)
        (xy -0.092 -3.201)
        (xy -0.033 -3.201)
        (xy -0.001 -3.201)
        (xy 0.063 -3.201)
      )

      (stroke (width 0.01) (type solid)) (fill solid) (layer "F.Mask"))
    (fp_rect (start -4.05 -4.21) (end 4.06 4.21)
      (stroke (width 0.05) (type default)) (fill none) (layer "F.CrtYd"))
  )

  (footprint "antmicro-footprints:Oscillator_SMD_ECS_2016MV_2x1.6x0.85mm" (layer "F.Cu")
    (at 111.737 95.366 180)
    (property "Author" "Antmicro")
    (property "License" "Apache-2.0")
    (property "MPN" "ECS-2016MV-250-CN-TR")
    (property "Manufacturer" "ECS Inc. International")
    (property "Sheetfile" "ethernet.kicad_sch")
    (property "Sheetname" "Ethernet")
    (property "Val" "25 MHz")
    (property "ki_description" "Oscillator, 25 MHz, HCMOS, SMD, 2mm x 1.6mm, MultiVolt ECS-2016MV Series")
    (property "ki_keywords" "OSCILLATOR")
    (attr smd)
    (fp_text reference "Y5" (at -2.083 -0.734 90) (layer "F.SilkS")
        (effects (font (size 0.7 0.7) (thickness 0.15)) (justify left bottom))
    )
    (fp_text value "Oscillator_25MHz_ESC_2016MV" (at 0 2.2) (layer "F.Fab")
        (effects (font (size 0.7 0.7) (thickness 0.15)) (justify right bottom))
    )
    (fp_text user "Author: Antmicro" (at -1.05 4.6) (layer "F.Fab") hide
        (effects (font (size 0.7 0.7) (thickness 0.15)) (justify right bottom))
    )
    (fp_text user "${REFERENCE}" (at -1.05 3.4) (layer "F.Fab") hide
        (effects (font (size 0.7 0.7) (thickness 0.15)) (justify right bottom))
    )
    (fp_text user "License: Apache-2.0" (at -1.05 5.8) (layer "F.Fab") hide
        (effects (font (size 0.7 0.7) (thickness 0.15)) (justify right bottom))
    )
    (fp_line (start -0.95 0.4) (end -0.95 -0.4)
      (stroke (width 0.15) (type solid)) (layer "F.SilkS"))
    (fp_line (start -0.4 -1.15) (end 0.4 -1.15)
      (stroke (width 0.15) (type solid)) (layer "F.SilkS"))
    (fp_line (start -0.4 1.15) (end 0.4 1.15)
      (stroke (width 0.15) (type solid)) (layer "F.SilkS"))
    (fp_line (start 0.95 0.4) (end 0.95 -0.4)
      (stroke (width 0.15) (type solid)) (layer "F.SilkS"))
    (fp_circle (center -0.95 -1.15) (end -0.9 -1.15)
      (stroke (width 0.15) (type solid)) (fill solid) (layer "F.SilkS"))
    (fp_rect (start -1.05 -1.25) (end 1.05 1.24)
      (stroke (width 0.05) (type solid)) (fill none) (layer "F.CrtYd"))
    (fp_rect (start -0.85 -1.054) (end 0.852 1.054)
      (stroke (width 0.15) (type solid)) (fill none) (layer "F.Fab"))
    (pad "1" smd rect (at -0.486 -0.637 180) (size 0.6858 0.7874) (layers "F.Cu" "F.Paste" "F.Mask")
      (net 2 "VCC3V3") (pinfunction "EN") (pintype "input"))
    (pad "2" smd rect (at -0.486 0.636 180) (size 0.6858 0.7874) (layers "F.Cu" "F.Paste" "F.Mask")
      (net 1 "GND") (pinfunction "GND") (pintype "power_in"))
    (pad "3" smd rect (at 0.487 0.636 180) (size 0.6858 0.7874) (layers "F.Cu" "F.Paste" "F.Mask")
      (net 676 "/Ethernet/PHY_CLK") (pinfunction "OUT") (pintype "output"))
    (pad "4" smd rect (at 0.487 -0.637 180) (size 0.6858 0.7874) (layers "F.Cu" "F.Paste" "F.Mask")
      (net 2 "VCC3V3") (pinfunction "VDD") (pintype "power_in"))
  )

  (footprint "antmicro-footprints:QFN-56-1EP_8x8mm_P0.5mm" (layer "F.Cu")
    (at 136.75 90.02 -90)
    (descr "QFN 56 Pin")
    (tags "QFN")
    (property "Author" "Antmicro")
    (property "License" "Apache-2.0")
    (property "MPN" "FT4232H-56Q-REEL")
    (property "Manufacturer" "FTDI Chip")
    (property "Sheetfile" "interfaces.kicad_sch")
    (property "Sheetname" "Interfaces")
    (property "ki_description" "Interface Bridges, USB to UART, MPSSE, 1.62 V, 1.98 V, VQFN, 56 Pins, -40 °C")
    (property "ki_keywords" "SMT, INTERFACE, IC, CONTROLLER, USB, UART, I2C, SPI, JTAG")
    (attr smd)
    (fp_text reference "U14" (at 0 -5.32 90) (layer "F.SilkS")
        (effects (font (size 0.7 0.7) (thickness 0.15)))
    )
    (fp_text value "FT4232H_VQFN" (at 0 5.32 90) (layer "F.Fab")
        (effects (font (size 1 1) (thickness 0.15)))
    )
    (fp_text user "${REFERENCE}" (at 0 0 90) (layer "F.Fab")
        (effects (font (size 1 1) (thickness 0.15)))
    )
    (fp_text user "Author: Antmicro" (at -4.4 8.519 -90) (layer "F.Fab") hide
        (effects (font (size 0.7 0.7) (thickness 0.15)) (justify left bottom))
    )
    (fp_text user "License: Apache-2.0" (at -4.4 9.719 -90) (layer "F.Fab") hide
        (effects (font (size 0.7 0.7) (thickness 0.15)) (justify left bottom))
    )
    (fp_line (start -4.111 -3.635) (end -4.111 -4.111)
      (stroke (width 0.15) (type solid)) (layer "F.SilkS"))
    (fp_line (start -4.111 4.11) (end -4.111 3.634)
      (stroke (width 0.15) (type solid)) (layer "F.SilkS"))
    (fp_line (start -3.635 -4.111) (end -4.111 -4.111)
      (stroke (width 0.15) (type solid)) (layer "F.SilkS"))
    (fp_line (start -3.635 4.11) (end -4.111 4.11)
      (stroke (width 0.15) (type solid)) (layer "F.SilkS"))
    (fp_line (start 3.634 -4.111) (end 4.11 -4.111)
      (stroke (width 0.15) (type solid)) (layer "F.SilkS"))
    (fp_line (start 3.634 4.11) (end 4.11 4.11)
      (stroke (width 0.15) (type solid)) (layer "F.SilkS"))
    (fp_line (start 4.11 -4.111) (end 4.11 -3.635)
      (stroke (width 0.15) (type solid)) (layer "F.SilkS"))
    (fp_line (start 4.11 4.11) (end 4.11 3.634)
      (stroke (width 0.15) (type solid)) (layer "F.SilkS"))
    (fp_circle (center -4.35 -3.6) (end -4.3 -3.6)
      (stroke (width 0.15) (type solid)) (fill solid) (layer "F.SilkS"))
    (fp_rect (start 4.4 4.4) (end -4.4 -4.4)
      (stroke (width 0.05) (type solid)) (fill none) (layer "F.CrtYd"))
    (fp_line (start -4 -3) (end -3 -4)
      (stroke (width 0.15) (type solid)) (layer "F.Fab"))
    (fp_rect (start 4 4) (end -4 -4)
      (stroke (width 0.15) (type solid)) (fill none) (layer "F.Fab"))
    (pad "" smd roundrect (at -2.101 -2.101 270) (size 1.13 1.13) (layers "F.Paste") (roundrect_rratio 0.221239))
    (pad "" smd roundrect (at -2.101 -0.7 270) (size 1.13 1.13) (layers "F.Paste") (roundrect_rratio 0.221239))
    (pad "" smd roundrect (at -2.101 0.699 270) (size 1.13 1.13) (layers "F.Paste") (roundrect_rratio 0.221239))
    (pad "" smd roundrect (at -2.101 2.1 270) (size 1.13 1.13) (layers "F.Paste") (roundrect_rratio 0.221239))
    (pad "" smd roundrect (at -0.7 -2.101 270) (size 1.13 1.13) (layers "F.Paste") (roundrect_rratio 0.221239))
    (pad "" smd roundrect (at -0.7 -0.7 270) (size 1.13 1.13) (layers "F.Paste") (roundrect_rratio 0.221239))
    (pad "" smd roundrect (at -0.7 0.699 270) (size 1.13 1.13) (layers "F.Paste") (roundrect_rratio 0.221239))
    (pad "" smd roundrect (at -0.7 2.1 270) (size 1.13 1.13) (layers "F.Paste") (roundrect_rratio 0.221239))
    (pad "" smd roundrect (at 0.699 -2.101 270) (size 1.13 1.13) (layers "F.Paste") (roundrect_rratio 0.221239))
    (pad "" smd roundrect (at 0.699 -0.7 270) (size 1.13 1.13) (layers "F.Paste") (roundrect_rratio 0.221239))
    (pad "" smd roundrect (at 0.699 0.699 270) (size 1.13 1.13) (layers "F.Paste") (roundrect_rratio 0.221239))
    (pad "" smd roundrect (at 0.699 2.1 270) (size 1.13 1.13) (layers "F.Paste") (roundrect_rratio 0.221239))
    (pad "" smd roundrect (at 2.1 -2.101 270) (size 1.13 1.13) (layers "F.Paste") (roundrect_rratio 0.221239))
    (pad "" smd roundrect (at 2.1 -0.7 270) (size 1.13 1.13) (layers "F.Paste") (roundrect_rratio 0.221239))
    (pad "" smd roundrect (at 2.1 0.699 270) (size 1.13 1.13) (layers "F.Paste") (roundrect_rratio 0.221239))
    (pad "" smd roundrect (at 2.1 2.1 270) (size 1.13 1.13) (layers "F.Paste") (roundrect_rratio 0.221239))
    (pad "1" smd roundrect (at -3.938 -3.25 270) (size 0.875 0.3) (layers "F.Cu" "F.Paste" "F.Mask") (roundrect_rratio 0.25)
      (net 510 "unconnected-(U14-EECS-Pad1)") (pinfunction "EECS") (pintype "bidirectional+no_connect"))
    (pad "2" smd roundrect (at -3.938 -2.75 270) (size 0.875 0.3) (layers "F.Cu" "F.Paste" "F.Mask") (roundrect_rratio 0.25)
      (net 657 "VREGOUT") (pinfunction "V_{CORE}") (pintype "power_in"))
    (pad "3" smd roundrect (at -3.938 -2.25 270) (size 0.875 0.3) (layers "F.Cu" "F.Paste" "F.Mask") (roundrect_rratio 0.25)
      (net 511 "/Interfaces/FTDI_CLK") (pinfunction "OSCI") (pintype "input"))
    (pad "4" smd roundrect (at -3.938 -1.75 270) (size 0.875 0.3) (layers "F.Cu" "F.Paste" "F.Mask") (roundrect_rratio 0.25)
      (net 512 "unconnected-(U14-OSCO-Pad4)") (pinfunction "OSCO") (pintype "output+no_connect"))
    (pad "5" smd roundrect (at -3.938 -1.25 270) (size 0.875 0.3) (layers "F.Cu" "F.Paste" "F.Mask") (roundrect_rratio 0.25)
      (net 307 "Net-(U14-V_{PHY})") (pinfunction "V_{PHY}") (pintype "power_in"))
    (pad "6" smd roundrect (at -3.938 -0.75 270) (size 0.875 0.3) (layers "F.Cu" "F.Paste" "F.Mask") (roundrect_rratio 0.25)
      (net 433 "Net-(U14-REF)") (pinfunction "REF") (pintype "input"))
    (pad "7" smd roundrect (at -3.938 -0.25 270) (size 0.875 0.3) (layers "F.Cu" "F.Paste" "F.Mask") (roundrect_rratio 0.25)
      (net 416 "DBG_USB_D_N") (pinfunction "D-") (pintype "bidirectional"))
    (pad "8" smd roundrect (at -3.938 0.249 270) (size 0.875 0.3) (layers "F.Cu" "F.Paste" "F.Mask") (roundrect_rratio 0.25)
      (net 417 "DBG_USB_D_P") (pinfunction "D+") (pintype "bidirectional"))
    (pad "9" smd roundrect (at -3.938 0.749 270) (size 0.875 0.3) (layers "F.Cu" "F.Paste" "F.Mask") (roundrect_rratio 0.25)
      (net 306 "Net-(U14-V_{PLL})") (pinfunction "V_{PLL}") (pintype "power_in"))
    (pad "10" smd roundrect (at -3.938 1.249 270) (size 0.875 0.3) (layers "F.Cu" "F.Paste" "F.Mask") (roundrect_rratio 0.25)
      (net 1 "GND") (pinfunction "TEST") (pintype "input"))
    (pad "11" smd roundrect (at -3.938 1.749 270) (size 0.875 0.3) (layers "F.Cu" "F.Paste" "F.Mask") (roundrect_rratio 0.25)
      (net 432 "Net-(U14-~{RESET})") (pinfunction "~{RESET}") (pintype "input"))
    (pad "12" smd roundrect (at -3.938 2.249 270) (size 0.875 0.3) (layers "F.Cu" "F.Paste" "F.Mask") (roundrect_rratio 0.25)
      (net 21 "JTAG_TCK") (pinfunction "ADBUS0") (pintype "bidirectional"))
    (pad "13" smd roundrect (at -3.938 2.749 270) (size 0.875 0.3) (layers "F.Cu" "F.Paste" "F.Mask") (roundrect_rratio 0.25)
      (net 19 "JTAG_TDI") (pinfunction "ADBUS1") (pintype "bidirectional"))
    (pad "14" smd roundrect (at -3.938 3.249 270) (size 0.875 0.3) (layers "F.Cu" "F.Paste" "F.Mask") (roundrect_rratio 0.25)
      (net 20 "JTAG_TDO") (pinfunction "ADBUS2") (pintype "bidirectional"))
    (pad "15" smd roundrect (at -3.25 3.937) (size 0.875 0.3) (layers "F.Cu" "F.Paste" "F.Mask") (roundrect_rratio 0.25)
      (net 22 "JTAG_TMS") (pinfunction "ADBUS3") (pintype "bidirectional"))
    (pad "16" smd roundrect (at -2.75 3.937) (size 0.875 0.3) (layers "F.Cu" "F.Paste" "F.Mask") (roundrect_rratio 0.25)
      (net 2 "VCC3V3") (pinfunction "V_{CCIO}") (pintype "power_in"))
    (pad "17" smd roundrect (at -2.25 3.937) (size 0.875 0.3) (layers "F.Cu" "F.Paste" "F.Mask") (roundrect_rratio 0.25)
      (net 513 "unconnected-(U14-ADBUS4-Pad17)") (pinfunction "ADBUS4") (pintype "bidirectional+no_connect"))
    (pad "18" smd roundrect (at -1.75 3.937) (size 0.875 0.3) (layers "F.Cu" "F.Paste" "F.Mask") (roundrect_rratio 0.25)
      (net 514 "unconnected-(U14-ADBUS5-Pad18)") (pinfunction "ADBUS5") (pintype "bidirectional+no_connect"))
    (pad "19" smd roundrect (at -1.25 3.937) (size 0.875 0.3) (layers "F.Cu" "F.Paste" "F.Mask") (roundrect_rratio 0.25)
      (net 515 "unconnected-(U14-ADBUS6-Pad19)") (pinfunction "ADBUS6") (pintype "bidirectional+no_connect"))
    (pad "20" smd roundrect (at -0.75 3.937) (size 0.875 0.3) (layers "F.Cu" "F.Paste" "F.Mask") (roundrect_rratio 0.25)
      (net 516 "unconnected-(U14-ADBUS7-Pad20)") (pinfunction "ADBUS7") (pintype "bidirectional+no_connect"))
    (pad "21" smd roundrect (at -0.25 3.937) (size 0.875 0.3) (layers "F.Cu" "F.Paste" "F.Mask") (roundrect_rratio 0.25)
      (net 1 "GND") (pinfunction "GND") (pintype "power_in"))
    (pad "22" smd roundrect (at 0.249 3.937) (size 0.875 0.3) (layers "F.Cu" "F.Paste" "F.Mask") (roundrect_rratio 0.25)
      (net 517 "unconnected-(U14-BDBUS0-Pad22)") (pinfunction "BDBUS0") (pintype "bidirectional+no_connect"))
    (pad "23" smd roundrect (at 0.749 3.937) (size 0.875 0.3) (layers "F.Cu" "F.Paste" "F.Mask") (roundrect_rratio 0.25)
      (net 518 "unconnected-(U14-BDBUS1-Pad23)") (pinfunction "BDBUS1") (pintype "bidirectional+no_connect"))
    (pad "24" smd roundrect (at 1.249 3.937) (size 0.875 0.3) (layers "F.Cu" "F.Paste" "F.Mask") (roundrect_rratio 0.25)
      (net 519 "unconnected-(U14-BDBUS2-Pad24)") (pinfunction "BDBUS2") (pintype "bidirectional+no_connect"))
    (pad "25" smd roundrect (at 1.749 3.937) (size 0.875 0.3) (layers "F.Cu" "F.Paste" "F.Mask") (roundrect_rratio 0.25)
      (net 520 "unconnected-(U14-BDBUS3-Pad25)") (pinfunction "BDBUS3") (pintype "bidirectional+no_connect"))
    (pad "26" smd roundrect (at 2.249 3.937) (size 0.875 0.3) (layers "F.Cu" "F.Paste" "F.Mask") (roundrect_rratio 0.25)
      (net 521 "unconnected-(U14-BDBUS4-Pad26)") (pinfunction "BDBUS4") (pintype "bidirectional+no_connect"))
    (pad "27" smd roundrect (at 2.749 3.937) (size 0.875 0.3) (layers "F.Cu" "F.Paste" "F.Mask") (roundrect_rratio 0.25)
      (net 522 "unconnected-(U14-BDBUS5-Pad27)") (pinfunction "BDBUS5") (pintype "bidirectional+no_connect"))
    (pad "28" smd roundrect (at 3.249 3.937) (size 0.875 0.3) (layers "F.Cu" "F.Paste" "F.Mask") (roundrect_rratio 0.25)
      (net 523 "unconnected-(U14-BDBUS6-Pad28)") (pinfunction "BDBUS6") (pintype "bidirectional+no_connect"))
    (pad "29" smd roundrect (at 3.937 3.249 270) (size 0.875 0.3) (layers "F.Cu" "F.Paste" "F.Mask") (roundrect_rratio 0.25)
      (net 524 "unconnected-(U14-BDBUS7-Pad29)") (pinfunction "BDBUS7") (pintype "bidirectional+no_connect"))
    (pad "30" smd roundrect (at 3.937 2.749 270) (size 0.875 0.3) (layers "F.Cu" "F.Paste" "F.Mask") (roundrect_rratio 0.25)
      (net 436 "Net-(U14-~{SUSPEND})") (pinfunction "~{SUSPEND}") (pintype "output"))
    (pad "31" smd roundrect (at 3.937 2.249 270) (size 0.875 0.3) (layers "F.Cu" "F.Paste" "F.Mask") (roundrect_rratio 0.25)
      (net 657 "VREGOUT") (pinfunction "V_{CORE}") (pintype "passive"))
    (pad "32" smd roundrect (at 3.937 1.749 270) (size 0.875 0.3) (layers "F.Cu" "F.Paste" "F.Mask") (roundrect_rratio 0.25)
      (net 525 "unconnected-(U14-CDBUS0-Pad32)") (pinfunction "CDBUS0") (pintype "bidirectional+no_connect"))
    (pad "33" smd roundrect (at 3.937 1.249 270) (size 0.875 0.3) (layers "F.Cu" "F.Paste" "F.Mask") (roundrect_rratio 0.25)
      (net 526 "unconnected-(U14-CDBUS1-Pad33)") (pinfunction "CDBUS1") (pintype "bidirectional+no_connect"))
    (pad "34" smd roundrect (at 3.937 0.749 270) (size 0.875 0.3) (layers "F.Cu" "F.Paste" "F.Mask") (roundrect_rratio 0.25)
      (net 527 "unconnected-(U14-CDBUS2-Pad34)") (pinfunction "CDBUS2") (pintype "bidirectional+no_connect"))
    (pad "35" smd roundrect (at 3.937 0.249 270) (size 0.875 0.3) (layers "F.Cu" "F.Paste" "F.Mask") (roundrect_rratio 0.25)
      (net 528 "unconnected-(U14-CDBUS3-Pad35)") (pinfunction "CDBUS3") (pintype "bidirectional+no_connect"))
    (pad "36" smd roundrect (at 3.937 -0.25 270) (size 0.875 0.3) (layers "F.Cu" "F.Paste" "F.Mask") (roundrect_rratio 0.25)
      (net 2 "VCC3V3") (pinfunction "V_{CCIO}") (pintype "passive"))
    (pad "37" smd roundrect (at 3.937 -0.75 270) (size 0.875 0.3) (layers "F.Cu" "F.Paste" "F.Mask") (roundrect_rratio 0.25)
      (net 529 "unconnected-(U14-CDBUS4-Pad37)") (pinfunction "CDBUS4") (pintype "bidirectional+no_connect"))
    (pad "38" smd roundrect (at 3.937 -1.25 270) (size 0.875 0.3) (layers "F.Cu" "F.Paste" "F.Mask") (roundrect_rratio 0.25)
      (net 530 "unconnected-(U14-CDBUS5-Pad38)") (pinfunction "CDBUS5") (pintype "bidirectional+no_connect"))
    (pad "39" smd roundrect (at 3.937 -1.75 270) (size 0.875 0.3) (layers "F.Cu" "F.Paste" "F.Mask") (roundrect_rratio 0.25)
      (net 531 "unconnected-(U14-CDBUS6-Pad39)") (pinfunction "CDBUS6") (pintype "bidirectional+no_connect"))
    (pad "40" smd roundrect (at 3.937 -2.25 270) (size 0.875 0.3) (layers "F.Cu" "F.Paste" "F.Mask") (roundrect_rratio 0.25)
      (net 532 "unconnected-(U14-CDBUS7-Pad40)") (pinfunction "CDBUS7") (pintype "bidirectional+no_connect"))
    (pad "41" smd roundrect (at 3.937 -2.75 270) (size 0.875 0.3) (layers "F.Cu" "F.Paste" "F.Mask") (roundrect_rratio 0.25)
      (net 1 "GND") (pinfunction "GND") (pintype "passive"))
    (pad "42" smd roundrect (at 3.937 -3.25 270) (size 0.875 0.3) (layers "F.Cu" "F.Paste" "F.Mask") (roundrect_rratio 0.25)
      (net 533 "unconnected-(U14-DDBUS0-Pad42)") (pinfunction "DDBUS0") (pintype "bidirectional+no_connect"))
    (pad "43" smd roundrect (at 3.249 -3.938) (size 0.875 0.3) (layers "F.Cu" "F.Paste" "F.Mask") (roundrect_rratio 0.25)
      (net 657 "VREGOUT") (pinfunction "V_{REGOUT}") (pintype "power_out"))
    (pad "44" smd roundrect (at 2.749 -3.938) (size 0.875 0.3) (layers "F.Cu" "F.Paste" "F.Mask") (roundrect_rratio 0.25)
      (net 2 "VCC3V3") (pinfunction "V_{REGIN}") (pintype "power_in"))
    (pad "45" smd roundrect (at 2.249 -3.938) (size 0.875 0.3) (layers "F.Cu" "F.Paste" "F.Mask") (roundrect_rratio 0.25)
      (net 1 "GND") (pinfunction "GND") (pintype "passive"))
    (pad "46" smd roundrect (at 1.749 -3.938) (size 0.875 0.3) (layers "F.Cu" "F.Paste" "F.Mask") (roundrect_rratio 0.25)
      (net 534 "unconnected-(U14-DDBUS1-Pad46)") (pinfunction "DDBUS1") (pintype "bidirectional+no_connect"))
    (pad "47" smd roundrect (at 1.249 -3.938) (size 0.875 0.3) (layers "F.Cu" "F.Paste" "F.Mask") (roundrect_rratio 0.25)
      (net 535 "unconnected-(U14-DDBUS2-Pad47)") (pinfunction "DDBUS2") (pintype "bidirectional+no_connect"))
    (pad "48" smd roundrect (at 0.749 -3.938) (size 0.875 0.3) (layers "F.Cu" "F.Paste" "F.Mask") (roundrect_rratio 0.25)
      (net 536 "unconnected-(U14-DDBUS3-Pad48)") (pinfunction "DDBUS3") (pintype "bidirectional+no_connect"))
    (pad "49" smd roundrect (at 0.249 -3.938) (size 0.875 0.3) (layers "F.Cu" "F.Paste" "F.Mask") (roundrect_rratio 0.25)
      (net 537 "unconnected-(U14-DDBUS4-Pad49)") (pinfunction "DDBUS4") (pintype "bidirectional+no_connect"))
    (pad "50" smd roundrect (at -0.25 -3.938) (size 0.875 0.3) (layers "F.Cu" "F.Paste" "F.Mask") (roundrect_rratio 0.25)
      (net 2 "VCC3V3") (pinfunction "V_{CCIO}") (pintype "passive"))
    (pad "51" smd roundrect (at -0.75 -3.938) (size 0.875 0.3) (layers "F.Cu" "F.Paste" "F.Mask") (roundrect_rratio 0.25)
      (net 538 "unconnected-(U14-DDBUS5-Pad51)") (pinfunction "DDBUS5") (pintype "bidirectional+no_connect"))
    (pad "52" smd roundrect (at -1.25 -3.938) (size 0.875 0.3) (layers "F.Cu" "F.Paste" "F.Mask") (roundrect_rratio 0.25)
      (net 539 "unconnected-(U14-DDBUS6-Pad52)") (pinfunction "DDBUS6") (pintype "bidirectional+no_connect"))
    (pad "53" smd roundrect (at -1.75 -3.938) (size 0.875 0.3) (layers "F.Cu" "F.Paste" "F.Mask") (roundrect_rratio 0.25)
      (net 434 "Net-(U14-DDBUS7)") (pinfunction "DDBUS7") (pintype "bidirectional"))
    (pad "54" smd roundrect (at -2.25 -3.938) (size 0.875 0.3) (layers "F.Cu" "F.Paste" "F.Mask") (roundrect_rratio 0.25)
      (net 435 "Net-(U14-~{PWR_{EN}})") (pinfunction "~{PWR_{EN}}") (pintype "output"))
    (pad "55" smd roundrect (at -2.75 -3.938) (size 0.875 0.3) (layers "F.Cu" "F.Paste" "F.Mask") (roundrect_rratio 0.25)
      (net 540 "unconnected-(U14-EEDATA-Pad55)") (pinfunction "EEDATA") (pintype "bidirectional+no_connect"))
    (pad "56" smd roundrect (at -3.25 -3.938) (size 0.875 0.3) (layers "F.Cu" "F.Paste" "F.Mask") (roundrect_rratio 0.25)
      (net 541 "unconnected-(U14-EECLK-Pad56)") (pinfunction "EECLK") (pintype "output+no_connect"))
    (pad "57" smd rect (at 0 0 270) (size 5.9 5.9) (layers "F.Cu" "F.Mask")
      (net 1 "GND") (pinfunction "GND") (pintype "passive"))
  )

  (footprint "antmicro-footprints:PinSocket_2x6_P2.54mm_Drill1.02mm_PMOD" (layer "F.Cu")
    (at 64.6 100.755 90)
    (descr "http://portal.fciconnect.com/Comergent//fci/drawing/68020.pdf")
    (property "Author" "Antmicro")
    (property "License" "Apache-2.0")
    (property "MPN" "M20-7830642")
    (property "Manufacturer" "Harwin")
    (property "Sheetfile" "rot.kicad_sch")
    (property "Sheetname" "RoT")
    (property "ki_description" "PCB Receptacle, Board-to-Board, 2.54 mm, 2 Rows, 12 Contacts, Through Hole Mount, M20")
    (property "ki_keywords" "CONNECTOR, HEADER")
    (attr through_hole)
    (fp_text reference "J4" (at 4.42 0.06 180) (layer "F.SilkS")
        (effects (font (size 0.7 0.7) (thickness 0.15)) (justify left bottom))
    )
    (fp_text value "PinSocket_2x6_P2.54mm_Drill1.02mm_PMOD" (at 1.6 15.8 90) (layer "F.Fab")
        (effects (font (size 0.7 0.7) (thickness 0.15)) (justify left bottom))
    )
    (fp_text user "${REFERENCE}" (at -1.52 17.8 90) (layer "F.Fab") hide
        (effects (font (size 0.7 0.7) (thickness 0.15)) (justify left bottom))
    )
    (fp_text user "License: Apache-2.0" (at -1.52 20.199 90) (layer "F.Fab") hide
        (effects (font (size 0.7 0.7) (thickness 0.15)) (justify left bottom))
    )
    (fp_text user "Author: Antmicro" (at -1.52 18.998 90) (layer "F.Fab") hide
        (effects (font (size 0.7 0.7) (thickness 0.15)) (justify left bottom))
    )
    (fp_line (start -1.401 -1.401) (end -1.401 -1)
      (stroke (width 0.15) (type solid)) (layer "F.SilkS"))
    (fp_line (start -1.401 -1.401) (end -1 -1.401)
      (stroke (width 0.15) (type solid)) (layer "F.SilkS"))
    (fp_line (start -1.401 14.098) (end -1.401 13.698)
      (stroke (width 0.15) (type solid)) (layer "F.SilkS"))
    (fp_line (start -1.401 14.098) (end -1 14.098)
      (stroke (width 0.15) (type solid)) (layer "F.SilkS"))
    (fp_line (start 3.898 -1.401) (end 3.499 -1.401)
      (stroke (width 0.15) (type solid)) (layer "F.SilkS"))
    (fp_line (start 3.898 -1.401) (end 3.898 -1)
      (stroke (width 0.15) (type solid)) (layer "F.SilkS"))
    (fp_line (start 3.898 14.098) (end 3.499 14.098)
      (stroke (width 0.15) (type solid)) (layer "F.SilkS"))
    (fp_line (start 3.898 14.098) (end 3.898 13.698)
      (stroke (width 0.15) (type solid)) (layer "F.SilkS"))
    (fp_line (start -1.52 -1.52) (end 4.04 -1.52)
      (stroke (width 0.05) (type solid)) (layer "F.CrtYd"))
    (fp_line (start -1.52 14.22) (end -1.52 -1.52)
      (stroke (width 0.05) (type solid)) (layer "F.CrtYd"))
    (fp_line (start -1.52 14.22) (end 4.04 14.22)
      (stroke (width 0.05) (type solid)) (layer "F.CrtYd"))
    (fp_line (start 4.04 14.22) (end 4.04 -1.52)
      (stroke (width 0.05) (type solid)) (layer "F.CrtYd"))
    (fp_line (start -1.27 -1.27) (end -1.27 13.97)
      (stroke (width 0.15) (type solid)) (layer "F.Fab"))
    (fp_line (start -1.27 -1.27) (end 3.809 -1.27)
      (stroke (width 0.15) (type solid)) (layer "F.Fab"))
    (fp_line (start -1.27 13.97) (end 3.809 13.97)
      (stroke (width 0.15) (type solid)) (layer "F.Fab"))
    (fp_line (start 3.809 -1.27) (end 3.809 13.97)
      (stroke (width 0.15) (type solid)) (layer "F.Fab"))
    (pad "1" thru_hole circle (at 0 0 90) (size 1.8 1.8) (drill 1.02) (layers "*.Cu" "*.Mask")
      (net 53 "SPI0_CS_N") (pintype "passive"))
    (pad "2" thru_hole circle (at 0 2.539 90) (size 1.8 1.8) (drill 1.02) (layers "*.Cu" "*.Mask")
      (net 55 "SPI0_MOSI") (pintype "passive"))
    (pad "3" thru_hole circle (at 0 5.078 90) (size 1.8 1.8) (drill 1.02) (layers "*.Cu" "*.Mask")
      (net 56 "SPI0_MISO") (pintype "passive"))
    (pad "4" thru_hole circle (at 0 7.618 90) (size 1.8 1.8) (drill 1.02) (layers "*.Cu" "*.Mask")
      (net 54 "SPI0_CLK") (pintype "passive"))
    (pad "5" thru_hole circle (at 0 10.159 90) (size 1.8 1.8) (drill 1.02) (layers "*.Cu" "*.Mask")
      (net 1 "GND") (pintype "passive"))
    (pad "6" thru_hole circle (at 0 12.698 90) (size 1.8 1.8) (drill 1.02) (layers "*.Cu" "*.Mask")
      (net 2 "VCC3V3") (pintype "passive"))
    (pad "7" thru_hole circle (at 2.539 0 90) (size 1.8 1.8) (drill 1.02) (layers "*.Cu" "*.Mask")
      (net 410 "PIRQ#") (pintype "passive"))
    (pad "8" thru_hole circle (at 2.539 2.539 90) (size 1.8 1.8) (drill 1.02) (layers "*.Cu" "*.Mask")
      (net 411 "RST") (pintype "passive"))
    (pad "9" thru_hole circle (at 2.539 5.078 90) (size 1.8 1.8) (drill 1.02) (layers "*.Cu" "*.Mask")
      (net 412 "GPIO") (pintype "passive"))
    (pad "10" thru_hole circle (at 2.539 7.618 90) (size 1.8 1.8) (drill 1.02) (layers "*.Cu" "*.Mask")
      (net 413 "PP") (pintype "passive"))
    (pad "11" thru_hole circle (at 2.539 10.159 90) (size 1.8 1.8) (drill 1.02) (layers "*.Cu" "*.Mask")
      (net 1 "GND") (pintype "passive"))
    (pad "12" thru_hole circle (at 2.539 12.698 90) (size 1.8 1.8) (drill 1.02) (layers "*.Cu" "*.Mask")
      (net 2 "VCC3V3") (pintype "passive"))
  )

  (footprint "antmicro-footprints:PinHeader_2x7_P2mm_Drill1mm_Shrouded" (layer "F.Cu")
    (at 142.64 68.565 180)
    (property "Author" "Antmicro")
    (property "License" "Apache-2.0")
    (property "MPN" "0878311420")
    (property "Manufacturer" "Molex")
    (property "Sheetfile" "interfaces.kicad_sch")
    (property "Sheetname" "Interfaces")
    (property "ki_description" "Pin Header, Wire-to-Board, 2 mm, 2 Rows, 14 Contacts, Surface Mount Straight, Milli-Grid 87832")
    (property "ki_keywords" "PINSTRIP, HEADER ")
    (attr through_hole)
    (fp_text reference "J9" (at -2.06 -5.45) (layer "F.SilkS")
        (effects (font (size 0.7 0.7) (thickness 0.15)) (justify right bottom))
    )
    (fp_text value "PinHeader_2x7_P2mm_Drill1mm_Shrouded" (at 0 3.4) (layer "F.Fab")
        (effects (font (size 0.7 0.7) (thickness 0.15)) (justify right bottom))
    )
    (fp_text user "License: Apache-2.0" (at -14.7 7.9) (layer "F.Fab") hide
        (effects (font (size 0.7 0.7) (thickness 0.15)) (justify right bottom))
    )
    (fp_text user "Author: Antmicro" (at -14.7 9.2) (layer "F.Fab") hide
        (effects (font (size 0.7 0.7) (thickness 0.15)) (justify right bottom))
    )
    (fp_text user "${REFERENCE}" (at -14.7 6.7) (layer "F.Fab") hide
        (effects (font (size 0.7 0.7) (thickness 0.15)) (justify right bottom))
    )
    (fp_line (start -2.41 2.2) (end 4.7 2.2)
      (stroke (width 0.15) (type solid)) (layer "F.SilkS"))
    (fp_line (start -2.4 -4.2) (end 14.4 -4.2)
      (stroke (width 0.15) (type solid)) (layer "F.SilkS"))
    (fp_line (start -2.4 2.2) (end -2.4 -4.2)
      (stroke (width 0.15) (type solid)) (layer "F.SilkS"))
    (fp_line (start 14.4 -4.2) (end 14.4 2.2)
      (stroke (width 0.15) (type solid)) (layer "F.SilkS"))
    (fp_line (start 14.4 2.2) (end 7.3 2.2)
      (stroke (width 0.15) (type solid)) (layer "F.SilkS"))
    (fp_line (start -2.51 -4.34) (end 14.51 -4.34)
      (stroke (width 0.05) (type solid)) (layer "F.CrtYd"))
    (fp_line (start -2.51 2.34) (end -2.51 -4.34)
      (stroke (width 0.05) (type solid)) (layer "F.CrtYd"))
    (fp_line (start -2.51 2.34) (end 14.51 2.34)
      (stroke (width 0.05) (type solid)) (layer "F.CrtYd"))
    (fp_line (start 14.51 2.34) (end 14.51 -4.34)
      (stroke (width 0.05) (type solid)) (layer "F.CrtYd"))
    (fp_line (start -2.33 2.15) (end -2.33 -4.13)
      (stroke (width 0.15) (type solid)) (layer "F.Fab"))
    (fp_line (start 14.356 -4.15) (end -2.32 -4.15)
      (stroke (width 0.15) (type solid)) (layer "F.Fab"))
    (fp_line (start 14.356 1.898) (end 14.356 -4.15)
      (stroke (width 0.15) (type solid)) (layer "F.Fab"))
    (fp_line (start 14.356 2.15) (end -2.293 2.15)
      (stroke (width 0.15) (type solid)) (layer "F.Fab"))
    (pad "1" thru_hole rect (at 0 0) (size 1.75 1.75) (drill 1) (layers "*.Cu" "*.Mask")
      (net 1 "GND") (pintype "passive"))
    (pad "2" thru_hole circle (at 0 -1.999) (size 1.75 1.75) (drill 1) (layers "*.Cu" "*.Mask")
      (net 2 "VCC3V3") (pintype "passive"))
    (pad "3" thru_hole circle (at 2 0) (size 1.75 1.75) (drill 1) (layers "*.Cu" "*.Mask")
      (net 1 "GND") (pintype "passive"))
    (pad "4" thru_hole circle (at 2 -1.999) (size 1.75 1.75) (drill 1) (layers "*.Cu" "*.Mask")
      (net 22 "JTAG_TMS") (pintype "passive"))
    (pad "5" thru_hole circle (at 4 0) (size 1.75 1.75) (drill 1) (layers "*.Cu" "*.Mask")
      (net 1 "GND") (pintype "passive"))
    (pad "6" thru_hole circle (at 4 -1.999) (size 1.75 1.75) (drill 1) (layers "*.Cu" "*.Mask")
      (net 21 "JTAG_TCK") (pintype "passive"))
    (pad "7" thru_hole circle (at 6 0) (size 1.75 1.75) (drill 1) (layers "*.Cu" "*.Mask")
      (net 1 "GND") (pintype "passive"))
    (pad "8" thru_hole circle (at 6 -1.999) (size 1.75 1.75) (drill 1) (layers "*.Cu" "*.Mask")
      (net 20 "JTAG_TDO") (pintype "passive"))
    (pad "9" thru_hole circle (at 8 0) (size 1.75 1.75) (drill 1) (layers "*.Cu" "*.Mask")
      (net 1 "GND") (pintype "passive"))
    (pad "10" thru_hole circle (at 8 -1.999) (size 1.75 1.75) (drill 1) (layers "*.Cu" "*.Mask")
      (net 19 "JTAG_TDI") (pintype "passive"))
    (pad "11" thru_hole circle (at 10 0) (size 1.75 1.75) (drill 1) (layers "*.Cu" "*.Mask")
      (net 1 "GND") (pintype "passive"))
    (pad "12" thru_hole circle (at 10 -1.999) (size 1.75 1.75) (drill 1) (layers "*.Cu" "*.Mask")
      (net 425 "unconnected-(J9-Pad12)") (pintype "passive+no_connect"))
    (pad "13" thru_hole circle (at 12 0) (size 1.75 1.75) (drill 1) (layers "*.Cu" "*.Mask")
      (net 1 "GND") (pintype "passive"))
    (pad "14" thru_hole circle (at 12 -1.999) (size 1.75 1.75) (drill 1) (layers "*.Cu" "*.Mask")
      (net 426 "unconnected-(J9-Pad14)") (pintype "passive+no_connect"))
  )

  (footprint "antmicro-footprints:Spacer_Drill3.7mm_H4mm_9774040151R" (layer "F.Cu")
    (at 73.811 112.426)
    (descr "Spacer steel M2.5 h=4mm fi=5.1mm")
    (property "Author" "Antmicro")
    (property "License" "Apache-2.0")
    (property "MPN" "9774040151R")
    (property "Manufacturer" "Würth Elektronik")
    (property "Public" "False")
    (property "Sheetfile" "rot.kicad_sch")
    (property "Sheetname" "RoT")
    (property "ki_description" "Round Standoff Threaded M2.5x0.45 Steel 0.157\" (4.00mm)")
    (property "ki_keywords" "SPACER")
    (attr smd)
    (fp_text reference "H2" (at 0 -3.15) (layer "F.SilkS")
        (effects (font (size 0.7 0.7) (thickness 0.15)) (justify left bottom))
    )
    (fp_text value "Spacer_Drill3.7mm_H4mm_9774040151R" (at 0 3.95) (layer "F.Fab")
        (effects (font (size 0.7 0.7) (thickness 0.15)) (justify left bottom))
    )
    (fp_text user "${REFERENCE}" (at -2.551 6.349) (layer "F.Fab") hide
        (effects (font (size 0.7 0.7) (thickness 0.15)) (justify left bottom))
    )
    (fp_text user "License: Apache-2.0" (at -2.551 8.749) (layer "F.Fab") hide
        (effects (font (size 0.7 0.7) (thickness 0.15)) (justify left bottom))
    )
    (fp_text user "Author: Antmicro" (at -2.551 7.549) (layer "F.Fab") hide
        (effects (font (size 0.7 0.7) (thickness 0.15)) (justify left bottom))
    )
    (fp_circle (center 0 0) (end 3.05 0)
      (stroke (width 0.05) (type solid)) (fill none) (layer "F.CrtYd"))
    (pad "" smd custom (at -1.7 -1.71) (size 0.62 0.62) (layers "F.Paste")
      (thermal_bridge_angle 90)
      (options (clearance outline) (anchor circle))
      (primitives
        (gr_arc (start -0.250195 1.279127) (mid 0.285453 0.294389) (end 1.266786 -0.24747) (width 0.2))
        (gr_arc (start -0.34334 1.279127) (mid 0.218448 0.232561) (end 1.259603 -0.339191) (width 0.2))
        (gr_arc (start -0.436309 1.279127) (mid 0.152481 0.169693) (end 1.255279 -0.431435) (width 0.2))
        (gr_arc (start -0.529126 1.279127) (mid 0.087542 0.105784) (end 1.253811 -0.524161) (width 0.2))
        (gr_arc (start -0.621807 1.279127) (mid 0.0309 0.033527) (end 1.275473 -0.621136) (width 0.2))
        (gr_arc (start -0.71437 1.279127) (mid -0.037758 -0.026651) (end 1.263664 -0.711602) (width 0.2))
        (gr_arc (start -0.806826 1.279127) (mid -0.105837 -0.087395) (end 1.253435 -0.802342) (width 0.2))
        (gr_arc (start -0.899187 1.279127) (mid -0.165236 -0.156885) (end 1.267475 -0.897258) (width 0.2))
        (gr_arc (start -0.991463 1.279127) (mid -0.228522 -0.222449) (end 1.270645 -0.990112) (width 0.2))
        (gr_arc (start -1.083663 1.279127) (mid -0.294507 -0.285313) (end 1.266278 -1.081674) (width 0.2))
        (gr_line (start 1.279127 -0.250195) (end 1.279127 -1.083663) (width 0.2))
        (gr_line (start -0.250195 1.279127) (end -1.083663 1.279127) (width 0.2))
      ))
    (pad "" smd custom (at -1.7 1.699 90) (size 0.62 0.62) (layers "F.Paste")
      (thermal_bridge_angle 90)
      (options (clearance outline) (anchor circle))
      (primitives
        (gr_arc (start -0.250195 1.279127) (mid 0.285453 0.294389) (end 1.266786 -0.24747) (width 0.2))
        (gr_arc (start -0.34334 1.279127) (mid 0.218448 0.232561) (end 1.259603 -0.339191) (width 0.2))
        (gr_arc (start -0.436309 1.279127) (mid 0.152481 0.169693) (end 1.255279 -0.431435) (width 0.2))
        (gr_arc (start -0.529126 1.279127) (mid 0.087542 0.105784) (end 1.253811 -0.524161) (width 0.2))
        (gr_arc (start -0.621807 1.279127) (mid 0.0309 0.033527) (end 1.275473 -0.621136) (width 0.2))
        (gr_arc (start -0.71437 1.279127) (mid -0.037758 -0.026651) (end 1.263664 -0.711602) (width 0.2))
        (gr_arc (start -0.806826 1.279127) (mid -0.105837 -0.087395) (end 1.253435 -0.802342) (width 0.2))
        (gr_arc (start -0.899187 1.279127) (mid -0.165236 -0.156885) (end 1.267475 -0.897258) (width 0.2))
        (gr_arc (start -0.991463 1.279127) (mid -0.228522 -0.222449) (end 1.270645 -0.990112) (width 0.2))
        (gr_arc (start -1.083663 1.279127) (mid -0.294507 -0.285313) (end 1.266278 -1.081674) (width 0.2))
        (gr_line (start 1.279127 -0.250195) (end 1.279127 -1.083663) (width 0.2))
        (gr_line (start -0.250195 1.279127) (end -1.083663 1.279127) (width 0.2))
      ))
    (pad "" smd custom (at 1.709 -1.71 270) (size 0.62 0.62) (layers "F.Paste")
      (thermal_bridge_angle 90)
      (options (clearance outline) (anchor circle))
      (primitives
        (gr_arc (start -0.250195 1.279127) (mid 0.285453 0.294389) (end 1.266786 -0.24747) (width 0.2))
        (gr_arc (start -0.34334 1.279127) (mid 0.218448 0.232561) (end 1.259603 -0.339191) (width 0.2))
        (gr_arc (start -0.436309 1.279127) (mid 0.152481 0.169693) (end 1.255279 -0.431435) (width 0.2))
        (gr_arc (start -0.529126 1.279127) (mid 0.087542 0.105784) (end 1.253811 -0.524161) (width 0.2))
        (gr_arc (start -0.621807 1.279127) (mid 0.0309 0.033527) (end 1.275473 -0.621136) (width 0.2))
        (gr_arc (start -0.71437 1.279127) (mid -0.037758 -0.026651) (end 1.263664 -0.711602) (width 0.2))
        (gr_arc (start -0.806826 1.279127) (mid -0.105837 -0.087395) (end 1.253435 -0.802342) (width 0.2))
        (gr_arc (start -0.899187 1.279127) (mid -0.165236 -0.156885) (end 1.267475 -0.897258) (width 0.2))
        (gr_arc (start -0.991463 1.279127) (mid -0.228522 -0.222449) (end 1.270645 -0.990112) (width 0.2))
        (gr_arc (start -1.083663 1.279127) (mid -0.294507 -0.285313) (end 1.266278 -1.081674) (width 0.2))
        (gr_line (start 1.279127 -0.250195) (end 1.279127 -1.083663) (width 0.2))
        (gr_line (start -0.250195 1.279127) (end -1.083663 1.279127) (width 0.2))
      ))
    (pad "" smd custom (at 1.709 1.699 180) (size 0.62 0.62) (layers "F.Paste")
      (thermal_bridge_angle 90)
      (options (clearance outline) (anchor circle))
      (primitives
        (gr_arc (start -0.250195 1.279127) (mid 0.285453 0.294389) (end 1.266786 -0.24747) (width 0.2))
        (gr_arc (start -0.34334 1.279127) (mid 0.218448 0.232561) (end 1.259603 -0.339191) (width 0.2))
        (gr_arc (start -0.436309 1.279127) (mid 0.152481 0.169693) (end 1.255279 -0.431435) (width 0.2))
        (gr_arc (start -0.529126 1.279127) (mid 0.087542 0.105784) (end 1.253811 -0.524161) (width 0.2))
        (gr_arc (start -0.621807 1.279127) (mid 0.0309 0.033527) (end 1.275473 -0.621136) (width 0.2))
        (gr_arc (start -0.71437 1.279127) (mid -0.037758 -0.026651) (end 1.263664 -0.711602) (width 0.2))
        (gr_arc (start -0.806826 1.279127) (mid -0.105837 -0.087395) (end 1.253435 -0.802342) (width 0.2))
        (gr_arc (start -0.899187 1.279127) (mid -0.165236 -0.156885) (end 1.267475 -0.897258) (width 0.2))
        (gr_arc (start -0.991463 1.279127) (mid -0.228522 -0.222449) (end 1.270645 -0.990112) (width 0.2))
        (gr_arc (start -1.083663 1.279127) (mid -0.294507 -0.285313) (end 1.266278 -1.081674) (width 0.2))
        (gr_line (start 1.279127 -0.250195) (end 1.279127 -1.083663) (width 0.2))
        (gr_line (start -0.250195 1.279127) (end -1.083663 1.279127) (width 0.2))
      ))
    (pad "1" thru_hole circle (at 0 0) (size 6 6) (drill 3.7) (layers "*.Cu" "*.Mask")
      (net 779 "unconnected-(H2-Pad1)") (pintype "passive+no_connect") (solder_paste_margin_ratio -0.05))
  )

  (footprint "antmicro-footprints:HTSSOP-20_W4.4mm_P0.65mm" (layer "F.Cu")
    (at 90.94 67.455 -90)
    (property "Author" "Antmicro")
    (property "License" "Apache-2.0")
    (property "MPN" "LM21212MH-2/NOPB")
    (property "Manufacturer" "Texas Instruments")
    (property "Sheetfile" "power-supply.kicad_sch")
    (property "Sheetname" "Power supply")
    (property "ki_description" "DC-DC Switching Buck Step Down Regulator, Adjustable, 2.95V-5.5Vin, 600mV-5.5Vout, 12Aout, HTSSOP-20")
    (property "ki_keywords" "SMT, PMIC, IC, SWITCHING, BUCK, VOLTAGE, REGULATOR")
    (attr smd)
    (fp_text reference "U13" (at 1.13 -3.07 -90) (layer "F.SilkS")
        (effects (font (size 0.7 0.7) (thickness 0.15)) (justify left bottom))
    )
    (fp_text value "LM21212-2" (at 0.11 5.065 -90) (layer "F.Fab")
        (effects (font (size 0.7 0.7) (thickness 0.15)) (justify left bottom))
    )
    (fp_text user "${REFERENCE}" (at -3.84 6.699 -90) (layer "F.Fab") hide
        (effects (font (size 0.7 0.7) (thickness 0.15)) (justify left bottom))
    )
    (fp_text user "License: Apache-2.0" (at -3.84 9.099 -90) (layer "F.Fab") hide
        (effects (font (size 0.7 0.7) (thickness 0.15)) (justify left bottom))
    )
    (fp_text user "Author: Antmicro" (at -3.84 7.899 -90) (layer "F.Fab") hide
        (effects (font (size 0.7 0.7) (thickness 0.15)) (justify left bottom))
    )
    (fp_line (start -1.88 -3.3) (end 1.88 -3.3)
      (stroke (width 0.15) (type solid)) (layer "F.SilkS"))
    (fp_line (start -1.88 3.3) (end 1.88 3.3)
      (stroke (width 0.15) (type solid)) (layer "F.SilkS"))
    (fp_circle (center -2.97 -3.325) (end -2.92 -3.325)
      (stroke (width 0.15) (type solid)) (fill solid) (layer "F.SilkS"))
    (fp_rect (start -3.73 -3.875) (end 3.73 3.875)
      (stroke (width 0.05) (type solid)) (fill none) (layer "F.CrtYd"))
    (fp_line (start -2.25 -3.3) (end 2.25 -3.3)
      (stroke (width 0.15) (type solid)) (layer "F.Fab"))
    (fp_line (start -2.25 3.3) (end -2.25 -3.3)
      (stroke (width 0.15) (type solid)) (layer "F.Fab"))
    (fp_line (start -2.25 3.3) (end 2.25 3.3)
      (stroke (width 0.15) (type solid)) (layer "F.Fab"))
    (fp_line (start 2.25 3.3) (end 2.25 -3.3)
      (stroke (width 0.15) (type solid)) (layer "F.Fab"))
    (pad "1" smd roundrect (at -2.97 -2.925 180) (size 0.42 1.4) (layers "F.Cu" "F.Paste" "F.Mask") (roundrect_rratio 0.4399965333)
      (net 423 "Net-(U13-FADJ)") (pinfunction "FADJ") (pintype "passive"))
    (pad "2" smd roundrect (at -2.97 -2.275 180) (size 0.42 1.4) (layers "F.Cu" "F.Paste" "F.Mask") (roundrect_rratio 0.4399965333)
      (net 509 "unconnected-(U13-SS-Pad2)") (pinfunction "SS") (pintype "passive+no_connect"))
    (pad "3" smd roundrect (at -2.97 -1.625 180) (size 0.42 1.4) (layers "F.Cu" "F.Paste" "F.Mask") (roundrect_rratio 0.4399965333)
      (net 366 "/Power supply/VCCA0_EN") (pinfunction "EN") (pintype "passive"))
    (pad "4" smd roundrect (at -2.97 -0.975 180) (size 0.42 1.4) (layers "F.Cu" "F.Paste" "F.Mask") (roundrect_rratio 0.4399965333)
      (net 232 "Net-(U13-AVIN)") (pinfunction "AVIN") (pintype "passive"))
    (pad "5" smd roundrect (at -2.97 -0.325 180) (size 0.42 1.4) (layers "F.Cu" "F.Paste" "F.Mask") (roundrect_rratio 0.4399965333)
      (net 11 "VCC5V0") (pinfunction "PVIN") (pintype "passive"))
    (pad "6" smd roundrect (at -2.97 0.325 180) (size 0.42 1.4) (layers "F.Cu" "F.Paste" "F.Mask") (roundrect_rratio 0.4399965333)
      (net 11 "VCC5V0") (pinfunction "PVIN") (pintype "passive"))
    (pad "7" smd roundrect (at -2.97 0.975 180) (size 0.42 1.4) (layers "F.Cu" "F.Paste" "F.Mask") (roundrect_rratio 0.4399965333)
      (net 11 "VCC5V0") (pinfunction "PVIN") (pintype "passive"))
    (pad "8" smd roundrect (at -2.97 1.625 180) (size 0.42 1.4) (layers "F.Cu" "F.Paste" "F.Mask") (roundrect_rratio 0.4399965333)
      (net 1 "GND") (pinfunction "PGND") (pintype "passive"))
    (pad "9" smd roundrect (at -2.97 2.275 180) (size 0.42 1.4) (layers "F.Cu" "F.Paste" "F.Mask") (roundrect_rratio 0.4399965333)
      (net 1 "GND") (pinfunction "PGND") (pintype "passive"))
    (pad "10" smd roundrect (at -2.97 2.925 180) (size 0.42 1.4) (layers "F.Cu" "F.Paste" "F.Mask") (roundrect_rratio 0.4399965333)
      (net 1 "GND") (pinfunction "PGND") (pintype "passive"))
    (pad "11" smd roundrect (at 2.97 2.925 180) (size 0.42 1.4) (layers "F.Cu" "F.Paste" "F.Mask") (roundrect_rratio 0.4399965333)
      (net 234 "Net-(L1-Pad1)") (pinfunction "SW") (pintype "passive"))
    (pad "12" smd roundrect (at 2.97 2.275 180) (size 0.42 1.4) (layers "F.Cu" "F.Paste" "F.Mask") (roundrect_rratio 0.4399965333)
      (net 234 "Net-(L1-Pad1)") (pinfunction "SW") (pintype "passive"))
    (pad "13" smd roundrect (at 2.97 1.625 180) (size 0.42 1.4) (layers "F.Cu" "F.Paste" "F.Mask") (roundrect_rratio 0.4399965333)
      (net 234 "Net-(L1-Pad1)") (pinfunction "SW") (pintype "passive"))
    (pad "14" smd roundrect (at 2.97 0.975 180) (size 0.42 1.4) (layers "F.Cu" "F.Paste" "F.Mask") (roundrect_rratio 0.4399965333)
      (net 234 "Net-(L1-Pad1)") (pinfunction "SW") (pintype "passive"))
    (pad "15" smd roundrect (at 2.97 0.325 180) (size 0.42 1.4) (layers "F.Cu" "F.Paste" "F.Mask") (roundrect_rratio 0.4399965333)
      (net 234 "Net-(L1-Pad1)") (pinfunction "SW") (pintype "passive"))
    (pad "16" smd roundrect (at 2.97 -0.325 180) (size 0.42 1.4) (layers "F.Cu" "F.Paste" "F.Mask") (roundrect_rratio 0.4399965333)
      (net 234 "Net-(L1-Pad1)") (pinfunction "SW") (pintype "passive"))
    (pad "17" smd roundrect (at 2.97 -0.975 180) (size 0.42 1.4) (layers "F.Cu" "F.Paste" "F.Mask") (roundrect_rratio 0.4399965333)
      (net 235 "/Power supply/1V2_PG") (pinfunction "PGOOD") (pintype "passive"))
    (pad "18" smd roundrect (at 2.97 -1.625 180) (size 0.42 1.4) (layers "F.Cu" "F.Paste" "F.Mask") (roundrect_rratio 0.4399965333)
      (net 267 "Net-(U13-COMP)") (pinfunction "COMP") (pintype "passive"))
    (pad "19" smd roundrect (at 2.97 -2.275 180) (size 0.42 1.4) (layers "F.Cu" "F.Paste" "F.Mask") (roundrect_rratio 0.4399965333)
      (net 289 "Net-(U13-FB)") (pinfunction "FB") (pintype "passive"))
    (pad "20" smd roundrect (at 2.97 -2.925 180) (size 0.42 1.4) (layers "F.Cu" "F.Paste" "F.Mask") (roundrect_rratio 0.4399965333)
      (net 1 "GND") (pinfunction "AGND") (pintype "passive"))
    (pad "21" smd roundrect (at 0 0.37 270) (size 3.32 4.55) (layers "F.Cu" "F.Paste" "F.Mask") (roundrect_rratio 0.06)
      (net 1 "GND") (pinfunction "EP") (pintype "passive"))
  )

  (footprint "antmicro-footprints:Conn_Plug_Molex_SlimStack_2x25_529910508" locked (layer "F.Cu")
    (at 74.09468 156.3802)
    (property "Author" "Antmicro")
    (property "License" "Apache-2.0")
    (property "MPN" "529910508")
    (property "Manufacturer" "Molex")
    (property "Pitch " "0.5 mm")
    (property "Sheetfile" "rot.kicad_sch")
    (property "Sheetname" "RoT")
    (property "ki_description" "Mezzanine Connector, Receptacle, 0.5mm, 2Rows, 50Contacts, Surface Mount, Phosphor Bronze")
    (property "ki_keywords" "CONNECTOR, B2B, PLUG")
    (attr smd)
    (fp_text reference "J3" (at -8.49468 0.9348 90) (layer "F.SilkS")
        (effects (font (size 0.7 0.7) (thickness 0.15)) (justify left bottom))
    )
    (fp_text value "Plug_Molex_SlimStack_2x25_529910508" (at 0 4.75) (layer "F.Fab")
        (effects (font (size 0.7 0.7) (thickness 0.15)) (justify left bottom))
    )
    (fp_text user "License: Apache-2.0" (at -8.5 8.3) (layer "F.Fab") hide
        (effects (font (size 0.7 0.7) (thickness 0.15)) (justify left bottom))
    )
    (fp_text user "Author: Antmicro" (at -8.5 7.099) (layer "F.Fab") hide
        (effects (font (size 0.7 0.7) (thickness 0.15)) (justify left bottom))
    )
    (fp_text user "${REFERENCE}" (at -8.5 5.9) (layer "F.Fab") hide
        (effects (font (size 0.7 0.7) (thickness 0.15)) (justify left bottom))
    )
    (fp_line (start -8.15 -2.7) (end -8.15 2.7)
      (stroke (width 0.15) (type solid)) (layer "F.SilkS"))
    (fp_line (start -6.7 -2.7) (end -8.15 -2.7)
      (stroke (width 0.15) (type solid)) (layer "F.SilkS"))
    (fp_line (start -6.7 2.7) (end -8.15 2.7)
      (stroke (width 0.15) (type solid)) (layer "F.SilkS"))
    (fp_line (start 6.7 -2.7) (end 8.15 -2.7)
      (stroke (width 0.15) (type solid)) (layer "F.SilkS"))
    (fp_line (start 6.7 2.7) (end 8.15 2.7)
      (stroke (width 0.15) (type solid)) (layer "F.SilkS"))
    (fp_line (start 8.15 2.7) (end 8.15 -2.7)
      (stroke (width 0.15) (type solid)) (layer "F.SilkS"))
    (fp_circle (center -6.45 -3.05) (end -6.45 -3.1)
      (stroke (width 0.15) (type solid)) (fill solid) (layer "F.SilkS"))
    (fp_line (start -8.657 -3.399) (end -8.657 3.401)
      (stroke (width 0.05) (type solid)) (layer "F.CrtYd"))
    (fp_line (start -8.657 3.401) (end 8.643 3.401)
      (stroke (width 0.05) (type solid)) (layer "F.CrtYd"))
    (fp_line (start 8.643 -3.399) (end -8.657 -3.399)
      (stroke (width 0.05) (type solid)) (layer "F.CrtYd"))
    (fp_line (start 8.643 3.401) (end 8.643 -3.399)
      (stroke (width 0.05) (type solid)) (layer "F.CrtYd"))
    (pad "1" smd rect locked (at -6.007 -2.041 180) (size 0.3 1.8) (layers "F.Cu" "F.Paste" "F.Mask")
      (net 2 "VCC3V3") (pintype "passive"))
    (pad "2" smd rect locked (at -6.007 2.058 180) (size 0.3 1.8) (layers "F.Cu" "F.Paste" "F.Mask")
      (net 1 "GND") (pintype "passive"))
    (pad "3" smd rect locked (at -5.507 -2.041 180) (size 0.3 1.8) (layers "F.Cu" "F.Paste" "F.Mask")
      (net 2 "VCC3V3") (pintype "passive"))
    (pad "4" smd rect locked (at -5.507 2.058 180) (size 0.3 1.8) (layers "F.Cu" "F.Paste" "F.Mask")
      (net 1 "GND") (pintype "passive"))
    (pad "5" smd rect locked (at -5.006 -2.05 180) (size 0.3 1.8) (layers "F.Cu" "F.Paste" "F.Mask")
      (net 666 "ROT_GPIO1") (pintype "passive"))
    (pad "6" smd rect locked (at -5.006 2.058 180) (size 0.3 1.8) (layers "F.Cu" "F.Paste" "F.Mask")
      (net 665 "ROT_GPIO2") (pintype "passive"))
    (pad "7" smd rect locked (at -4.506 -2.041 180) (size 0.3 1.8) (layers "F.Cu" "F.Paste" "F.Mask")
      (net 91 "QSPI0_CS1_N") (pintype "passive"))
    (pad "8" smd rect locked (at -4.506 2.058 180) (size 0.3 1.8) (layers "F.Cu" "F.Paste" "F.Mask")
      (net 138 "QSPIA1_D2") (pintype "passive"))
    (pad "9" smd rect locked (at -4.007 -2.041 180) (size 0.3 1.8) (layers "F.Cu" "F.Paste" "F.Mask")
      (net 143 "QSPIA2_D2") (pintype "passive"))
    (pad "10" smd rect locked (at -4.007 2.058 180) (size 0.3 1.8) (layers "F.Cu" "F.Paste" "F.Mask")
      (net 137 "QSPIA1_D1") (pintype "passive"))
    (pad "11" smd rect locked (at -3.507 -2.041 180) (size 0.3 1.8) (layers "F.Cu" "F.Paste" "F.Mask")
      (net 142 "QSPIA2_D1") (pintype "passive"))
    (pad "12" smd rect locked (at -3.507 2.058 180) (size 0.3 1.8) (layers "F.Cu" "F.Paste" "F.Mask")
      (net 140 "QSPIA1_CS_N") (pintype "passive"))
    (pad "13" smd rect locked (at -3.007 -2.041 180) (size 0.3 1.8) (layers "F.Cu" "F.Paste" "F.Mask")
      (net 145 "QSPIA2_CS_N") (pintype "passive"))
    (pad "14" smd rect locked (at -3.007 2.058 180) (size 0.3 1.8) (layers "F.Cu" "F.Paste" "F.Mask")
      (net 139 "QSPIA1_D3") (pintype "passive"))
    (pad "15" smd rect locked (at -2.507 -2.041 180) (size 0.3 1.8) (layers "F.Cu" "F.Paste" "F.Mask")
      (net 144 "QSPIA2_D3") (pintype "passive"))
    (pad "16" smd rect locked (at -2.507 2.058 180) (size 0.3 1.8) (layers "F.Cu" "F.Paste" "F.Mask")
      (net 136 "QSPIA1_D0") (pintype "passive"))
    (pad "17" smd rect locked (at -2.005 -2.041 180) (size 0.3 1.8) (layers "F.Cu" "F.Paste" "F.Mask")
      (net 135 "QSPIA_CLK") (pintype "passive"))
    (pad "18" smd rect locked (at -2.005 2.058 180) (size 0.3 1.8) (layers "F.Cu" "F.Paste" "F.Mask")
      (net 68 "QSPI0_CLK") (pintype "passive"))
    (pad "19" smd rect locked (at -1.505 -2.041 180) (size 0.3 1.8) (layers "F.Cu" "F.Paste" "F.Mask")
      (net 141 "QSPIA2_D0") (pintype "passive"))
    (pad "20" smd rect locked (at -1.505 2.058 180) (size 0.3 1.8) (layers "F.Cu" "F.Paste" "F.Mask")
      (net 69 "QSPI0_CS0_N") (pintype "passive"))
    (pad "21" smd rect locked (at -1.005 -2.041 180) (size 0.3 1.8) (layers "F.Cu" "F.Paste" "F.Mask")
      (net 127 "QSPIB1_D2") (pintype "passive"))
    (pad "22" smd rect locked (at -1.005 2.058 180) (size 0.3 1.8) (layers "F.Cu" "F.Paste" "F.Mask")
      (net 70 "QSPI0_D0") (pintype "passive"))
    (pad "23" smd rect locked (at -0.505 -2.041 180) (size 0.3 1.8) (layers "F.Cu" "F.Paste" "F.Mask")
      (net 126 "QSPIB1_D1") (pintype "passive"))
    (pad "24" smd rect locked (at -0.505 2.058 180) (size 0.3 1.8) (layers "F.Cu" "F.Paste" "F.Mask")
      (net 71 "QSPI0_D1") (pintype "passive"))
    (pad "25" smd rect locked (at -0.005 -2.041 180) (size 0.3 1.8) (layers "F.Cu" "F.Paste" "F.Mask")
      (net 129 "QSPIB1_CS_N") (pintype "passive"))
    (pad "26" smd rect locked (at -0.005 2.058 180) (size 0.3 1.8) (layers "F.Cu" "F.Paste" "F.Mask")
      (net 72 "QSPI0_D2") (pintype "passive"))
    (pad "27" smd rect locked (at 0.493 -2.041 180) (size 0.3 1.8) (layers "F.Cu" "F.Paste" "F.Mask")
      (net 128 "QSPIB1_D3") (pintype "passive"))
    (pad "28" smd rect locked (at 0.493 2.058 180) (size 0.3 1.8) (layers "F.Cu" "F.Paste" "F.Mask")
      (net 73 "QSPI0_D3") (pintype "passive"))
    (pad "29" smd rect locked (at 0.994 -2.041 180) (size 0.3 1.8) (layers "F.Cu" "F.Paste" "F.Mask")
      (net 125 "QSPIB1_D0") (pintype "passive"))
    (pad "30" smd rect locked (at 0.994 2.058 180) (size 0.3 1.8) (layers "F.Cu" "F.Paste" "F.Mask")
      (net 272 "ROT_QSPI_SCK") (pintype "passive"))
    (pad "31" smd rect locked (at 1.494 -2.041 180) (size 0.3 1.8) (layers "F.Cu" "F.Paste" "F.Mask")
      (net 132 "QSPIB2_D2") (pintype "passive"))
    (pad "32" smd rect locked (at 1.494 2.058 180) (size 0.3 1.8) (layers "F.Cu" "F.Paste" "F.Mask")
      (net 273 "ROT_QSPI_DQ3") (pintype "passive"))
    (pad "33" smd rect locked (at 1.993 -2.041 180) (size 0.3 1.8) (layers "F.Cu" "F.Paste" "F.Mask")
      (net 131 "QSPIB2_D1") (pintype "passive"))
    (pad "34" smd rect locked (at 1.993 2.058 180) (size 0.3 1.8) (layers "F.Cu" "F.Paste" "F.Mask")
      (net 274 "ROT_QSPI_DQ2") (pintype "passive"))
    (pad "35" smd rect locked (at 2.493 -2.041 180) (size 0.3 1.8) (layers "F.Cu" "F.Paste" "F.Mask")
      (net 134 "QSPIB2_CS_N") (pintype "passive"))
    (pad "36" smd rect locked (at 2.493 2.058 180) (size 0.3 1.8) (layers "F.Cu" "F.Paste" "F.Mask")
      (net 275 "ROT_QSPI_DQ1") (pintype "passive"))
    (pad "37" smd rect locked (at 2.993 -2.041 180) (size 0.3 1.8) (layers "F.Cu" "F.Paste" "F.Mask")
      (net 133 "QSPIB2_D3") (pintype "passive"))
    (pad "38" smd rect locked (at 2.993 2.058 180) (size 0.3 1.8) (layers "F.Cu" "F.Paste" "F.Mask")
      (net 276 "ROT_QSPI_DQ0") (pintype "passive"))
    (pad "39" smd rect locked (at 3.493 -2.041 180) (size 0.3 1.8) (layers "F.Cu" "F.Paste" "F.Mask")
      (net 124 "QSPIB_CLK") (pintype "passive"))
    (pad "40" smd rect locked (at 3.493 2.058 180) (size 0.3 1.8) (layers "F.Cu" "F.Paste" "F.Mask")
      (net 268 "PROGRAM_N") (pintype "passive"))
    (pad "41" smd rect locked (at 3.994 -2.041 180) (size 0.3 1.8) (layers "F.Cu" "F.Paste" "F.Mask")
      (net 130 "QSPIB2_D0") (pintype "passive"))
    (pad "42" smd rect locked (at 3.994 2.058 180) (size 0.3 1.8) (layers "F.Cu" "F.Paste" "F.Mask")
      (net 269 "INIT_N") (pintype "passive"))
    (pad "43" smd rect locked (at 4.494 -2.041 180) (size 0.3 1.8) (layers "F.Cu" "F.Paste" "F.Mask")
      (net 271 "ROT_QSPI_CS_N") (pintype "passive"))
    (pad "44" smd rect locked (at 4.494 2.058 180) (size 0.3 1.8) (layers "F.Cu" "F.Paste" "F.Mask")
      (net 409 "ROT_RDY\\ROT_GPIO0") (pintype "passive"))
    (pad "45" smd rect locked (at 4.994 -2.041 180) (size 0.3 1.8) (layers "F.Cu" "F.Paste" "F.Mask")
      (net 661 "ROT_SS") (pintype "passive"))
    (pad "46" smd rect locked (at 4.994 2.058 180) (size 0.3 1.8) (layers "F.Cu" "F.Paste" "F.Mask")
      (net 662 "ROT_TX") (pintype "passive"))
    (pad "47" smd rect locked (at 5.494 -2.041 180) (size 0.3 1.8) (layers "F.Cu" "F.Paste" "F.Mask")
      (net 659 "ROT_MISO") (pintype "passive"))
    (pad "48" smd rect locked (at 5.494 2.058 180) (size 0.3 1.8) (layers "F.Cu" "F.Paste" "F.Mask")
      (net 663 "ROT_RX") (pintype "passive"))
    (pad "49" smd rect locked (at 5.994 -2.041 180) (size 0.3 1.8) (layers "F.Cu" "F.Paste" "F.Mask")
      (net 660 "ROT_MOSI") (pintype "passive"))
    (pad "50" smd rect locked (at 5.994 2.058 180) (size 0.3 1.8) (layers "F.Cu" "F.Paste" "F.Mask")
      (net 664 "ROT_SCLK") (pintype "passive"))
  )

  (footprint "antmicro-footprints:Spacer_Drill3.7mm_H2.5mm_9774025151R" (layer "F.Cu")
    (at 129.511 81.495)
    (property "Author" "Antmicro")
    (property "License" "Apache-2.0")
    (property "MPN" "9774025151R")
    (property "Manufacturer" "Würth Elektronik")
    (property "Public" "False")
    (property "Sheetfile" "pcie-conn.kicad_sch")
    (property "Sheetname" "PCIe-connector")
    (property "ki_description" "Spacer, SMT, Non Stop, Steel, Swage Round, 5.1 mm x 2.5 mm, M2.5 Thread, WA-SMSI Series")
    (property "ki_keywords" "MECHANICAL, SPACER")
    (solder_paste_ratio -0.1)
    (attr smd)
    (fp_text reference "H1" (at 0 -3.2) (layer "F.SilkS")
        (effects (font (size 0.7 0.7) (thickness 0.15)) (justify left bottom))
    )
    (fp_text value "Spacer_Drill3.7mm_H2.5mm_9774025151R" (at 0 4) (layer "F.Fab")
        (effects (font (size 0.7 0.7) (thickness 0.15)) (justify left bottom))
    )
    (fp_text user "License: Apache-2.0" (at -2.75 8.25) (layer "F.Fab") hide
        (effects (font (size 0.7 0.7) (thickness 0.15)) (justify left bottom))
    )
    (fp_text user "${REFERENCE}" (at -2.75 5.5) (layer "F.Fab") hide
        (effects (font (size 0.7 0.7) (thickness 0.15)) (justify left bottom))
    )
    (fp_text user "Author: Antmicro" (at -2.75 6.75) (layer "F.Fab") hide
        (effects (font (size 0.7 0.7) (thickness 0.15)) (justify left bottom))
    )
    (fp_circle (center 0 0) (end 0 -3.05)
      (stroke (width 0.05) (type solid)) (fill none) (layer "F.CrtYd"))
    (pad "" smd custom (at -1.71 -1.71) (size 0.62 0.62) (layers "F.Paste")
      (thermal_bridge_angle 90)
      (options (clearance outline) (anchor circle))
      (primitives
        (gr_arc (start -0.250195 1.279127) (mid 0.285453 0.294389) (end 1.266786 -0.24747) (width 0.2))
        (gr_arc (start -0.34334 1.279127) (mid 0.218448 0.232561) (end 1.259603 -0.339191) (width 0.2))
        (gr_arc (start -0.436309 1.279127) (mid 0.152481 0.169693) (end 1.255279 -0.431435) (width 0.2))
        (gr_arc (start -0.529126 1.279127) (mid 0.087542 0.105784) (end 1.253811 -0.524161) (width 0.2))
        (gr_arc (start -0.621807 1.279127) (mid 0.0309 0.033527) (end 1.275473 -0.621136) (width 0.2))
        (gr_arc (start -0.71437 1.279127) (mid -0.037758 -0.026651) (end 1.263664 -0.711602) (width 0.2))
        (gr_arc (start -0.806826 1.279127) (mid -0.105837 -0.087395) (end 1.253435 -0.802342) (width 0.2))
        (gr_arc (start -0.899187 1.279127) (mid -0.165236 -0.156885) (end 1.267475 -0.897258) (width 0.2))
        (gr_arc (start -0.991463 1.279127) (mid -0.228522 -0.222449) (end 1.270645 -0.990112) (width 0.2))
        (gr_arc (start -1.083663 1.279127) (mid -0.294507 -0.285313) (end 1.266278 -1.081674) (width 0.2))
        (gr_line (start 1.279127 -0.250195) (end 1.279127 -1.083663) (width 0.2))
        (gr_line (start -0.250195 1.279127) (end -1.083663 1.279127) (width 0.2))
      ))
    (pad "" smd custom (at -1.71 1.699 90) (size 0.62 0.62) (layers "F.Paste")
      (thermal_bridge_angle 90)
      (options (clearance outline) (anchor circle))
      (primitives
        (gr_arc (start -0.250195 1.279127) (mid 0.285453 0.294389) (end 1.266786 -0.24747) (width 0.2))
        (gr_arc (start -0.34334 1.279127) (mid 0.218448 0.232561) (end 1.259603 -0.339191) (width 0.2))
        (gr_arc (start -0.436309 1.279127) (mid 0.152481 0.169693) (end 1.255279 -0.431435) (width 0.2))
        (gr_arc (start -0.529126 1.279127) (mid 0.087542 0.105784) (end 1.253811 -0.524161) (width 0.2))
        (gr_arc (start -0.621807 1.279127) (mid 0.0309 0.033527) (end 1.275473 -0.621136) (width 0.2))
        (gr_arc (start -0.71437 1.279127) (mid -0.037758 -0.026651) (end 1.263664 -0.711602) (width 0.2))
        (gr_arc (start -0.806826 1.279127) (mid -0.105837 -0.087395) (end 1.253435 -0.802342) (width 0.2))
        (gr_arc (start -0.899187 1.279127) (mid -0.165236 -0.156885) (end 1.267475 -0.897258) (width 0.2))
        (gr_arc (start -0.991463 1.279127) (mid -0.228522 -0.222449) (end 1.270645 -0.990112) (width 0.2))
        (gr_arc (start -1.083663 1.279127) (mid -0.294507 -0.285313) (end 1.266278 -1.081674) (width 0.2))
        (gr_line (start 1.279127 -0.250195) (end 1.279127 -1.083663) (width 0.2))
        (gr_line (start -0.250195 1.279127) (end -1.083663 1.279127) (width 0.2))
      ))
    (pad "" smd custom (at 1.699 -1.71 270) (size 0.62 0.62) (layers "F.Paste")
      (thermal_bridge_angle 90)
      (options (clearance outline) (anchor circle))
      (primitives
        (gr_arc (start -0.250195 1.279127) (mid 0.285453 0.294389) (end 1.266786 -0.24747) (width 0.2))
        (gr_arc (start -0.34334 1.279127) (mid 0.218448 0.232561) (end 1.259603 -0.339191) (width 0.2))
        (gr_arc (start -0.436309 1.279127) (mid 0.152481 0.169693) (end 1.255279 -0.431435) (width 0.2))
        (gr_arc (start -0.529126 1.279127) (mid 0.087542 0.105784) (end 1.253811 -0.524161) (width 0.2))
        (gr_arc (start -0.621807 1.279127) (mid 0.0309 0.033527) (end 1.275473 -0.621136) (width 0.2))
        (gr_arc (start -0.71437 1.279127) (mid -0.037758 -0.026651) (end 1.263664 -0.711602) (width 0.2))
        (gr_arc (start -0.806826 1.279127) (mid -0.105837 -0.087395) (end 1.253435 -0.802342) (width 0.2))
        (gr_arc (start -0.899187 1.279127) (mid -0.165236 -0.156885) (end 1.267475 -0.897258) (width 0.2))
        (gr_arc (start -0.991463 1.279127) (mid -0.228522 -0.222449) (end 1.270645 -0.990112) (width 0.2))
        (gr_arc (start -1.083663 1.279127) (mid -0.294507 -0.285313) (end 1.266278 -1.081674) (width 0.2))
        (gr_line (start 1.279127 -0.250195) (end 1.279127 -1.083663) (width 0.2))
        (gr_line (start -0.250195 1.279127) (end -1.083663 1.279127) (width 0.2))
      ))
    (pad "" smd custom (at 1.699 1.699 180) (size 0.62 0.62) (layers "F.Paste")
      (thermal_bridge_angle 90)
      (options (clearance outline) (anchor circle))
      (primitives
        (gr_arc (start -0.250195 1.279127) (mid 0.285453 0.294389) (end 1.266786 -0.24747) (width 0.2))
        (gr_arc (start -0.34334 1.279127) (mid 0.218448 0.232561) (end 1.259603 -0.339191) (width 0.2))
        (gr_arc (start -0.436309 1.279127) (mid 0.152481 0.169693) (end 1.255279 -0.431435) (width 0.2))
        (gr_arc (start -0.529126 1.279127) (mid 0.087542 0.105784) (end 1.253811 -0.524161) (width 0.2))
        (gr_arc (start -0.621807 1.279127) (mid 0.0309 0.033527) (end 1.275473 -0.621136) (width 0.2))
        (gr_arc (start -0.71437 1.279127) (mid -0.037758 -0.026651) (end 1.263664 -0.711602) (width 0.2))
        (gr_arc (start -0.806826 1.279127) (mid -0.105837 -0.087395) (end 1.253435 -0.802342) (width 0.2))
        (gr_arc (start -0.899187 1.279127) (mid -0.165236 -0.156885) (end 1.267475 -0.897258) (width 0.2))
        (gr_arc (start -0.991463 1.279127) (mid -0.228522 -0.222449) (end 1.270645 -0.990112) (width 0.2))
        (gr_arc (start -1.083663 1.279127) (mid -0.294507 -0.285313) (end 1.266278 -1.081674) (width 0.2))
        (gr_line (start 1.279127 -0.250195) (end 1.279127 -1.083663) (width 0.2))
        (gr_line (start -0.250195 1.279127) (end -1.083663 1.279127) (width 0.2))
      ))
    (pad "1" thru_hole circle (at 0 0) (size 6 6) (drill 3.7) (layers "*.Cu" "*.Mask")
      (net 778 "unconnected-(H1-Pad1)") (pintype "passive+no_connect") (solder_paste_margin_ratio -0.05))
  )

  (footprint "antmicro-footprints:R_0402_1005Metric" (layer "F.Cu")
    (at 90.7 88.7)
    (descr "Resistor SMD 0402")
    (tags "resistor SMD 0402")
    (property "Author" "Antmicro")
    (property "License" "Apache-2.0")
    (property "MPN" "CR0402-FX-3163GLF")
    (property "Manufacturer" "Bourns")
    (property "Public" "False")
    (property "Sheetfile" "power-supply.kicad_sch")
    (property "Sheetname" "Power supply")
    (property "Tolerance" "1%")
    (property "Val" "316k")
    (property "ki_description" "SMD Chip Resistor")
    (property "ki_keywords" "0402, SMT, RESISTOR, PASSIVE")
    (attr smd)
    (fp_text reference "R45" (at 2.1 0.5) (layer "F.SilkS")
        (effects (font (size 0.7 0.7) (thickness 0.15)))
    )
    (fp_text value "R_316k_0402" (at 0 1.17) (layer "F.Fab")
        (effects (font (size 1 1) (thickness 0.15)))
    )
    (fp_text user "Author: Antmicro" (at -0.95 4.169) (layer "F.Fab") hide
        (effects (font (size 0.7 0.7) (thickness 0.15)) (justify left bottom))
    )
    (fp_text user "${REFERENCE}" (at 0 0) (layer "F.Fab")
        (effects (font (size 0.25 0.25) (thickness 0.04)))
    )
    (fp_text user "License: Apache-2.0" (at -0.95 5.169) (layer "F.Fab") hide
        (effects (font (size 0.7 0.7) (thickness 0.15)) (justify left bottom))
    )
    (fp_rect (start -0.925 -0.47) (end 0.925 0.47)
      (stroke (width 0.05) (type default)) (fill none) (layer "F.CrtYd"))
    (fp_rect (start -0.5 -0.25) (end 0.5 0.25)
      (stroke (width 0.15) (type solid)) (fill none) (layer "F.Fab"))
    (pad "1" smd roundrect (at -0.48 0) (size 0.59 0.64) (layers "F.Cu" "F.Paste" "F.Mask") (roundrect_rratio 0.25)
      (net 301 "Net-(U16-FB)") (pintype "passive"))
    (pad "2" smd roundrect (at 0.48 0) (size 0.59 0.64) (layers "F.Cu" "F.Paste" "F.Mask") (roundrect_rratio 0.25)
      (net 359 "Net-(C122-Pad2)") (pintype "passive"))
  )

  (footprint "antmicro-footprints:USON-14_3.5x1.35_P0.5mm" (layer "F.Cu")
    (at 137.53 75.23 90)
    (descr "JEDEC MO-229")
    (property "Author" "Antmicro")
    (property "License" "Apache-2.0")
    (property "MPN" "SP3011-06UTG")
    (property "Manufacturer" "Littelfuse")
    (property "Sheetfile" "interfaces.kicad_sch")
    (property "Sheetname" "Interfaces")
    (property "ki_description" "TVS diode array, 8 kV, USON-14, 6 V, 0.4 pF")
    (property "ki_keywords" "SMT, DIODE, SEMICONDUCTOR, TVS, ESD")
    (attr smd)
    (fp_text reference "D2" (at -0.645 -2.05 90) (layer "F.SilkS")
        (effects (font (size 0.7 0.7) (thickness 0.15)) (justify left bottom))
    )
    (fp_text value "SP3011-06UTG" (at -1.3 3 90) (layer "F.Fab")
        (effects (font (size 0.7 0.7) (thickness 0.15)) (justify left bottom))
    )
    (fp_text user "." (at -0.9 -2.25 90) (layer "F.SilkS")
        (effects (font (size 1 1) (thickness 0.15)))
    )
    (fp_text user "Author: Antmicro" (at -1.3 5.4 90) (layer "F.Fab") hide
        (effects (font (size 0.7 0.7) (thickness 0.15)) (justify left bottom))
    )
    (fp_text user "${REFERENCE}" (at -1.3 4.2 90) (layer "F.Fab") hide
        (effects (font (size 0.7 0.7) (thickness 0.15)) (justify left bottom))
    )
    (fp_text user "License: Apache-2.0" (at -1.3 6.6 90) (layer "F.Fab") hide
        (effects (font (size 0.7 0.7) (thickness 0.15)) (justify left bottom))
    )
    (fp_line (start -0.8 1.75) (end 0.8 1.75)
      (stroke (width 0.12) (type solid)) (layer "F.SilkS"))
    (fp_line (start -0.4 -1.75) (end 0.8 -1.75)
      (stroke (width 0.12) (type solid)) (layer "F.SilkS"))
    (fp_rect (start 1 -1.9) (end -0.95 1.9)
      (stroke (width 0.05) (type solid)) (fill none) (layer "F.CrtYd"))
    (fp_line (start -0.7 -1.55) (end -0.5 -1.75)
      (stroke (width 0.1) (type solid)) (layer "F.Fab"))
    (fp_line (start -0.7 1.75) (end -0.7 -1.55)
      (stroke (width 0.1) (type solid)) (layer "F.Fab"))
    (fp_line (start -0.5 -1.75) (end 0.65 -1.75)
      (stroke (width 0.1) (type solid)) (layer "F.Fab"))
    (fp_line (start 0.65 -1.75) (end 0.65 1.75)
      (stroke (width 0.1) (type solid)) (layer "F.Fab"))
    (fp_line (start 0.65 1.75) (end -0.7 1.75)
      (stroke (width 0.1) (type solid)) (layer "F.Fab"))
    (pad "1" smd roundrect (at -0.623 -1.5) (size 0.2 0.5) (layers "F.Cu" "F.Paste" "F.Mask") (roundrect_rratio 0.25)
      (chamfer_ratio 0.2) (chamfer bottom_left)
      (net 19 "JTAG_TDI") (pintype "passive"))
    (pad "2" smd roundrect (at -0.623 -1) (size 0.2 0.5) (layers "F.Cu" "F.Paste" "F.Mask") (roundrect_rratio 0.25)
      (net 20 "JTAG_TDO") (pintype "passive"))
    (pad "3" smd roundrect (at -0.623 -0.5) (size 0.2 0.5) (layers "F.Cu" "F.Paste" "F.Mask") (roundrect_rratio 0.25)
      (net 298 "unconnected-(D2-Pad12)") (pintype "passive+no_connect"))
    (pad "4" smd roundrect (at -0.623 0) (size 0.2 0.5) (layers "F.Cu" "F.Paste" "F.Mask") (roundrect_rratio 0.25)
      (net 297 "unconnected-(D2-Pad11)") (pintype "passive+no_connect"))
    (pad "5" smd roundrect (at -0.623 0.498) (size 0.2 0.5) (layers "F.Cu" "F.Paste" "F.Mask") (roundrect_rratio 0.25)
      (net 1 "GND") (pintype "passive"))
    (pad "6" smd roundrect (at -0.623 0.998) (size 0.2 0.5) (layers "F.Cu" "F.Paste" "F.Mask") (roundrect_rratio 0.25)
      (net 21 "JTAG_TCK") (pintype "passive"))
    (pad "7" smd roundrect (at -0.623 1.499) (size 0.2 0.5) (layers "F.Cu" "F.Paste" "F.Mask") (roundrect_rratio 0.25)
      (net 22 "JTAG_TMS") (pintype "passive"))
    (pad "8" smd roundrect (at 0.625 1.499) (size 0.2 0.5) (layers "F.Cu" "F.Paste" "F.Mask") (roundrect_rratio 0.25)
      (net 22 "JTAG_TMS") (pintype "passive"))
    (pad "9" smd roundrect (at 0.625 0.998) (size 0.2 0.5) (layers "F.Cu" "F.Paste" "F.Mask") (roundrect_rratio 0.25)
      (net 21 "JTAG_TCK") (pintype "passive"))
    (pad "10" smd roundrect (at 0.625 0.498) (size 0.2 0.5) (layers "F.Cu" "F.Paste" "F.Mask") (roundrect_rratio 0.25)
      (net 1 "GND") (pintype "passive"))
    (pad "11" smd roundrect (at 0.625 0) (size 0.2 0.5) (layers "F.Cu" "F.Paste" "F.Mask") (roundrect_rratio 0.25)
      (net 297 "unconnected-(D2-Pad11)") (pintype "passive+no_connect"))
    (pad "12" smd roundrect (at 0.625 -0.5) (size 0.2 0.5) (layers "F.Cu" "F.Paste" "F.Mask") (roundrect_rratio 0.25)
      (net 298 "unconnected-(D2-Pad12)") (pintype "passive+no_connect"))
    (pad "13" smd roundrect (at 0.625 -1) (size 0.2 0.5) (layers "F.Cu" "F.Paste" "F.Mask") (roundrect_rratio 0.25)
      (net 20 "JTAG_TDO") (pintype "passive"))
    (pad "14" smd roundrect (at 0.625 -1.5) (size 0.2 0.5) (layers "F.Cu" "F.Paste" "F.Mask") (roundrect_rratio 0.25)
      (net 19 "JTAG_TDI") (pintype "passive"))
  )

  (footprint "antmicro-footprints:Oscillator_SMD_ECS_3225MV_3.2x2.5x1.2mm" (layer "F.Cu")
    (at 88.4 113.5)
    (property "Author" "Antmicro")
    (property "License" "Apache-2.0")
    (property "MPN" "ECS-3225MVQ-1000CN-TR")
    (property "Manufacturer" "ECS Inc. International")
    (property "Public" "False")
    (property "Sheetfile" "fpga-banks.kicad_sch")
    (property "Sheetname" "FPGA banks")
    (property "Val" "100 MHz")
    (property "ki_description" "Oscillator, 100 MHz, CMOS, SMD, 3.2mm x 2.5mm, MultiVolt ECS-3225MVQ Series")
    (property "ki_keywords" "OSCILLATOR")
    (attr smd)
    (fp_text reference "Y1" (at -0.77 -2.255 unlocked) (layer "F.SilkS")
        (effects (font (size 0.7 0.7) (thickness 0.15)) (justify left bottom))
    )
    (fp_text value "Oscillator_100MHz_ECS_3225MV" (at 0 3.302 unlocked) (layer "F.Fab")
        (effects (font (size 0.7 0.7) (thickness 0.15)) (justify left bottom))
    )
    (fp_text user "${REFERENCE}" (at -2.2 6.502) (layer "F.Fab") hide
        (effects (font (size 0.7 0.7) (thickness 0.15)) (justify left bottom))
    )
    (fp_text user "License: Apache-2.0" (at -2.2 7.702) (layer "F.Fab") hide
        (effects (font (size 0.7 0.7) (thickness 0.15)) (justify left bottom))
    )
    (fp_text user "Author: Antmicro" (at -2.2 5.302) (layer "F.Fab") hide
        (effects (font (size 0.7 0.7) (thickness 0.15)) (justify left bottom))
    )
    (fp_line (start -1.25 -0.102) (end -1.25 0.102)
      (stroke (width 0.15) (type solid)) (layer "F.SilkS"))
    (fp_line (start 1.25 -0.102) (end 1.25 0.102)
      (stroke (width 0.15) (type solid)) (layer "F.SilkS"))
    (fp_circle (center -1.55 -1.6) (end -1.5 -1.6)
      (stroke (width 0.15) (type solid)) (fill solid) (layer "F.SilkS"))
    (fp_rect (start 1.5 -1.85) (end -1.5 1.85)
      (stroke (width 0.05) (type solid)) (fill none) (layer "F.CrtYd"))
    (fp_line (start -1.25 -1.6) (end -1.25 1.6)
      (stroke (width 0.15) (type solid)) (layer "F.Fab"))
    (fp_line (start 1.25 -1.6) (end -1.25 -1.6)
      (stroke (width 0.15) (type solid)) (layer "F.Fab"))
    (fp_line (start 1.25 -1.6) (end 1.25 1.6)
      (stroke (width 0.15) (type solid)) (layer "F.Fab"))
    (fp_line (start 1.25 1.6) (end -1.25 1.6)
      (stroke (width 0.15) (type solid)) (layer "F.Fab"))
    (pad "1" smd rect (at -0.8 -1.1) (size 1.2 1.4) (layers "F.Cu" "F.Paste" "F.Mask")
      (net 2 "VCC3V3") (pinfunction "EN") (pintype "input") (solder_mask_margin 0.0762))
    (pad "2" smd rect (at -0.8 1.1) (size 1.2 1.4) (layers "F.Cu" "F.Paste" "F.Mask")
      (net 1 "GND") (pinfunction "GND") (pintype "power_in") (solder_mask_margin 0.0762))
    (pad "3" smd rect (at 0.8 1.1) (size 1.2 1.4) (layers "F.Cu" "F.Paste" "F.Mask")
      (net 367 "GCLK100") (pinfunction "OUT") (pintype "output") (solder_mask_margin 0.0762))
    (pad "4" smd rect (at 0.8 -1.1) (size 1.2 1.4) (layers "F.Cu" "F.Paste" "F.Mask")
      (net 2 "VCC3V3") (pinfunction "VDD") (pintype "power_in") (solder_mask_margin 0.0762))
  )

  (footprint "antmicro-footprints:R_0402_1005Metric" (layer "B.Cu")
    (at 95.6 89.75 180)
    (descr "Resistor SMD 0402")
    (tags "resistor SMD 0402")
    (property "Author" "Antmicro")
    (property "License" "Apache-2.0")
    (property "MPN" "CR0402-FX-1022GLF")
    (property "Manufacturer" "Bourns")
    (property "Public" "False")
    (property "Sheetfile" "ethernet.kicad_sch")
    (property "Sheetname" "Ethernet")
    (property "Tolerance" "1%")
    (property "Val" "10k2")
    (property "ki_description" "SMD Chip Resistor")
    (property "ki_keywords" "0402, SMT, RESISTOR, PASSIVE")
    (attr smd)
    (fp_text reference "R11" (at 2.03 0.05 180) (layer "B.SilkS")
        (effects (font (size 0.7 0.7) (thickness 0.127)) (justify mirror))
    )
    (fp_text value "R_10k2_0402" (at 0 -1.17 180) (layer "B.Fab")
        (effects (font (size 1 1) (thickness 0.15)) (justify mirror))
    )
    (fp_text user "${REFERENCE}" (at 0 0 180) (layer "B.Fab")
        (effects (font (size 0.25 0.25) (thickness 0.04)) (justify mirror))
    )
    (fp_text user "License: Apache-2.0" (at -0.95 -5.169) (layer "B.Fab") hide
        (effects (font (size 0.7 0.7) (thickness 0.15)) (justify left bottom mirror))
    )
    (fp_text user "Author: Antmicro" (at -0.95 -4.169) (layer "B.Fab") hide
        (effects (font (size 0.7 0.7) (thickness 0.15)) (justify left bottom mirror))
    )
    (fp_rect (start -0.925 0.47) (end 0.925 -0.47)
      (stroke (width 0.05) (type default)) (fill none) (layer "B.CrtYd"))
    (fp_rect (start -0.5 0.25) (end 0.5 -0.25)
      (stroke (width 0.15) (type solid)) (fill none) (layer "B.Fab"))
    (pad "1" smd roundrect (at -0.48 0 180) (size 0.59 0.64) (layers "B.Cu" "B.Paste" "B.Mask") (roundrect_rratio 0.25)
      (net 164 "/Ethernet/ETH_LED1") (pintype "passive"))
    (pad "2" smd roundrect (at 0.48 0 180) (size 0.59 0.64) (layers "B.Cu" "B.Paste" "B.Mask") (roundrect_rratio 0.25)
      (net 2 "VCC3V3") (pintype "passive"))
  )

  (footprint "antmicro-footprints:SOT-23-3" (layer "B.Cu")
    (at 67.25 85.05)
    (property "Author" "Antmicro")
    (property "License" "Apache-2.0")
    (property "MPN" "2N7002")
    (property "Manufacturer" "ON Semiconductor")
    (property "Sheetfile" "power-supply.kicad_sch")
    (property "Sheetname" "Power supply")
    (property "ki_description" "Power MOSFET, N Channel, 60 V, 115 mA, 1.2 ohm, SOT-23, Surface Mount")
    (property "ki_keywords" "SMT, TRANSISTOR, SEMICONDUCTOR, NMOS")
    (attr smd)
    (fp_text reference "Q11" (at 1 -2.4) (layer "B.SilkS")
        (effects (font (size 0.7 0.7) (thickness 0.127)) (justify mirror))
    )
    (fp_text value "2N7002" (at 0.025 -3.25 180) (layer "B.Fab")
        (effects (font (size 1 1) (thickness 0.15)) (justify mirror))
    )
    (fp_text user "${REFERENCE}" (at -0.125 -0.15 180) (layer "B.Fab")
        (effects (font (size 0.25 0.25) (thickness 0.05)) (justify mirror))
    )
    (fp_text user "Author: Antmicro" (at -1.837 -5.3 180) (layer "B.Fab") hide
        (effects (font (size 0.7 0.7) (thickness 0.15)) (justify left bottom mirror))
    )
    (fp_text user "License: Apache-2.0" (at -1.8 -6.8 180) (layer "B.Fab") hide
        (effects (font (size 0.7 0.7) (thickness 0.15)) (justify left bottom mirror))
    )
    (fp_line (start -1.45 1.35) (end -0.85 1.35)
      (stroke (width 0.15) (type solid)) (layer "B.SilkS"))
    (fp_line (start -0.85 1.35) (end -0.7 1.5)
      (stroke (width 0.15) (type solid)) (layer "B.SilkS"))
    (fp_line (start -0.7 -1.5) (end -0.7 -1.35)
      (stroke (width 0.15) (type solid)) (layer "B.SilkS"))
    (fp_line (start 0.7 -1.5) (end -0.7 -1.5)
      (stroke (width 0.15) (type solid)) (layer "B.SilkS"))
    (fp_line (start 0.7 -0.4) (end 0.7 -1.5)
      (stroke (width 0.15) (type solid)) (layer "B.SilkS"))
    (fp_line (start 0.7 0.4) (end 0.7 1.5)
      (stroke (width 0.15) (type solid)) (layer "B.SilkS"))
    (fp_line (start 0.7 1.5) (end -0.7 1.5)
      (stroke (width 0.15) (type solid)) (layer "B.SilkS"))
    (fp_line (start -1.75 -1.4) (end -1.75 -0.5)
      (stroke (width 0.05) (type solid)) (layer "B.CrtYd"))
    (fp_line (start -1.75 -0.5) (end -0.85 -0.5)
      (stroke (width 0.05) (type solid)) (layer "B.CrtYd"))
    (fp_line (start -1.75 0.5) (end -1.75 1.4)
      (stroke (width 0.05) (type solid)) (layer "B.CrtYd"))
    (fp_line (start -0.9 1.4) (end -1.75 1.4)
      (stroke (width 0.05) (type solid)) (layer "B.CrtYd"))
    (fp_line (start -0.9 1.6) (end -0.9 1.4)
      (stroke (width 0.05) (type solid)) (layer "B.CrtYd"))
    (fp_line (start -0.9 1.6) (end 0.825 1.6)
      (stroke (width 0.05) (type solid)) (layer "B.CrtYd"))
    (fp_line (start -0.85 -1.65) (end -0.85 -1.4)
      (stroke (width 0.05) (type solid)) (layer "B.CrtYd"))
    (fp_line (start -0.85 -1.4) (end -1.75 -1.4)
      (stroke (width 0.05) (type solid)) (layer "B.CrtYd"))
    (fp_line (start -0.85 -0.5) (end -0.85 0.5)
      (stroke (width 0.05) (type solid)) (layer "B.CrtYd"))
    (fp_line (start -0.85 0.5) (end -1.75 0.5)
      (stroke (width 0.05) (type solid)) (layer "B.CrtYd"))
    (fp_line (start 0.825 0.45) (end 1.75 0.45)
      (stroke (width 0.05) (type solid)) (layer "B.CrtYd"))
    (fp_line (start 0.825 1.6) (end 0.825 0.45)
      (stroke (width 0.05) (type solid)) (layer "B.CrtYd"))
    (fp_line (start 0.85 -1.65) (end -0.85 -1.65)
      (stroke (width 0.05) (type solid)) (layer "B.CrtYd"))
    (fp_line (start 0.85 -0.45) (end 0.85 -1.65)
      (stroke (width 0.05) (type solid)) (layer "B.CrtYd"))
    (fp_line (start 1.75 -0.45) (end 0.85 -0.45)
      (stroke (width 0.05) (type solid)) (layer "B.CrtYd"))
    (fp_line (start 1.75 0.45) (end 1.75 -0.45)
      (stroke (width 0.05) (type solid)) (layer "B.CrtYd"))
    (fp_line (start -0.712 -1.519) (end 0.688 -1.519)
      (stroke (width 0.15) (type solid)) (layer "B.Fab"))
    (fp_line (start -0.712 1.325) (end -0.712 -1.523)
      (stroke (width 0.15) (type solid)) (layer "B.Fab"))
    (fp_line (start -0.437 1.526) (end -0.712 1.325)
      (stroke (width 0.15) (type solid)) (layer "B.Fab"))
    (fp_line (start -0.437 1.526) (end 0.688 1.526)
      (stroke (width 0.15) (type solid)) (layer "B.Fab"))
    (fp_line (start 0.688 -1.519) (end 0.688 1.52)
      (stroke (width 0.15) (type solid)) (layer "B.Fab"))
    (pad "1" smd roundrect (at -1.1 0.951) (size 1 0.6) (layers "B.Cu" "B.Paste" "B.Mask") (roundrect_rratio 0.15)
      (net 385 "1V0_PG") (pinfunction "G") (pintype "passive"))
    (pad "2" smd roundrect (at -1.1 -0.949) (size 1 0.6) (layers "B.Cu" "B.Paste" "B.Mask") (roundrect_rratio 0.15)
      (net 1 "GND") (pinfunction "S") (pintype "passive"))
    (pad "3" smd roundrect (at 1.1 0.0005) (size 1 0.6) (layers "B.Cu" "B.Paste" "B.Mask") (roundrect_rratio 0.15)
      (net 395 "Net-(Q11-D)") (pinfunction "D") (pintype "passive"))
  )

  (footprint "antmicro-footprints:SOT-23-3" (layer "B.Cu")
    (at 71.2 93.3 180)
    (property "Author" "Antmicro")
    (property "License" "Apache-2.0")
    (property "MPN" "2N7002")
    (property "Manufacturer" "ON Semiconductor")
    (property "Sheetfile" "power-supply.kicad_sch")
    (property "Sheetname" "Power supply")
    (property "ki_description" "Power MOSFET, N Channel, 60 V, 115 mA, 1.2 ohm, SOT-23, Surface Mount")
    (property "ki_keywords" "SMT, TRANSISTOR, SEMICONDUCTOR, NMOS")
    (attr smd)
    (fp_text reference "Q12" (at 0.1 -2.5 180) (layer "B.SilkS")
        (effects (font (size 0.7 0.7) (thickness 0.127)) (justify mirror))
    )
    (fp_text value "2N7002" (at 0.025 -3.25 180) (layer "B.Fab")
        (effects (font (size 1 1) (thickness 0.15)) (justify mirror))
    )
    (fp_text user "License: Apache-2.0" (at -1.8 -6.8) (layer "B.Fab") hide
        (effects (font (size 0.7 0.7) (thickness 0.15)) (justify left bottom mirror))
    )
    (fp_text user "Author: Antmicro" (at -1.837 -5.3) (layer "B.Fab") hide
        (effects (font (size 0.7 0.7) (thickness 0.15)) (justify left bottom mirror))
    )
    (fp_text user "${REFERENCE}" (at -0.125 -0.15 180) (layer "B.Fab")
        (effects (font (size 0.25 0.25) (thickness 0.05)) (justify mirror))
    )
    (fp_line (start -1.45 1.35) (end -0.85 1.35)
      (stroke (width 0.15) (type solid)) (layer "B.SilkS"))
    (fp_line (start -0.85 1.35) (end -0.7 1.5)
      (stroke (width 0.15) (type solid)) (layer "B.SilkS"))
    (fp_line (start -0.7 -1.5) (end -0.7 -1.35)
      (stroke (width 0.15) (type solid)) (layer "B.SilkS"))
    (fp_line (start 0.7 -1.5) (end -0.7 -1.5)
      (stroke (width 0.15) (type solid)) (layer "B.SilkS"))
    (fp_line (start 0.7 -0.4) (end 0.7 -1.5)
      (stroke (width 0.15) (type solid)) (layer "B.SilkS"))
    (fp_line (start 0.7 0.4) (end 0.7 1.5)
      (stroke (width 0.15) (type solid)) (layer "B.SilkS"))
    (fp_line (start 0.7 1.5) (end -0.7 1.5)
      (stroke (width 0.15) (type solid)) (layer "B.SilkS"))
    (fp_line (start -1.75 -1.4) (end -1.75 -0.5)
      (stroke (width 0.05) (type solid)) (layer "B.CrtYd"))
    (fp_line (start -1.75 -0.5) (end -0.85 -0.5)
      (stroke (width 0.05) (type solid)) (layer "B.CrtYd"))
    (fp_line (start -1.75 0.5) (end -1.75 1.4)
      (stroke (width 0.05) (type solid)) (layer "B.CrtYd"))
    (fp_line (start -0.9 1.4) (end -1.75 1.4)
      (stroke (width 0.05) (type solid)) (layer "B.CrtYd"))
    (fp_line (start -0.9 1.6) (end -0.9 1.4)
      (stroke (width 0.05) (type solid)) (layer "B.CrtYd"))
    (fp_line (start -0.9 1.6) (end 0.825 1.6)
      (stroke (width 0.05) (type solid)) (layer "B.CrtYd"))
    (fp_line (start -0.85 -1.65) (end -0.85 -1.4)
      (stroke (width 0.05) (type solid)) (layer "B.CrtYd"))
    (fp_line (start -0.85 -1.4) (end -1.75 -1.4)
      (stroke (width 0.05) (type solid)) (layer "B.CrtYd"))
    (fp_line (start -0.85 -0.5) (end -0.85 0.5)
      (stroke (width 0.05) (type solid)) (layer "B.CrtYd"))
    (fp_line (start -0.85 0.5) (end -1.75 0.5)
      (stroke (width 0.05) (type solid)) (layer "B.CrtYd"))
    (fp_line (start 0.825 0.45) (end 1.75 0.45)
      (stroke (width 0.05) (type solid)) (layer "B.CrtYd"))
    (fp_line (start 0.825 1.6) (end 0.825 0.45)
      (stroke (width 0.05) (type solid)) (layer "B.CrtYd"))
    (fp_line (start 0.85 -1.65) (end -0.85 -1.65)
      (stroke (width 0.05) (type solid)) (layer "B.CrtYd"))
    (fp_line (start 0.85 -0.45) (end 0.85 -1.65)
      (stroke (width 0.05) (type solid)) (layer "B.CrtYd"))
    (fp_line (start 1.75 -0.45) (end 0.85 -0.45)
      (stroke (width 0.05) (type solid)) (layer "B.CrtYd"))
    (fp_line (start 1.75 0.45) (end 1.75 -0.45)
      (stroke (width 0.05) (type solid)) (layer "B.CrtYd"))
    (fp_line (start -0.712 -1.519) (end 0.688 -1.519)
      (stroke (width 0.15) (type solid)) (layer "B.Fab"))
    (fp_line (start -0.712 1.325) (end -0.712 -1.523)
      (stroke (width 0.15) (type solid)) (layer "B.Fab"))
    (fp_line (start -0.437 1.526) (end -0.712 1.325)
      (stroke (width 0.15) (type solid)) (layer "B.Fab"))
    (fp_line (start -0.437 1.526) (end 0.688 1.526)
      (stroke (width 0.15) (type solid)) (layer "B.Fab"))
    (fp_line (start 0.688 -1.519) (end 0.688 1.52)
      (stroke (width 0.15) (type solid)) (layer "B.Fab"))
    (pad "1" smd roundrect (at -1.1 0.951 180) (size 1 0.6) (layers "B.Cu" "B.Paste" "B.Mask") (roundrect_rratio 0.15)
      (net 270 "/Power supply/5V0_PG") (pinfunction "G") (pintype "passive"))
    (pad "2" smd roundrect (at -1.1 -0.949 180) (size 1 0.6) (layers "B.Cu" "B.Paste" "B.Mask") (roundrect_rratio 0.15)
      (net 1 "GND") (pinfunction "S") (pintype "passive"))
    (pad "3" smd roundrect (at 1.1 0.0005 180) (size 1 0.6) (layers "B.Cu" "B.Paste" "B.Mask") (roundrect_rratio 0.15)
      (net 396 "Net-(Q12-D)") (pinfunction "D") (pintype "passive"))
  )

  (footprint "antmicro-footprints:SOT-23-3" (layer "B.Cu")
    (at 67.25 93.25 180)
    (property "Author" "Antmicro")
    (property "License" "Apache-2.0")
    (property "MPN" "2N7002")
    (property "Manufacturer" "ON Semiconductor")
    (property "Sheetfile" "power-supply.kicad_sch")
    (property "Sheetname" "Power supply")
    (property "ki_description" "Power MOSFET, N Channel, 60 V, 115 mA, 1.2 ohm, SOT-23, Surface Mount")
    (property "ki_keywords" "SMT, TRANSISTOR, SEMICONDUCTOR, NMOS")
    (attr smd)
    (fp_text reference "Q13" (at -0.25 -2.55 180) (layer "B.SilkS")
        (effects (font (size 0.7 0.7) (thickness 0.127)) (justify mirror))
    )
    (fp_text value "2N7002" (at 0.025 -3.25 180) (layer "B.Fab")
        (effects (font (size 1 1) (thickness 0.15)) (justify mirror))
    )
    (fp_text user "License: Apache-2.0" (at -1.8 -6.8) (layer "B.Fab") hide
        (effects (font (size 0.7 0.7) (thickness 0.15)) (justify left bottom mirror))
    )
    (fp_text user "Author: Antmicro" (at -1.837 -5.3) (layer "B.Fab") hide
        (effects (font (size 0.7 0.7) (thickness 0.15)) (justify left bottom mirror))
    )
    (fp_text user "${REFERENCE}" (at -0.125 -0.15 180) (layer "B.Fab")
        (effects (font (size 0.25 0.25) (thickness 0.05)) (justify mirror))
    )
    (fp_line (start -1.45 1.35) (end -0.85 1.35)
      (stroke (width 0.15) (type solid)) (layer "B.SilkS"))
    (fp_line (start -0.85 1.35) (end -0.7 1.5)
      (stroke (width 0.15) (type solid)) (layer "B.SilkS"))
    (fp_line (start -0.7 -1.5) (end -0.7 -1.35)
      (stroke (width 0.15) (type solid)) (layer "B.SilkS"))
    (fp_line (start 0.7 -1.5) (end -0.7 -1.5)
      (stroke (width 0.15) (type solid)) (layer "B.SilkS"))
    (fp_line (start 0.7 -0.4) (end 0.7 -1.5)
      (stroke (width 0.15) (type solid)) (layer "B.SilkS"))
    (fp_line (start 0.7 0.4) (end 0.7 1.5)
      (stroke (width 0.15) (type solid)) (layer "B.SilkS"))
    (fp_line (start 0.7 1.5) (end -0.7 1.5)
      (stroke (width 0.15) (type solid)) (layer "B.SilkS"))
    (fp_line (start -1.75 -1.4) (end -1.75 -0.5)
      (stroke (width 0.05) (type solid)) (layer "B.CrtYd"))
    (fp_line (start -1.75 -0.5) (end -0.85 -0.5)
      (stroke (width 0.05) (type solid)) (layer "B.CrtYd"))
    (fp_line (start -1.75 0.5) (end -1.75 1.4)
      (stroke (width 0.05) (type solid)) (layer "B.CrtYd"))
    (fp_line (start -0.9 1.4) (end -1.75 1.4)
      (stroke (width 0.05) (type solid)) (layer "B.CrtYd"))
    (fp_line (start -0.9 1.6) (end -0.9 1.4)
      (stroke (width 0.05) (type solid)) (layer "B.CrtYd"))
    (fp_line (start -0.9 1.6) (end 0.825 1.6)
      (stroke (width 0.05) (type solid)) (layer "B.CrtYd"))
    (fp_line (start -0.85 -1.65) (end -0.85 -1.4)
      (stroke (width 0.05) (type solid)) (layer "B.CrtYd"))
    (fp_line (start -0.85 -1.4) (end -1.75 -1.4)
      (stroke (width 0.05) (type solid)) (layer "B.CrtYd"))
    (fp_line (start -0.85 -0.5) (end -0.85 0.5)
      (stroke (width 0.05) (type solid)) (layer "B.CrtYd"))
    (fp_line (start -0.85 0.5) (end -1.75 0.5)
      (stroke (width 0.05) (type solid)) (layer "B.CrtYd"))
    (fp_line (start 0.825 0.45) (end 1.75 0.45)
      (stroke (width 0.05) (type solid)) (layer "B.CrtYd"))
    (fp_line (start 0.825 1.6) (end 0.825 0.45)
      (stroke (width 0.05) (type solid)) (layer "B.CrtYd"))
    (fp_line (start 0.85 -1.65) (end -0.85 -1.65)
      (stroke (width 0.05) (type solid)) (layer "B.CrtYd"))
    (fp_line (start 0.85 -0.45) (end 0.85 -1.65)
      (stroke (width 0.05) (type solid)) (layer "B.CrtYd"))
    (fp_line (start 1.75 -0.45) (end 0.85 -0.45)
      (stroke (width 0.05) (type solid)) (layer "B.CrtYd"))
    (fp_line (start 1.75 0.45) (end 1.75 -0.45)
      (stroke (width 0.05) (type solid)) (layer "B.CrtYd"))
    (fp_line (start -0.712 -1.519) (end 0.688 -1.519)
      (stroke (width 0.15) (type solid)) (layer "B.Fab"))
    (fp_line (start -0.712 1.325) (end -0.712 -1.523)
      (stroke (width 0.15) (type solid)) (layer "B.Fab"))
    (fp_line (start -0.437 1.526) (end -0.712 1.325)
      (stroke (width 0.15) (type solid)) (layer "B.Fab"))
    (fp_line (start -0.437 1.526) (end 0.688 1.526)
      (stroke (width 0.15) (type solid)) (layer "B.Fab"))
    (fp_line (start 0.688 -1.519) (end 0.688 1.52)
      (stroke (width 0.15) (type solid)) (layer "B.Fab"))
    (pad "1" smd roundrect (at -1.1 0.951 180) (size 1 0.6) (layers "B.Cu" "B.Paste" "B.Mask") (roundrect_rratio 0.15)
      (net 222 "/Power supply/3V3_PG") (pinfunction "G") (pintype "passive"))
    (pad "2" smd roundrect (at -1.1 -0.949 180) (size 1 0.6) (layers "B.Cu" "B.Paste" "B.Mask") (roundrect_rratio 0.15)
      (net 1 "GND") (pinfunction "S") (pintype "passive"))
    (pad "3" smd roundrect (at 1.1 0.0005 180) (size 1 0.6) (layers "B.Cu" "B.Paste" "B.Mask") (roundrect_rratio 0.15)
      (net 397 "Net-(Q13-D)") (pinfunction "D") (pintype "passive"))
  )

  (footprint "antmicro-footprints:SOT-23-3" (layer "B.Cu")
    (at 71.2 89.15 180)
    (property "Author" "Antmicro")
    (property "License" "Apache-2.0")
    (property "MPN" "2N7002")
    (property "Manufacturer" "ON Semiconductor")
    (property "Sheetfile" "power-supply.kicad_sch")
    (property "Sheetname" "Power supply")
    (property "ki_description" "Power MOSFET, N Channel, 60 V, 115 mA, 1.2 ohm, SOT-23, Surface Mount")
    (property "ki_keywords" "SMT, TRANSISTOR, SEMICONDUCTOR, NMOS")
    (attr smd)
    (fp_text reference "Q14" (at -2.4 -0.9 90) (layer "B.SilkS")
        (effects (font (size 0.7 0.7) (thickness 0.127)) (justify mirror))
    )
    (fp_text value "2N7002" (at 0.025 -3.25) (layer "B.Fab")
        (effects (font (size 1 1) (thickness 0.15)) (justify mirror))
    )
    (fp_text user "Author: Antmicro" (at -1.837 -5.3) (layer "B.Fab") hide
        (effects (font (size 0.7 0.7) (thickness 0.15)) (justify left bottom mirror))
    )
    (fp_text user "${REFERENCE}" (at -0.125 -0.15) (layer "B.Fab")
        (effects (font (size 0.25 0.25) (thickness 0.05)) (justify mirror))
    )
    (fp_text user "License: Apache-2.0" (at -1.8 -6.8) (layer "B.Fab") hide
        (effects (font (size 0.7 0.7) (thickness 0.15)) (justify left bottom mirror))
    )
    (fp_line (start -1.45 1.35) (end -0.85 1.35)
      (stroke (width 0.15) (type solid)) (layer "B.SilkS"))
    (fp_line (start -0.85 1.35) (end -0.7 1.5)
      (stroke (width 0.15) (type solid)) (layer "B.SilkS"))
    (fp_line (start -0.7 -1.5) (end -0.7 -1.35)
      (stroke (width 0.15) (type solid)) (layer "B.SilkS"))
    (fp_line (start 0.7 -1.5) (end -0.7 -1.5)
      (stroke (width 0.15) (type solid)) (layer "B.SilkS"))
    (fp_line (start 0.7 -0.4) (end 0.7 -1.5)
      (stroke (width 0.15) (type solid)) (layer "B.SilkS"))
    (fp_line (start 0.7 0.4) (end 0.7 1.5)
      (stroke (width 0.15) (type solid)) (layer "B.SilkS"))
    (fp_line (start 0.7 1.5) (end -0.7 1.5)
      (stroke (width 0.15) (type solid)) (layer "B.SilkS"))
    (fp_line (start -1.75 -1.4) (end -1.75 -0.5)
      (stroke (width 0.05) (type solid)) (layer "B.CrtYd"))
    (fp_line (start -1.75 -0.5) (end -0.85 -0.5)
      (stroke (width 0.05) (type solid)) (layer "B.CrtYd"))
    (fp_line (start -1.75 0.5) (end -1.75 1.4)
      (stroke (width 0.05) (type solid)) (layer "B.CrtYd"))
    (fp_line (start -0.9 1.4) (end -1.75 1.4)
      (stroke (width 0.05) (type solid)) (layer "B.CrtYd"))
    (fp_line (start -0.9 1.6) (end -0.9 1.4)
      (stroke (width 0.05) (type solid)) (layer "B.CrtYd"))
    (fp_line (start -0.9 1.6) (end 0.825 1.6)
      (stroke (width 0.05) (type solid)) (layer "B.CrtYd"))
    (fp_line (start -0.85 -1.65) (end -0.85 -1.4)
      (stroke (width 0.05) (type solid)) (layer "B.CrtYd"))
    (fp_line (start -0.85 -1.4) (end -1.75 -1.4)
      (stroke (width 0.05) (type solid)) (layer "B.CrtYd"))
    (fp_line (start -0.85 -0.5) (end -0.85 0.5)
      (stroke (width 0.05) (type solid)) (layer "B.CrtYd"))
    (fp_line (start -0.85 0.5) (end -1.75 0.5)
      (stroke (width 0.05) (type solid)) (layer "B.CrtYd"))
    (fp_line (start 0.825 0.45) (end 1.75 0.45)
      (stroke (width 0.05) (type solid)) (layer "B.CrtYd"))
    (fp_line (start 0.825 1.6) (end 0.825 0.45)
      (stroke (width 0.05) (type solid)) (layer "B.CrtYd"))
    (fp_line (start 0.85 -1.65) (end -0.85 -1.65)
      (stroke (width 0.05) (type solid)) (layer "B.CrtYd"))
    (fp_line (start 0.85 -0.45) (end 0.85 -1.65)
      (stroke (width 0.05) (type solid)) (layer "B.CrtYd"))
    (fp_line (start 1.75 -0.45) (end 0.85 -0.45)
      (stroke (width 0.05) (type solid)) (layer "B.CrtYd"))
    (fp_line (start 1.75 0.45) (end 1.75 -0.45)
      (stroke (width 0.05) (type solid)) (layer "B.CrtYd"))
    (fp_line (start -0.712 -1.519) (end 0.688 -1.519)
      (stroke (width 0.15) (type solid)) (layer "B.Fab"))
    (fp_line (start -0.712 1.325) (end -0.712 -1.523)
      (stroke (width 0.15) (type solid)) (layer "B.Fab"))
    (fp_line (start -0.437 1.526) (end -0.712 1.325)
      (stroke (width 0.15) (type solid)) (layer "B.Fab"))
    (fp_line (start -0.437 1.526) (end 0.688 1.526)
      (stroke (width 0.15) (type solid)) (layer "B.Fab"))
    (fp_line (start 0.688 -1.519) (end 0.688 1.52)
      (stroke (width 0.15) (type solid)) (layer "B.Fab"))
    (pad "1" smd roundrect (at -1.1 0.951 180) (size 1 0.6) (layers "B.Cu" "B.Paste" "B.Mask") (roundrect_rratio 0.15)
      (net 236 "/Power supply/2V5_PG") (pinfunction "G") (pintype "passive"))
    (pad "2" smd roundrect (at -1.1 -0.949 180) (size 1 0.6) (layers "B.Cu" "B.Paste" "B.Mask") (roundrect_rratio 0.15)
      (net 1 "GND") (pinfunction "S") (pintype "passive"))
    (pad "3" smd roundrect (at 1.1 0.0005 180) (size 1 0.6) (layers "B.Cu" "B.Paste" "B.Mask") (roundrect_rratio 0.15)
      (net 398 "Net-(Q14-D)") (pinfunction "D") (pintype "passive"))
  )

  (footprint "antmicro-footprints:SOT-23-3" (layer "B.Cu")
    (at 75.15 93.3 180)
    (property "Author" "Antmicro")
    (property "License" "Apache-2.0")
    (property "MPN" "2N7002")
    (property "Manufacturer" "ON Semiconductor")
    (property "Sheetfile" "power-supply.kicad_sch")
    (property "Sheetname" "Power supply")
    (property "ki_description" "Power MOSFET, N Channel, 60 V, 115 mA, 1.2 ohm, SOT-23, Surface Mount")
    (property "ki_keywords" "SMT, TRANSISTOR, SEMICONDUCTOR, NMOS")
    (attr smd)
    (fp_text reference "Q15" (at 0.025 -2.6 180) (layer "B.SilkS")
        (effects (font (size 0.7 0.7) (thickness 0.127)) (justify mirror))
    )
    (fp_text value "2N7002" (at 0.025 -3.25 180) (layer "B.Fab")
        (effects (font (size 1 1) (thickness 0.15)) (justify mirror))
    )
    (fp_text user "License: Apache-2.0" (at -1.8 -6.8) (layer "B.Fab") hide
        (effects (font (size 0.7 0.7) (thickness 0.15)) (justify left bottom mirror))
    )
    (fp_text user "Author: Antmicro" (at -1.837 -5.3) (layer "B.Fab") hide
        (effects (font (size 0.7 0.7) (thickness 0.15)) (justify left bottom mirror))
    )
    (fp_text user "${REFERENCE}" (at -0.125 -0.15 180) (layer "B.Fab")
        (effects (font (size 0.25 0.25) (thickness 0.05)) (justify mirror))
    )
    (fp_line (start -1.45 1.35) (end -0.85 1.35)
      (stroke (width 0.15) (type solid)) (layer "B.SilkS"))
    (fp_line (start -0.85 1.35) (end -0.7 1.5)
      (stroke (width 0.15) (type solid)) (layer "B.SilkS"))
    (fp_line (start -0.7 -1.5) (end -0.7 -1.35)
      (stroke (width 0.15) (type solid)) (layer "B.SilkS"))
    (fp_line (start 0.7 -1.5) (end -0.7 -1.5)
      (stroke (width 0.15) (type solid)) (layer "B.SilkS"))
    (fp_line (start 0.7 -0.4) (end 0.7 -1.5)
      (stroke (width 0.15) (type solid)) (layer "B.SilkS"))
    (fp_line (start 0.7 0.4) (end 0.7 1.5)
      (stroke (width 0.15) (type solid)) (layer "B.SilkS"))
    (fp_line (start 0.7 1.5) (end -0.7 1.5)
      (stroke (width 0.15) (type solid)) (layer "B.SilkS"))
    (fp_line (start -1.75 -1.4) (end -1.75 -0.5)
      (stroke (width 0.05) (type solid)) (layer "B.CrtYd"))
    (fp_line (start -1.75 -0.5) (end -0.85 -0.5)
      (stroke (width 0.05) (type solid)) (layer "B.CrtYd"))
    (fp_line (start -1.75 0.5) (end -1.75 1.4)
      (stroke (width 0.05) (type solid)) (layer "B.CrtYd"))
    (fp_line (start -0.9 1.4) (end -1.75 1.4)
      (stroke (width 0.05) (type solid)) (layer "B.CrtYd"))
    (fp_line (start -0.9 1.6) (end -0.9 1.4)
      (stroke (width 0.05) (type solid)) (layer "B.CrtYd"))
    (fp_line (start -0.9 1.6) (end 0.825 1.6)
      (stroke (width 0.05) (type solid)) (layer "B.CrtYd"))
    (fp_line (start -0.85 -1.65) (end -0.85 -1.4)
      (stroke (width 0.05) (type solid)) (layer "B.CrtYd"))
    (fp_line (start -0.85 -1.4) (end -1.75 -1.4)
      (stroke (width 0.05) (type solid)) (layer "B.CrtYd"))
    (fp_line (start -0.85 -0.5) (end -0.85 0.5)
      (stroke (width 0.05) (type solid)) (layer "B.CrtYd"))
    (fp_line (start -0.85 0.5) (end -1.75 0.5)
      (stroke (width 0.05) (type solid)) (layer "B.CrtYd"))
    (fp_line (start 0.825 0.45) (end 1.75 0.45)
      (stroke (width 0.05) (type solid)) (layer "B.CrtYd"))
    (fp_line (start 0.825 1.6) (end 0.825 0.45)
      (stroke (width 0.05) (type solid)) (layer "B.CrtYd"))
    (fp_line (start 0.85 -1.65) (end -0.85 -1.65)
      (stroke (width 0.05) (type solid)) (layer "B.CrtYd"))
    (fp_line (start 0.85 -0.45) (end 0.85 -1.65)
      (stroke (width 0.05) (type solid)) (layer "B.CrtYd"))
    (fp_line (start 1.75 -0.45) (end 0.85 -0.45)
      (stroke (width 0.05) (type solid)) (layer "B.CrtYd"))
    (fp_line (start 1.75 0.45) (end 1.75 -0.45)
      (stroke (width 0.05) (type solid)) (layer "B.CrtYd"))
    (fp_line (start -0.712 -1.519) (end 0.688 -1.519)
      (stroke (width 0.15) (type solid)) (layer "B.Fab"))
    (fp_line (start -0.712 1.325) (end -0.712 -1.523)
      (stroke (width 0.15) (type solid)) (layer "B.Fab"))
    (fp_line (start -0.437 1.526) (end -0.712 1.325)
      (stroke (width 0.15) (type solid)) (layer "B.Fab"))
    (fp_line (start -0.437 1.526) (end 0.688 1.526)
      (stroke (width 0.15) (type solid)) (layer "B.Fab"))
    (fp_line (start 0.688 -1.519) (end 0.688 1.52)
      (stroke (width 0.15) (type solid)) (layer "B.Fab"))
    (pad "1" smd roundrect (at -1.1 0.951 180) (size 1 0.6) (layers "B.Cu" "B.Paste" "B.Mask") (roundrect_rratio 0.15)
      (net 223 "/Power supply/1V8_PG") (pinfunction "G") (pintype "passive"))
    (pad "2" smd roundrect (at -1.1 -0.949 180) (size 1 0.6) (layers "B.Cu" "B.Paste" "B.Mask") (roundrect_rratio 0.15)
      (net 1 "GND") (pinfunction "S") (pintype "passive"))
    (pad "3" smd roundrect (at 1.1 0.0005 180) (size 1 0.6) (layers "B.Cu" "B.Paste" "B.Mask") (roundrect_rratio 0.15)
      (net 399 "Net-(Q15-D)") (pinfunction "D") (pintype "passive"))
  )

  (footprint "antmicro-footprints:R_0402_1005Metric" (layer "B.Cu")
    (at 89.15 87.55 180)
    (descr "Resistor SMD 0402")
    (tags "resistor SMD 0402")
    (property "Author" "Antmicro")
    (property "License" "Apache-2.0")
    (property "MPN" "CR0402-FX-1002GLF")
    (property "Manufacturer" "Bourns")
    (property "Public" "False")
    (property "Sheetfile" "power-supply.kicad_sch")
    (property "Sheetname" "Power supply")
    (property "Tolerance" "1%")
    (property "Val" "10k")
    (property "ki_description" "SMD Chip Resistor, 10 kohm, ± 1%, 62.5 mW, 0402 [1005 Metric], Thick Film, General Purpose")
    (property "ki_keywords" "0402, SMT, RESISTOR, PASSIVE")
    (attr smd)
    (fp_text reference "R104" (at 0 1.17 180) (layer "B.SilkS")
        (effects (font (size 0.7 0.7) (thickness 0.127)) (justify mirror))
    )
    (fp_text value "R_10k_0402" (at 0 -1.17 180) (layer "B.Fab")
        (effects (font (size 1 1) (thickness 0.15)) (justify mirror))
    )
    (fp_text user "${REFERENCE}" (at 0 0 180) (layer "B.Fab")
        (effects (font (size 0.25 0.25) (thickness 0.04)) (justify mirror))
    )
    (fp_text user "Author: Antmicro" (at -0.95 -4.169) (layer "B.Fab") hide
        (effects (font (size 0.7 0.7) (thickness 0.15)) (justify left bottom mirror))
    )
    (fp_text user "License: Apache-2.0" (at -0.95 -5.169) (layer "B.Fab") hide
        (effects (font (size 0.7 0.7) (thickness 0.15)) (justify left bottom mirror))
    )
    (fp_rect (start -0.925 0.47) (end 0.925 -0.47)
      (stroke (width 0.05) (type default)) (fill none) (layer "B.CrtYd"))
    (fp_rect (start -0.5 0.25) (end 0.5 -0.25)
      (stroke (width 0.15) (type solid)) (fill none) (layer "B.Fab"))
    (pad "1" smd roundrect (at -0.48 0 180) (size 0.59 0.64) (layers "B.Cu" "B.Paste" "B.Mask") (roundrect_rratio 0.25)
      (net 11 "VCC5V0") (pintype "passive"))
    (pad "2" smd roundrect (at 0.48 0 180) (size 0.59 0.64) (layers "B.Cu" "B.Paste" "B.Mask") (roundrect_rratio 0.25)
      (net 236 "/Power supply/2V5_PG") (pintype "passive"))
  )

  (footprint "antmicro-footprints:R_0402_1005Metric" (layer "B.Cu")
    (at 117.909056 89.493104 180)
    (descr "Resistor SMD 0402")
    (tags "resistor SMD 0402")
    (property "Author" "Antmicro")
    (property "License" "Apache-2.0")
    (property "MPN" "CR0402-FX-1002GLF")
    (property "Manufacturer" "Bourns")
    (property "Public" "False")
    (property "Sheetfile" "power-supply.kicad_sch")
    (property "Sheetname" "Power supply")
    (property "Tolerance" "1%")
    (property "Val" "10k")
    (property "ki_description" "SMD Chip Resistor, 10 kohm, ± 1%, 62.5 mW, 0402 [1005 Metric], Thick Film, General Purpose")
    (property "ki_keywords" "0402, SMT, RESISTOR, PASSIVE")
    (attr smd)
    (fp_text reference "R105" (at 0 0.95 180) (layer "B.SilkS")
        (effects (font (size 0.7 0.7) (thickness 0.127)) (justify mirror))
    )
    (fp_text value "R_10k_0402" (at 0 -1.17 180) (layer "B.Fab")
        (effects (font (size 1 1) (thickness 0.15)) (justify mirror))
    )
    (fp_text user "Author: Antmicro" (at -0.95 -4.169) (layer "B.Fab") hide
        (effects (font (size 0.7 0.7) (thickness 0.15)) (justify left bottom mirror))
    )
    (fp_text user "License: Apache-2.0" (at -0.95 -5.169) (layer "B.Fab") hide
        (effects (font (size 0.7 0.7) (thickness 0.15)) (justify left bottom mirror))
    )
    (fp_text user "${REFERENCE}" (at 0 0 180) (layer "B.Fab")
        (effects (font (size 0.25 0.25) (thickness 0.04)) (justify mirror))
    )
    (fp_rect (start -0.925 0.47) (end 0.925 -0.47)
      (stroke (width 0.05) (type default)) (fill none) (layer "B.CrtYd"))
    (fp_rect (start -0.5 0.25) (end 0.5 -0.25)
      (stroke (width 0.15) (type solid)) (fill none) (layer "B.Fab"))
    (pad "1" smd roundrect (at -0.48 0 180) (size 0.59 0.64) (layers "B.Cu" "B.Paste" "B.Mask") (roundrect_rratio 0.25)
      (net 11 "VCC5V0") (pintype "passive"))
    (pad "2" smd roundrect (at 0.48 0 180) (size 0.59 0.64) (layers "B.Cu" "B.Paste" "B.Mask") (roundrect_rratio 0.25)
      (net 223 "/Power supply/1V8_PG") (pintype "passive"))
  )

  (footprint "antmicro-footprints:R_0402_1005Metric" (layer "B.Cu")
    (at 64.25 86.7 180)
    (descr "Resistor SMD 0402")
    (tags "resistor SMD 0402")
    (property "Author" "Antmicro")
    (property "License" "Apache-2.0")
    (property "MPN" "CR0402-FX-1001GLF")
    (property "Manufacturer" "Bourns")
    (property "Public" "False")
    (property "Sheetfile" "power-supply.kicad_sch")
    (property "Sheetname" "Power supply")
    (property "Tolerance" "1%")
    (property "Val" "1k")
    (property "ki_description" "SMD Chip Resistor, 1 kohm, ± 1%, 63 mW, 0402 [1005 Metric], Thick Film, General Purpose")
    (property "ki_keywords" "0402, SMT, RESISTOR, PASSIVE")
    (attr smd)
    (fp_text reference "R107" (at 0.13 0.805 180) (layer "B.SilkS")
        (effects (font (size 0.7 0.7) (thickness 0.127)) (justify mirror))
    )
    (fp_text value "R_1k_0402" (at 0 -1.17 180) (layer "B.Fab")
        (effects (font (size 1 1) (thickness 0.15)) (justify mirror))
    )
    (fp_text user "License: Apache-2.0" (at -0.95 -5.169) (layer "B.Fab") hide
        (effects (font (size 0.7 0.7) (thickness 0.15)) (justify left bottom mirror))
    )
    (fp_text user "Author: Antmicro" (at -0.95 -4.169) (layer "B.Fab") hide
        (effects (font (size 0.7 0.7) (thickness 0.15)) (justify left bottom mirror))
    )
    (fp_text user "${REFERENCE}" (at 0 0 180) (layer "B.Fab")
        (effects (font (size 0.25 0.25) (thickness 0.04)) (justify mirror))
    )
    (fp_rect (start -0.925 0.47) (end 0.925 -0.47)
      (stroke (width 0.05) (type default)) (fill none) (layer "B.CrtYd"))
    (fp_rect (start -0.5 0.25) (end 0.5 -0.25)
      (stroke (width 0.15) (type solid)) (fill none) (layer "B.Fab"))
    (pad "1" smd roundrect (at -0.48 0 180) (size 0.59 0.64) (layers "B.Cu" "B.Paste" "B.Mask") (roundrect_rratio 0.25)
      (net 394 "Net-(Q10-D)") (pintype "passive"))
    (pad "2" smd roundrect (at 0.48 0 180) (size 0.59 0.64) (layers "B.Cu" "B.Paste" "B.Mask") (roundrect_rratio 0.25)
      (net 315 "Net-(D7-A)") (pintype "passive"))
  )

  (footprint "antmicro-footprints:R_0402_1005Metric" (layer "B.Cu")
    (at 64.25 85.05 180)
    (descr "Resistor SMD 0402")
    (tags "resistor SMD 0402")
    (property "Author" "Antmicro")
    (property "License" "Apache-2.0")
    (property "MPN" "CR0402-FX-1001GLF")
    (property "Manufacturer" "Bourns")
    (property "Public" "False")
    (property "Sheetfile" "power-supply.kicad_sch")
    (property "Sheetname" "Power supply")
    (property "Tolerance" "1%")
    (property "Val" "1k")
    (property "ki_description" "SMD Chip Resistor, 1 kohm, ± 1%, 63 mW, 0402 [1005 Metric], Thick Film, General Purpose")
    (property "ki_keywords" "0402, SMT, RESISTOR, PASSIVE")
    (attr smd)
    (fp_text reference "R108" (at 0.17 0.765 180) (layer "B.SilkS")
        (effects (font (size 0.7 0.7) (thickness 0.127)) (justify mirror))
    )
    (fp_text value "R_1k_0402" (at 0 -1.17 180) (layer "B.Fab")
        (effects (font (size 1 1) (thickness 0.15)) (justify mirror))
    )
    (fp_text user "Author: Antmicro" (at -0.95 -4.169) (layer "B.Fab") hide
        (effects (font (size 0.7 0.7) (thickness 0.15)) (justify left bottom mirror))
    )
    (fp_text user "${REFERENCE}" (at 0 0 180) (layer "B.Fab")
        (effects (font (size 0.25 0.25) (thickness 0.04)) (justify mirror))
    )
    (fp_text user "License: Apache-2.0" (at -0.95 -5.169) (layer "B.Fab") hide
        (effects (font (size 0.7 0.7) (thickness 0.15)) (justify left bottom mirror))
    )
    (fp_rect (start -0.925 0.47) (end 0.925 -0.47)
      (stroke (width 0.05) (type default)) (fill none) (layer "B.CrtYd"))
    (fp_rect (start -0.5 0.25) (end 0.5 -0.25)
      (stroke (width 0.15) (type solid)) (fill none) (layer "B.Fab"))
    (pad "1" smd roundrect (at -0.48 0 180) (size 0.59 0.64) (layers "B.Cu" "B.Paste" "B.Mask") (roundrect_rratio 0.25)
      (net 395 "Net-(Q11-D)") (pintype "passive"))
    (pad "2" smd roundrect (at 0.48 0 180) (size 0.59 0.64) (layers "B.Cu" "B.Paste" "B.Mask") (roundrect_rratio 0.25)
      (net 316 "Net-(D8-A)") (pintype "passive"))
  )

  (footprint "antmicro-footprints:R_0402_1005Metric" (layer "B.Cu")
    (at 64.25 94.95 180)
    (descr "Resistor SMD 0402")
    (tags "resistor SMD 0402")
    (property "Author" "Antmicro")
    (property "License" "Apache-2.0")
    (property "MPN" "CR0402-FX-1001GLF")
    (property "Manufacturer" "Bourns")
    (property "Public" "False")
    (property "Sheetfile" "power-supply.kicad_sch")
    (property "Sheetname" "Power supply")
    (property "Tolerance" "1%")
    (property "Val" "1k")
    (property "ki_description" "SMD Chip Resistor, 1 kohm, ± 1%, 63 mW, 0402 [1005 Metric], Thick Film, General Purpose")
    (property "ki_keywords" "0402, SMT, RESISTOR, PASSIVE")
    (attr smd)
    (fp_text reference "R109" (at -0.07 -0.895 180) (layer "B.SilkS")
        (effects (font (size 0.7 0.7) (thickness 0.127)) (justify mirror))
    )
    (fp_text value "R_1k_0402" (at 0 -1.17 180) (layer "B.Fab")
        (effects (font (size 1 1) (thickness 0.15)) (justify mirror))
    )
    (fp_text user "License: Apache-2.0" (at -0.95 -5.169) (layer "B.Fab") hide
        (effects (font (size 0.7 0.7) (thickness 0.15)) (justify left bottom mirror))
    )
    (fp_text user "${REFERENCE}" (at 0 0 180) (layer "B.Fab")
        (effects (font (size 0.25 0.25) (thickness 0.04)) (justify mirror))
    )
    (fp_text user "Author: Antmicro" (at -0.95 -4.169) (layer "B.Fab") hide
        (effects (font (size 0.7 0.7) (thickness 0.15)) (justify left bottom mirror))
    )
    (fp_rect (start -0.925 0.47) (end 0.925 -0.47)
      (stroke (width 0.05) (type default)) (fill none) (layer "B.CrtYd"))
    (fp_rect (start -0.5 0.25) (end 0.5 -0.25)
      (stroke (width 0.15) (type solid)) (fill none) (layer "B.Fab"))
    (pad "1" smd roundrect (at -0.48 0 180) (size 0.59 0.64) (layers "B.Cu" "B.Paste" "B.Mask") (roundrect_rratio 0.25)
      (net 396 "Net-(Q12-D)") (pintype "passive"))
    (pad "2" smd roundrect (at 0.48 0 180) (size 0.59 0.64) (layers "B.Cu" "B.Paste" "B.Mask") (roundrect_rratio 0.25)
      (net 343 "Net-(D9-A)") (pintype "passive"))
  )

  (footprint "antmicro-footprints:R_0402_1005Metric" (layer "B.Cu")
    (at 64.25 93.3 180)
    (descr "Resistor SMD 0402")
    (tags "resistor SMD 0402")
    (property "Author" "Antmicro")
    (property "License" "Apache-2.0")
    (property "MPN" "CR0402-FX-1001GLF")
    (property "Manufacturer" "Bourns")
    (property "Public" "False")
    (property "Sheetfile" "power-supply.kicad_sch")
    (property "Sheetname" "Power supply")
    (property "Tolerance" "1%")
    (property "Val" "1k")
    (property "ki_description" "SMD Chip Resistor, 1 kohm, ± 1%, 63 mW, 0402 [1005 Metric], Thick Film, General Purpose")
    (property "ki_keywords" "0402, SMT, RESISTOR, PASSIVE")
    (attr smd)
    (fp_text reference "R110" (at 0.15 0.8 180) (layer "B.SilkS")
        (effects (font (size 0.7 0.7) (thickness 0.127)) (justify mirror))
    )
    (fp_text value "R_1k_0402" (at 0 -1.17 180) (layer "B.Fab")
        (effects (font (size 1 1) (thickness 0.15)) (justify mirror))
    )
    (fp_text user "Author: Antmicro" (at -0.95 -4.169) (layer "B.Fab") hide
        (effects (font (size 0.7 0.7) (thickness 0.15)) (justify left bottom mirror))
    )
    (fp_text user "${REFERENCE}" (at 0 0 180) (layer "B.Fab")
        (effects (font (size 0.25 0.25) (thickness 0.04)) (justify mirror))
    )
    (fp_text user "License: Apache-2.0" (at -0.95 -5.169) (layer "B.Fab") hide
        (effects (font (size 0.7 0.7) (thickness 0.15)) (justify left bottom mirror))
    )
    (fp_rect (start -0.925 0.47) (end 0.925 -0.47)
      (stroke (width 0.05) (type default)) (fill none) (layer "B.CrtYd"))
    (fp_rect (start -0.5 0.25) (end 0.5 -0.25)
      (stroke (width 0.15) (type solid)) (fill none) (layer "B.Fab"))
    (pad "1" smd roundrect (at -0.48 0 180) (size 0.59 0.64) (layers "B.Cu" "B.Paste" "B.Mask") (roundrect_rratio 0.25)
      (net 397 "Net-(Q13-D)") (pintype "passive"))
    (pad "2" smd roundrect (at 0.48 0 180) (size 0.59 0.64) (layers "B.Cu" "B.Paste" "B.Mask") (roundrect_rratio 0.25)
      (net 344 "Net-(D10-A)") (pintype "passive"))
  )

  (footprint "antmicro-footprints:R_0402_1005Metric" (layer "B.Cu")
    (at 64.25 91.65 180)
    (descr "Resistor SMD 0402")
    (tags "resistor SMD 0402")
    (property "Author" "Antmicro")
    (property "License" "Apache-2.0")
    (property "MPN" "CR0402-FX-1001GLF")
    (property "Manufacturer" "Bourns")
    (property "Public" "False")
    (property "Sheetfile" "power-supply.kicad_sch")
    (property "Sheetname" "Power supply")
    (property "Tolerance" "1%")
    (property "Val" "1k")
    (property "ki_description" "SMD Chip Resistor, 1 kohm, ± 1%, 63 mW, 0402 [1005 Metric], Thick Film, General Purpose")
    (property "ki_keywords" "0402, SMT, RESISTOR, PASSIVE")
    (attr smd)
    (fp_text reference "R111" (at 0.15 0.8 180) (layer "B.SilkS")
        (effects (font (size 0.7 0.7) (thickness 0.127)) (justify mirror))
    )
    (fp_text value "R_1k_0402" (at 0 -1.17 180) (layer "B.Fab")
        (effects (font (size 1 1) (thickness 0.15)) (justify mirror))
    )
    (fp_text user "${REFERENCE}" (at 0 0 180) (layer "B.Fab")
        (effects (font (size 0.25 0.25) (thickness 0.04)) (justify mirror))
    )
    (fp_text user "License: Apache-2.0" (at -0.95 -5.169) (layer "B.Fab") hide
        (effects (font (size 0.7 0.7) (thickness 0.15)) (justify left bottom mirror))
    )
    (fp_text user "Author: Antmicro" (at -0.95 -4.169) (layer "B.Fab") hide
        (effects (font (size 0.7 0.7) (thickness 0.15)) (justify left bottom mirror))
    )
    (fp_rect (start -0.925 0.47) (end 0.925 -0.47)
      (stroke (width 0.05) (type default)) (fill none) (layer "B.CrtYd"))
    (fp_rect (start -0.5 0.25) (end 0.5 -0.25)
      (stroke (width 0.15) (type solid)) (fill none) (layer "B.Fab"))
    (pad "1" smd roundrect (at -0.48 0 180) (size 0.59 0.64) (layers "B.Cu" "B.Paste" "B.Mask") (roundrect_rratio 0.25)
      (net 398 "Net-(Q14-D)") (pintype "passive"))
    (pad "2" smd roundrect (at 0.48 0 180) (size 0.59 0.64) (layers "B.Cu" "B.Paste" "B.Mask") (roundrect_rratio 0.25)
      (net 345 "Net-(D11-A)") (pintype "passive"))
  )

  (footprint "antmicro-footprints:R_0402_1005Metric" (layer "B.Cu")
    (at 64.25 89.95 180)
    (descr "Resistor SMD 0402")
    (tags "resistor SMD 0402")
    (property "Author" "Antmicro")
    (property "License" "Apache-2.0")
    (property "MPN" "CR0402-FX-1001GLF")
    (property "Manufacturer" "Bourns")
    (property "Public" "False")
    (property "Sheetfile" "power-supply.kicad_sch")
    (property "Sheetname" "Power supply")
    (property "Tolerance" "1%")
    (property "Val" "1k")
    (property "ki_description" "SMD Chip Resistor, 1 kohm, ± 1%, 63 mW, 0402 [1005 Metric], Thick Film, General Purpose")
    (property "ki_keywords" "0402, SMT, RESISTOR, PASSIVE")
    (attr smd)
    (fp_text reference "R112" (at -1.67 -0.925 270) (layer "B.SilkS")
        (effects (font (size 0.7 0.7) (thickness 0.127)) (justify mirror))
    )
    (fp_text value "R_1k_0402" (at 0 -1.17 180) (layer "B.Fab")
        (effects (font (size 1 1) (thickness 0.15)) (justify mirror))
    )
    (fp_text user "License: Apache-2.0" (at -0.95 -5.169) (layer "B.Fab") hide
        (effects (font (size 0.7 0.7) (thickness 0.15)) (justify left bottom mirror))
    )
    (fp_text user "Author: Antmicro" (at -0.95 -4.169) (layer "B.Fab") hide
        (effects (font (size 0.7 0.7) (thickness 0.15)) (justify left bottom mirror))
    )
    (fp_text user "${REFERENCE}" (at 0 0 180) (layer "B.Fab")
        (effects (font (size 0.25 0.25) (thickness 0.04)) (justify mirror))
    )
    (fp_rect (start -0.925 0.47) (end 0.925 -0.47)
      (stroke (width 0.05) (type default)) (fill none) (layer "B.CrtYd"))
    (fp_rect (start -0.5 0.25) (end 0.5 -0.25)
      (stroke (width 0.15) (type solid)) (fill none) (layer "B.Fab"))
    (pad "1" smd roundrect (at -0.48 0 180) (size 0.59 0.64) (layers "B.Cu" "B.Paste" "B.Mask") (roundrect_rratio 0.25)
      (net 399 "Net-(Q15-D)") (pintype "passive"))
    (pad "2" smd roundrect (at 0.48 0 180) (size 0.59 0.64) (layers "B.Cu" "B.Paste" "B.Mask") (roundrect_rratio 0.25)
      (net 346 "Net-(D12-A)") (pintype "passive"))
  )

  (footprint "antmicro-footprints:R_0402_1005Metric" (layer "B.Cu")
    (at 64.25 88.35 180)
    (descr "Resistor SMD 0402")
    (tags "resistor SMD 0402")
    (property "Author" "Antmicro")
    (property "License" "Apache-2.0")
    (property "MPN" "CR0402-FX-1001GLF")
    (property "Manufacturer" "Bourns")
    (property "Public" "False")
    (property "Sheetfile" "power-supply.kicad_sch")
    (property "Sheetname" "Power supply")
    (property "Tolerance" "1%")
    (property "Val" "1k")
    (property "ki_description" "SMD Chip Resistor, 1 kohm, ± 1%, 63 mW, 0402 [1005 Metric], Thick Film, General Purpose")
    (property "ki_keywords" "0402, SMT, RESISTOR, PASSIVE")
    (attr smd)
    (fp_text reference "R113" (at -0.41 0.805 180) (layer "B.SilkS")
        (effects (font (size 0.7 0.7) (thickness 0.127)) (justify mirror))
    )
    (fp_text value "R_1k_0402" (at 0 -1.17 180) (layer "B.Fab")
        (effects (font (size 1 1) (thickness 0.15)) (justify mirror))
    )
    (fp_text user "Author: Antmicro" (at -0.95 -4.169) (layer "B.Fab") hide
        (effects (font (size 0.7 0.7) (thickness 0.15)) (justify left bottom mirror))
    )
    (fp_text user "${REFERENCE}" (at 0 0 180) (layer "B.Fab")
        (effects (font (size 0.25 0.25) (thickness 0.04)) (justify mirror))
    )
    (fp_text user "License: Apache-2.0" (at -0.95 -5.169) (layer "B.Fab") hide
        (effects (font (size 0.7 0.7) (thickness 0.15)) (justify left bottom mirror))
    )
    (fp_rect (start -0.925 0.47) (end 0.925 -0.47)
      (stroke (width 0.05) (type default)) (fill none) (layer "B.CrtYd"))
    (fp_rect (start -0.5 0.25) (end 0.5 -0.25)
      (stroke (width 0.15) (type solid)) (fill none) (layer "B.Fab"))
    (pad "1" smd roundrect (at -0.48 0 180) (size 0.59 0.64) (layers "B.Cu" "B.Paste" "B.Mask") (roundrect_rratio 0.25)
      (net 400 "Net-(Q16-D)") (pintype "passive"))
    (pad "2" smd roundrect (at 0.48 0 180) (size 0.59 0.64) (layers "B.Cu" "B.Paste" "B.Mask") (roundrect_rratio 0.25)
      (net 347 "Net-(D13-A)") (pintype "passive"))
  )

  (footprint "antmicro-footprints:R_0402_1005Metric" (layer "B.Cu")
    (at 74.2 87.55 180)
    (descr "Resistor SMD 0402")
    (tags "resistor SMD 0402")
    (property "Author" "Antmicro")
    (property "License" "Apache-2.0")
    (property "MPN" "CR0402-FX-1002GLF")
    (property "Manufacturer" "Bourns")
    (property "Public" "False")
    (property "Sheetfile" "power-supply.kicad_sch")
    (property "Sheetname" "Power supply")
    (property "Tolerance" "1%")
    (property "Val" "10k")
    (property "ki_description" "SMD Chip Resistor, 10 kohm, ± 1%, 62.5 mW, 0402 [1005 Metric], Thick Film, General Purpose")
    (property "ki_keywords" "0402, SMT, RESISTOR, PASSIVE")
    (attr smd)
    (fp_text reference "R106" (at -0.15 1.17 180) (layer "B.SilkS")
        (effects (font (size 0.7 0.7) (thickness 0.127)) (justify mirror))
    )
    (fp_text value "R_10k_0402" (at 0 -1.17 180) (layer "B.Fab")
        (effects (font (size 1 1) (thickness 0.15)) (justify mirror))
    )
    (fp_text user "${REFERENCE}" (at 0 0 180) (layer "B.Fab")
        (effects (font (size 0.25 0.25) (thickness 0.04)) (justify mirror))
    )
    (fp_text user "License: Apache-2.0" (at -0.95 -5.169) (layer "B.Fab") hide
        (effects (font (size 0.7 0.7) (thickness 0.15)) (justify left bottom mirror))
    )
    (fp_text user "Author: Antmicro" (at -0.95 -4.169) (layer "B.Fab") hide
        (effects (font (size 0.7 0.7) (thickness 0.15)) (justify left bottom mirror))
    )
    (fp_rect (start -0.925 0.47) (end 0.925 -0.47)
      (stroke (width 0.05) (type default)) (fill none) (layer "B.CrtYd"))
    (fp_rect (start -0.5 0.25) (end 0.5 -0.25)
      (stroke (width 0.15) (type solid)) (fill none) (layer "B.Fab"))
    (pad "1" smd roundrect (at -0.48 0 180) (size 0.59 0.64) (layers "B.Cu" "B.Paste" "B.Mask") (roundrect_rratio 0.25)
      (net 11 "VCC5V0") (pintype "passive"))
    (pad "2" smd roundrect (at 0.48 0 180) (size 0.59 0.64) (layers "B.Cu" "B.Paste" "B.Mask") (roundrect_rratio 0.25)
      (net 224 "/Power supply/1V35_PG") (pintype "passive"))
  )

  (footprint "antmicro-footprints:R_0402_1005Metric" (layer "B.Cu")
    (at 97.05 88 -90)
    (descr "Resistor SMD 0402")
    (tags "resistor SMD 0402")
    (property "Author" "Antmicro")
    (property "License" "Apache-2.0")
    (property "MPN" "CR0402-FX-1001GLF")
    (property "Manufacturer" "Bourns")
    (property "Public" "False")
    (property "Sheetfile" "ethernet.kicad_sch")
    (property "Sheetname" "Ethernet")
    (property "Tolerance" "1%")
    (property "Val" "1k")
    (property "ki_description" "SMD Chip Resistor, 1 kohm, ± 1%, 63 mW, 0402 [1005 Metric], Thick Film, General Purpose")
    (property "ki_keywords" "0402, SMT, RESISTOR, PASSIVE")
    (attr smd)
    (fp_text reference "R15" (at -2.03 -0.05 90) (layer "B.SilkS")
        (effects (font (size 0.7 0.7) (thickness 0.127)) (justify mirror))
    )
    (fp_text value "R_1k_0402" (at 0 -1.17 90) (layer "B.Fab")
        (effects (font (size 1 1) (thickness 0.15)) (justify mirror))
    )
    (fp_text user "${REFERENCE}" (at 0 0 90) (layer "B.Fab")
        (effects (font (size 0.25 0.25) (thickness 0.04)) (justify mirror))
    )
    (fp_text user "License: Apache-2.0" (at -0.95 -5.169 90) (layer "B.Fab") hide
        (effects (font (size 0.7 0.7) (thickness 0.15)) (justify left bottom mirror))
    )
    (fp_text user "Author: Antmicro" (at -0.95 -4.169 90) (layer "B.Fab") hide
        (effects (font (size 0.7 0.7) (thickness 0.15)) (justify left bottom mirror))
    )
    (fp_rect (start -0.925 0.47) (end 0.925 -0.47)
      (stroke (width 0.05) (type default)) (fill none) (layer "B.CrtYd"))
    (fp_rect (start -0.5 0.25) (end 0.5 -0.25)
      (stroke (width 0.15) (type solid)) (fill none) (layer "B.Fab"))
    (pad "1" smd roundrect (at -0.48 0 270) (size 0.59 0.64) (layers "B.Cu" "B.Paste" "B.Mask") (roundrect_rratio 0.25)
      (net 681 "Net-(J1-Pad15)") (pintype "passive"))
    (pad "2" smd roundrect (at 0.48 0 270) (size 0.59 0.64) (layers "B.Cu" "B.Paste" "B.Mask") (roundrect_rratio 0.25)
      (net 165 "/Ethernet/ETH_LED2") (pintype "passive"))
  )

  (footprint "antmicro-footprints:R_0402_1005Metric" (layer "B.Cu")
    (at 115.7 136.75 180)
    (descr "Resistor SMD 0402")
    (tags "resistor SMD 0402")
    (property "Author" "Antmicro")
    (property "Current" "1A")
    (property "License" "Apache-2.0")
    (property "MPN" "ERJ2GE0R00X")
    (property "Manufacturer" "Panasonic")
    (property "Public" "False")
    (property "Sheetfile" "edge-connector.kicad_sch")
    (property "Sheetname" "Edge connector")
    (property "Tolerance" "")
    (property "Val" "0R")
    (property "ki_description" "SMD Chip Resistor, Jumper, 0 ohm, 100 mW, 0402 [1005 Metric], Thick Film, General Purpose")
    (property "ki_keywords" "0402, SMT, RESISTOR, PASSIVE")
    (attr smd)
    (fp_text reference "R47" (at 0.02 -1.185 180) (layer "B.SilkS")
        (effects (font (size 0.7 0.7) (thickness 0.127)) (justify mirror))
    )
    (fp_text value "R_0R_0402" (at 0 -1.17 180) (layer "B.Fab")
        (effects (font (size 1 1) (thickness 0.15)) (justify mirror))
    )
    (fp_text user "Author: Antmicro" (at -0.95 -4.169) (layer "B.Fab") hide
        (effects (font (size 0.7 0.7) (thickness 0.15)) (justify left bottom mirror))
    )
    (fp_text user "License: Apache-2.0" (at -0.95 -5.169) (layer "B.Fab") hide
        (effects (font (size 0.7 0.7) (thickness 0.15)) (justify left bottom mirror))
    )
    (fp_text user "${REFERENCE}" (at 0 0 180) (layer "B.Fab")
        (effects (font (size 0.25 0.25) (thickness 0.04)) (justify mirror))
    )
    (fp_rect (start -0.925 0.47) (end 0.925 -0.47)
      (stroke (width 0.05) (type default)) (fill none) (layer "B.CrtYd"))
    (fp_rect (start -0.5 0.25) (end 0.5 -0.25)
      (stroke (width 0.15) (type solid)) (fill none) (layer "B.Fab"))
    (pad "1" smd roundrect (at -0.48 0 180) (size 0.59 0.64) (layers "B.Cu" "B.Paste" "B.Mask") (roundrect_rratio 0.25)
      (net 277 "SGPIO1_CLK") (pintype "passive"))
    (pad "2" smd roundrect (at 0.48 0 180) (size 0.59 0.64) (layers "B.Cu" "B.Paste" "B.Mask") (roundrect_rratio 0.25)
      (net 83 "SGPIO0_CLK") (pintype "passive"))
  )

  (footprint "antmicro-footprints:R_0402_1005Metric" (layer "B.Cu")
    (at 86.4 135.6 90)
    (descr "Resistor SMD 0402")
    (tags "resistor SMD 0402")
    (property "Author" "Antmicro")
    (property "Current" "1A")
    (property "DNP" "DNP")
    (property "License" "Apache-2.0")
    (property "MPN" "ERJ2GE0R00X")
    (property "Manufacturer" "Panasonic")
    (property "Public" "False")
    (property "Sheetfile" "fpga-banks.kicad_sch")
    (property "Sheetname" "FPGA banks")
    (property "Tolerance" "")
    (property "Val" "0R")
    (property "dnp" "")
    (property "exclude_from_bom" "")
    (property "ki_description" "SMD Chip Resistor, Jumper, 0 ohm, 100 mW, 0402 [1005 Metric], Thick Film, General Purpose")
    (property "ki_keywords" "0402, SMT, RESISTOR, PASSIVE")
    (attr smd exclude_from_pos_files exclude_from_bom)
    (fp_text reference "R132" (at -2.35 0.02 90) (layer "B.SilkS")
        (effects (font (size 0.7 0.7) (thickness 0.127)) (justify mirror))
    )
    (fp_text value "R_0R_0402" (at 0 -1.17 90) (layer "B.Fab")
        (effects (font (size 1 1) (thickness 0.15)) (justify mirror))
    )
    (fp_text user "License: Apache-2.0" (at -0.95 -5.169 270) (layer "B.Fab") hide
        (effects (font (size 0.7 0.7) (thickness 0.15)) (justify left bottom mirror))
    )
    (fp_text user "${REFERENCE}" (at 0 0 90) (layer "B.Fab")
        (effects (font (size 0.25 0.25) (thickness 0.04)) (justify mirror))
    )
    (fp_text user "Author: Antmicro" (at -0.95 -4.169 270) (layer "B.Fab") hide
        (effects (font (size 0.7 0.7) (thickness 0.15)) (justify left bottom mirror))
    )
    (fp_rect (start -0.925 0.47) (end 0.925 -0.47)
      (stroke (width 0.05) (type default)) (fill none) (layer "B.CrtYd"))
    (fp_rect (start -0.5 0.25) (end 0.5 -0.25)
      (stroke (width 0.15) (type solid)) (fill none) (layer "B.Fab"))
    (pad "1" smd roundrect (at -0.48 0 90) (size 0.59 0.64) (layers "B.Cu" "B.Paste" "B.Mask") (roundrect_rratio 0.25)
      (net 54 "SPI0_CLK") (pintype "passive"))
    (pad "2" smd roundrect (at 0.48 0 90) (size 0.59 0.64) (layers "B.Cu" "B.Paste" "B.Mask") (roundrect_rratio 0.25)
      (net 427 "Net-(U21I-PB4A)") (pintype "passive"))
  )

  (footprint "antmicro-footprints:C_0603_1608Metric" (layer "B.Cu")
    (at 88.7 98.6 90)
    (descr "Capacitor SMD 0603")
    (tags "capacitor 0603")
    (property "Author" "Antmicro")
    (property "Dielectric" "")
    (property "License" "Apache-2.0")
    (property "MPN" "GRM188R60J226MEA0D")
    (property "Manufacturer" "Murata")
    (property "Public" "False")
    (property "Sheetfile" "interfaces.kicad_sch")
    (property "Sheetname" "Interfaces")
    (property "Val" "22u")
    (property "Voltage" "")
    (property "ki_description" "SMD Multilayer Ceramic Capacitor, 22 µF, 6.3 V, 0603 [1608 Metric], ± 20%, X5R, GRM Series")
    (property "ki_keywords" "0603, SMT, CAPACITOR, PASSIVE, CERAMIC, MLCC")
    (attr smd)
    (fp_text reference "C49" (at -0.075 -1.06 90) (layer "B.SilkS")
        (effects (font (size 0.7 0.7) (thickness 0.127)) (justify mirror))
    )
    (fp_text value "C_22u_0603" (at 0 -1.9 90) (layer "B.Fab")
        (effects (font (size 1 1) (thickness 0.15)) (justify mirror))
    )
    (fp_text user "License: Apache-2.0" (at -1.682 -5.895 270) (layer "B.Fab") hide
        (effects (font (size 0.7 0.7) (thickness 0.15)) (justify left bottom mirror))
    )
    (fp_text user "${REFERENCE}" (at -1.682 -3.895 270) (layer "B.Fab") hide
        (effects (font (size 0.7 0.7) (thickness 0.15)) (justify left bottom mirror))
    )
    (fp_text user "Author: Antmicro" (at -1.682 -4.894 270) (layer "B.Fab") hide
        (effects (font (size 0.7 0.7) (thickness 0.15)) (justify left bottom mirror))
    )
    (fp_line (start -0.15 -0.4) (end 0.15 -0.4)
      (stroke (width 0.15) (type solid)) (layer "B.SilkS"))
    (fp_line (start -0.15 0.4) (end 0.15 0.4)
      (stroke (width 0.15) (type solid)) (layer "B.SilkS"))
    (fp_rect (start -1.25 0.65) (end 1.25 -0.65)
      (stroke (width 0.05) (type solid)) (fill none) (layer "B.CrtYd"))
    (fp_rect (start -0.8 0.4) (end 0.8 -0.4)
      (stroke (width 0.15) (type solid)) (fill none) (layer "B.Fab"))
    (pad "1" smd roundrect (at -0.7 0 90) (size 0.8 1) (layers "B.Cu" "B.Paste" "B.Mask") (roundrect_rratio 0.2)
      (net 1 "GND") (pintype "passive"))
    (pad "2" smd roundrect (at 0.7 0 90) (size 0.8 1) (layers "B.Cu" "B.Paste" "B.Mask") (roundrect_rratio 0.2)
      (net 2 "VCC3V3") (pintype "passive"))
  )

  (footprint "antmicro-footprints:R_0402_1005Metric" (layer "B.Cu")
    (at 88.7 95.7)
    (descr "Resistor SMD 0402")
    (tags "resistor SMD 0402")
    (property "Author" "Antmicro")
    (property "License" "Apache-2.0")
    (property "MPN" "CR0402-FX-4702GLF")
    (property "Manufacturer" "Bourns")
    (property "Public" "False")
    (property "Sheetfile" "interfaces.kicad_sch")
    (property "Sheetname" "Interfaces")
    (property "Tolerance" "1%")
    (property "Val" "47k")
    (property "ki_description" "SMD Chip Resistor, 47 kohm, ± 1%, 62.5 mW, 0402 [1005 Metric], Thick Film, General Purpose")
    (property "ki_keywords" "0402, SMT, RESISTOR, PASSIVE")
    (attr smd)
    (fp_text reference "R68" (at 0 -2.2) (layer "B.SilkS")
        (effects (font (size 0.7 0.7) (thickness 0.127)) (justify mirror))
    )
    (fp_text value "R_47k_0402" (at 0 -1.17) (layer "B.Fab")
        (effects (font (size 1 1) (thickness 0.15)) (justify mirror))
    )
    (fp_text user "Author: Antmicro" (at -0.95 -4.169 180) (layer "B.Fab") hide
        (effects (font (size 0.7 0.7) (thickness 0.15)) (justify left bottom mirror))
    )
    (fp_text user "License: Apache-2.0" (at -0.95 -5.169 180) (layer "B.Fab") hide
        (effects (font (size 0.7 0.7) (thickness 0.15)) (justify left bottom mirror))
    )
    (fp_text user "${REFERENCE}" (at 0 0) (layer "B.Fab")
        (effects (font (size 0.25 0.25) (thickness 0.04)) (justify mirror))
    )
    (fp_rect (start -0.925 0.47) (end 0.925 -0.47)
      (stroke (width 0.05) (type default)) (fill none) (layer "B.CrtYd"))
    (fp_rect (start -0.5 0.25) (end 0.5 -0.25)
      (stroke (width 0.15) (type solid)) (fill none) (layer "B.Fab"))
    (pad "1" smd roundrect (at -0.48 0) (size 0.59 0.64) (layers "B.Cu" "B.Paste" "B.Mask") (roundrect_rratio 0.25)
      (net 2 "VCC3V3") (pintype "passive"))
    (pad "2" smd roundrect (at 0.48 0) (size 0.59 0.64) (layers "B.Cu" "B.Paste" "B.Mask") (roundrect_rratio 0.25)
      (net 286 "MMC_DAT7") (pintype "passive"))
  )

  (footprint "antmicro-footprints:R_0402_1005Metric" (layer "B.Cu")
    (at 88.7 96.7)
    (descr "Resistor SMD 0402")
    (tags "resistor SMD 0402")
    (property "Author" "Antmicro")
    (property "License" "Apache-2.0")
    (property "MPN" "CR0402-FX-4702GLF")
    (property "Manufacturer" "Bourns")
    (property "Public" "False")
    (property "Sheetfile" "interfaces.kicad_sch")
    (property "Sheetname" "Interfaces")
    (property "Tolerance" "1%")
    (property "Val" "47k")
    (property "ki_description" "SMD Chip Resistor, 47 kohm, ± 1%, 62.5 mW, 0402 [1005 Metric], Thick Film, General Purpose")
    (property "ki_keywords" "0402, SMT, RESISTOR, PASSIVE")
    (attr smd)
    (fp_text reference "R66" (at 0 -2.3) (layer "B.SilkS")
        (effects (font (size 0.7 0.7) (thickness 0.127)) (justify mirror))
    )
    (fp_text value "R_47k_0402" (at 0 -1.17) (layer "B.Fab")
        (effects (font (size 1 1) (thickness 0.15)) (justify mirror))
    )
    (fp_text user "License: Apache-2.0" (at -0.95 -5.169 180) (layer "B.Fab") hide
        (effects (font (size 0.7 0.7) (thickness 0.15)) (justify left bottom mirror))
    )
    (fp_text user "Author: Antmicro" (at -0.95 -4.169 180) (layer "B.Fab") hide
        (effects (font (size 0.7 0.7) (thickness 0.15)) (justify left bottom mirror))
    )
    (fp_text user "${REFERENCE}" (at 0 0) (layer "B.Fab")
        (effects (font (size 0.25 0.25) (thickness 0.04)) (justify mirror))
    )
    (fp_rect (start -0.925 0.47) (end 0.925 -0.47)
      (stroke (width 0.05) (type default)) (fill none) (layer "B.CrtYd"))
    (fp_rect (start -0.5 0.25) (end 0.5 -0.25)
      (stroke (width 0.15) (type solid)) (fill none) (layer "B.Fab"))
    (pad "1" smd roundrect (at -0.48 0) (size 0.59 0.64) (layers "B.Cu" "B.Paste" "B.Mask") (roundrect_rratio 0.25)
      (net 2 "VCC3V3") (pintype "passive"))
    (pad "2" smd roundrect (at 0.48 0) (size 0.59 0.64) (layers "B.Cu" "B.Paste" "B.Mask") (roundrect_rratio 0.25)
      (net 284 "MMC_DAT5") (pintype "passive"))
  )

  (footprint "antmicro-footprints:R_0402_1005Metric" (layer "B.Cu")
    (at 94.55 100.6 180)
    (descr "Resistor SMD 0402")
    (tags "resistor SMD 0402")
    (property "Author" "Antmicro")
    (property "License" "Apache-2.0")
    (property "MPN" "CR0402-FX-4702GLF")
    (property "Manufacturer" "Bourns")
    (property "Public" "False")
    (property "Sheetfile" "interfaces.kicad_sch")
    (property "Sheetname" "Interfaces")
    (property "Tolerance" "1%")
    (property "Val" "47k")
    (property "ki_description" "SMD Chip Resistor, 47 kohm, ± 1%, 62.5 mW, 0402 [1005 Metric], Thick Film, General Purpose")
    (property "ki_keywords" "0402, SMT, RESISTOR, PASSIVE")
    (attr smd)
    (fp_text reference "R64" (at 0 -6.776) (layer "B.SilkS")
        (effects (font (size 0.7 0.7) (thickness 0.127)) (justify mirror))
    )
    (fp_text value "R_47k_0402" (at 0 -1.17) (layer "B.Fab")
        (effects (font (size 1 1) (thickness 0.15)) (justify mirror))
    )
    (fp_text user "${REFERENCE}" (at 0 0) (layer "B.Fab")
        (effects (font (size 0.25 0.25) (thickness 0.04)) (justify mirror))
    )
    (fp_text user "Author: Antmicro" (at -0.95 -4.169) (layer "B.Fab") hide
        (effects (font (size 0.7 0.7) (thickness 0.15)) (justify left bottom mirror))
    )
    (fp_text user "License: Apache-2.0" (at -0.95 -5.169) (layer "B.Fab") hide
        (effects (font (size 0.7 0.7) (thickness 0.15)) (justify left bottom mirror))
    )
    (fp_rect (start -0.925 0.47) (end 0.925 -0.47)
      (stroke (width 0.05) (type default)) (fill none) (layer "B.CrtYd"))
    (fp_rect (start -0.5 0.25) (end 0.5 -0.25)
      (stroke (width 0.15) (type solid)) (fill none) (layer "B.Fab"))
    (pad "1" smd roundrect (at -0.48 0 180) (size 0.59 0.64) (layers "B.Cu" "B.Paste" "B.Mask") (roundrect_rratio 0.25)
      (net 2 "VCC3V3") (pintype "passive"))
    (pad "2" smd roundrect (at 0.48 0 180) (size 0.59 0.64) (layers "B.Cu" "B.Paste" "B.Mask") (roundrect_rratio 0.25)
      (net 282 "MMC_DAT3") (pintype "passive"))
  )

  (footprint "antmicro-footprints:R_0402_1005Metric" (layer "B.Cu")
    (at 88.6 100.6)
    (descr "Resistor SMD 0402")
    (tags "resistor SMD 0402")
    (property "Author" "Antmicro")
    (property "License" "Apache-2.0")
    (property "MPN" "CR0402-FX-4702GLF")
    (property "Manufacturer" "Bourns")
    (property "Public" "False")
    (property "Sheetfile" "interfaces.kicad_sch")
    (property "Sheetname" "Interfaces")
    (property "Tolerance" "1%")
    (property "Val" "47k")
    (property "ki_description" "SMD Chip Resistor, 47 kohm, ± 1%, 62.5 mW, 0402 [1005 Metric], Thick Film, General Purpose")
    (property "ki_keywords" "0402, SMT, RESISTOR, PASSIVE")
    (attr smd)
    (fp_text reference "R63" (at 0.1 2.07) (layer "B.SilkS")
        (effects (font (size 0.7 0.7) (thickness 0.127)) (justify mirror))
    )
    (fp_text value "R_47k_0402" (at 0 -1.17) (layer "B.Fab")
        (effects (font (size 1 1) (thickness 0.15)) (justify mirror))
    )
    (fp_text user "${REFERENCE}" (at 0 0) (layer "B.Fab")
        (effects (font (size 0.25 0.25) (thickness 0.04)) (justify mirror))
    )
    (fp_text user "Author: Antmicro" (at -0.95 -4.169 180) (layer "B.Fab") hide
        (effects (font (size 0.7 0.7) (thickness 0.15)) (justify left bottom mirror))
    )
    (fp_text user "License: Apache-2.0" (at -0.95 -5.169 180) (layer "B.Fab") hide
        (effects (font (size 0.7 0.7) (thickness 0.15)) (justify left bottom mirror))
    )
    (fp_rect (start -0.925 0.47) (end 0.925 -0.47)
      (stroke (width 0.05) (type default)) (fill none) (layer "B.CrtYd"))
    (fp_rect (start -0.5 0.25) (end 0.5 -0.25)
      (stroke (width 0.15) (type solid)) (fill none) (layer "B.Fab"))
    (pad "1" smd roundrect (at -0.48 0) (size 0.59 0.64) (layers "B.Cu" "B.Paste" "B.Mask") (roundrect_rratio 0.25)
      (net 2 "VCC3V3") (pintype "passive"))
    (pad "2" smd roundrect (at 0.48 0) (size 0.59 0.64) (layers "B.Cu" "B.Paste" "B.Mask") (roundrect_rratio 0.25)
      (net 281 "MMC_DAT2") (pintype "passive"))
  )

  (footprint "antmicro-footprints:R_0402_1005Metric" (layer "B.Cu")
    (at 88.6 101.6)
    (descr "Resistor SMD 0402")
    (tags "resistor SMD 0402")
    (property "Author" "Antmicro")
    (property "License" "Apache-2.0")
    (property "MPN" "CR0402-FX-4702GLF")
    (property "Manufacturer" "Bourns")
    (property "Public" "False")
    (property "Sheetfile" "interfaces.kicad_sch")
    (property "Sheetname" "Interfaces")
    (property "Tolerance" "1%")
    (property "Val" "47k")
    (property "ki_description" "SMD Chip Resistor, 47 kohm, ± 1%, 62.5 mW, 0402 [1005 Metric], Thick Film, General Purpose")
    (property "ki_keywords" "0402, SMT, RESISTOR, PASSIVE")
    (attr smd)
    (fp_text reference "R61" (at 0.1 2.07) (layer "B.SilkS")
        (effects (font (size 0.7 0.7) (thickness 0.127)) (justify mirror))
    )
    (fp_text value "R_47k_0402" (at 0 -1.17) (layer "B.Fab")
        (effects (font (size 1 1) (thickness 0.15)) (justify mirror))
    )
    (fp_text user "Author: Antmicro" (at -0.95 -4.169 180) (layer "B.Fab") hide
        (effects (font (size 0.7 0.7) (thickness 0.15)) (justify left bottom mirror))
    )
    (fp_text user "${REFERENCE}" (at 0 0) (layer "B.Fab")
        (effects (font (size 0.25 0.25) (thickness 0.04)) (justify mirror))
    )
    (fp_text user "License: Apache-2.0" (at -0.95 -5.169 180) (layer "B.Fab") hide
        (effects (font (size 0.7 0.7) (thickness 0.15)) (justify left bottom mirror))
    )
    (fp_rect (start -0.925 0.47) (end 0.925 -0.47)
      (stroke (width 0.05) (type default)) (fill none) (layer "B.CrtYd"))
    (fp_rect (start -0.5 0.25) (end 0.5 -0.25)
      (stroke (width 0.15) (type solid)) (fill none) (layer "B.Fab"))
    (pad "1" smd roundrect (at -0.48 0) (size 0.59 0.64) (layers "B.Cu" "B.Paste" "B.Mask") (roundrect_rratio 0.25)
      (net 2 "VCC3V3") (pintype "passive"))
    (pad "2" smd roundrect (at 0.48 0) (size 0.59 0.64) (layers "B.Cu" "B.Paste" "B.Mask") (roundrect_rratio 0.25)
      (net 279 "MMC_DAT0") (pintype "passive"))
  )

  (footprint "antmicro-footprints:C_0603_1608Metric" (layer "B.Cu")
    (at 90.8 98.6 -90)
    (descr "Capacitor SMD 0603")
    (tags "capacitor 0603")
    (property "Author" "Antmicro")
    (property "Dielectric" "")
    (property "License" "Apache-2.0")
    (property "MPN" "GRM188R60J226MEA0D")
    (property "Manufacturer" "Murata")
    (property "Public" "False")
    (property "Sheetfile" "interfaces.kicad_sch")
    (property "Sheetname" "Interfaces")
    (property "Val" "22u")
    (property "Voltage" "")
    (property "ki_description" "SMD Multilayer Ceramic Capacitor, 22 µF, 6.3 V, 0603 [1608 Metric], ± 20%, X5R, GRM Series")
    (property "ki_keywords" "0603, SMT, CAPACITOR, PASSIVE, CERAMIC, MLCC")
    (attr smd)
    (fp_text reference "C50" (at -0.205 -1.1 90) (layer "B.SilkS")
        (effects (font (size 0.7 0.7) (thickness 0.127)) (justify mirror))
    )
    (fp_text value "C_22u_0603" (at 0 -1.9 90) (layer "B.Fab")
        (effects (font (size 1 1) (thickness 0.15)) (justify mirror))
    )
    (fp_text user "Author: Antmicro" (at -1.682 -4.894 90) (layer "B.Fab") hide
        (effects (font (size 0.7 0.7) (thickness 0.15)) (justify left bottom mirror))
    )
    (fp_text user "License: Apache-2.0" (at -1.682 -5.895 90) (layer "B.Fab") hide
        (effects (font (size 0.7 0.7) (thickness 0.15)) (justify left bottom mirror))
    )
    (fp_text user "${REFERENCE}" (at -1.682 -3.895 90) (layer "B.Fab") hide
        (effects (font (size 0.7 0.7) (thickness 0.15)) (justify left bottom mirror))
    )
    (fp_line (start -0.15 -0.4) (end 0.15 -0.4)
      (stroke (width 0.15) (type solid)) (layer "B.SilkS"))
    (fp_line (start -0.15 0.4) (end 0.15 0.4)
      (stroke (width 0.15) (type solid)) (layer "B.SilkS"))
    (fp_rect (start -1.25 0.65) (end 1.25 -0.65)
      (stroke (width 0.05) (type solid)) (fill none) (layer "B.CrtYd"))
    (fp_rect (start -0.8 0.4) (end 0.8 -0.4)
      (stroke (width 0.15) (type solid)) (fill none) (layer "B.Fab"))
    (pad "1" smd roundrect (at -0.7 0 270) (size 0.8 1) (layers "B.Cu" "B.Paste" "B.Mask") (roundrect_rratio 0.2)
      (net 1 "GND") (pintype "passive"))
    (pad "2" smd roundrect (at 0.7 0 270) (size 0.8 1) (layers "B.Cu" "B.Paste" "B.Mask") (roundrect_rratio 0.2)
      (net 2 "VCC3V3") (pintype "passive"))
  )

  (footprint "antmicro-footprints:C_0603_1608Metric" (layer "B.Cu")
    (at 85.9 102.8 180)
    (descr "Capacitor SMD 0603")
    (tags "capacitor 0603")
    (property "Author" "Antmicro")
    (property "Dielectric" "")
    (property "License" "Apache-2.0")
    (property "MPN" "GRM188R60J226MEA0D")
    (property "Manufacturer" "Murata")
    (property "Public" "False")
    (property "Sheetfile" "interfaces.kicad_sch")
    (property "Sheetname" "Interfaces")
    (property "Val" "22u")
    (property "Voltage" "")
    (property "ki_description" "SMD Multilayer Ceramic Capacitor, 22 µF, 6.3 V, 0603 [1608 Metric], ± 20%, X5R, GRM Series")
    (property "ki_keywords" "0603, SMT, CAPACITOR, PASSIVE, CERAMIC, MLCC")
    (attr smd)
    (fp_text reference "C48" (at 0.03 -1.185) (layer "B.SilkS")
        (effects (font (size 0.7 0.7) (thickness 0.127)) (justify mirror))
    )
    (fp_text value "C_22u_0603" (at 0 -1.9) (layer "B.Fab")
        (effects (font (size 1 1) (thickness 0.15)) (justify mirror))
    )
    (fp_text user "${REFERENCE}" (at -1.682 -3.895) (layer "B.Fab") hide
        (effects (font (size 0.7 0.7) (thickness 0.15)) (justify left bottom mirror))
    )
    (fp_text user "Author: Antmicro" (at -1.682 -4.894) (layer "B.Fab") hide
        (effects (font (size 0.7 0.7) (thickness 0.15)) (justify left bottom mirror))
    )
    (fp_text user "License: Apache-2.0" (at -1.682 -5.895) (layer "B.Fab") hide
        (effects (font (size 0.7 0.7) (thickness 0.15)) (justify left bottom mirror))
    )
    (fp_line (start -0.15 -0.4) (end 0.15 -0.4)
      (stroke (width 0.15) (type solid)) (layer "B.SilkS"))
    (fp_line (start -0.15 0.4) (end 0.15 0.4)
      (stroke (width 0.15) (type solid)) (layer "B.SilkS"))
    (fp_rect (start -1.25 0.65) (end 1.25 -0.65)
      (stroke (width 0.05) (type solid)) (fill none) (layer "B.CrtYd"))
    (fp_rect (start -0.8 0.4) (end 0.8 -0.4)
      (stroke (width 0.15) (type solid)) (fill none) (layer "B.Fab"))
    (pad "1" smd roundrect (at -0.7 0 180) (size 0.8 1) (layers "B.Cu" "B.Paste" "B.Mask") (roundrect_rratio 0.2)
      (net 1 "GND") (pintype "passive"))
    (pad "2" smd roundrect (at 0.7 0 180) (size 0.8 1) (layers "B.Cu" "B.Paste" "B.Mask") (roundrect_rratio 0.2)
      (net 2 "VCC3V3") (pintype "passive"))
  )

  (footprint "antmicro-footprints:C_0402_1005Metric" (layer "B.Cu")
    (at 85.8 95.6 180)
    (descr "Capacitor SMD 0402")
    (tags "capacitor SMD 0402")
    (property "Author" "Antmicro")
    (property "Dielectric" "X5R")
    (property "License" "Apache-2.0")
    (property "MPN" "GRM155R61H104KE14D")
    (property "Manufacturer" "Murata")
    (property "Public" "False")
    (property "Sheetfile" "interfaces.kicad_sch")
    (property "Sheetname" "Interfaces")
    (property "Val" "100n")
    (property "Voltage" "50V")
    (property "ki_description" "SMD Multilayer Ceramic Capacitor, 0.1 µF, 50 V, 0402 [1005 Metric], ± 10%, X5R, GRM Series")
    (property "ki_keywords" "0402, SMT, CAPACITOR, PASSIVE, CERAMIC, MLCC")
    (attr smd)
    (fp_text reference "C51" (at 0.4 9.42375) (layer "B.SilkS")
        (effects (font (size 0.7 0.7) (thickness 0.127)) (justify mirror))
    )
    (fp_text value "C_100n_0402" (at 0 -1.17) (layer "B.Fab")
        (effects (font (size 1 1) (thickness 0.15)) (justify mirror))
    )
    (fp_text user "Author: Antmicro" (at -0.939 -3.399) (layer "B.Fab") hide
        (effects (font (size 0.7 0.7) (thickness 0.15)) (justify left bottom mirror))
    )
    (fp_text user "${REFERENCE}" (at 0 0) (layer "B.Fab")
        (effects (font (size 0.25 0.25) (thickness 0.04)) (justify mirror))
    )
    (fp_text user "License: Apache-2.0" (at -0.939 -5.799) (layer "B.Fab") hide
        (effects (font (size 0.7 0.7) (thickness 0.15)) (justify left bottom mirror))
    )
    (fp_rect (start -0.925 0.47) (end 0.925 -0.47)
      (stroke (width 0.05) (type default)) (fill none) (layer "B.CrtYd"))
    (fp_line (start -0.494 -0.248) (end -0.494 0.25)
      (stroke (width 0.15) (type solid)) (layer "B.Fab"))
    (fp_line (start -0.494 0.25) (end 0.504 0.25)
      (stroke (width 0.15) (type solid)) (layer "B.Fab"))
    (fp_line (start 0.504 -0.248) (end -0.494 -0.248)
      (stroke (width 0.15) (type solid)) (layer "B.Fab"))
    (fp_line (start 0.504 0.25) (end 0.504 -0.248)
      (stroke (width 0.15) (type solid)) (layer "B.Fab"))
    (pad "1" smd roundrect (at -0.48 0 180) (size 0.59 0.64) (layers "B.Cu" "B.Paste" "B.Mask") (roundrect_rratio 0.25)
      (net 1 "GND") (pintype "passive"))
    (pad "2" smd roundrect (at 0.48 0 180) (size 0.59 0.64) (layers "B.Cu" "B.Paste" "B.Mask") (roundrect_rratio 0.25)
      (net 2 "VCC3V3") (pintype "passive"))
  )

  (footprint "antmicro-footprints:C_0402_1005Metric" (layer "B.Cu")
    (at 85.8 97.6 180)
    (descr "Capacitor SMD 0402")
    (tags "capacitor SMD 0402")
    (property "Author" "Antmicro")
    (property "Dielectric" "X5R")
    (property "License" "Apache-2.0")
    (property "MPN" "GRM155R61H104KE14D")
    (property "Manufacturer" "Murata")
    (property "Public" "False")
    (property "Sheetfile" "interfaces.kicad_sch")
    (property "Sheetname" "Interfaces")
    (property "Val" "100n")
    (property "Voltage" "50V")
    (property "ki_description" "SMD Multilayer Ceramic Capacitor, 0.1 µF, 50 V, 0402 [1005 Metric], ± 10%, X5R, GRM Series")
    (property "ki_keywords" "0402, SMT, CAPACITOR, PASSIVE, CERAMIC, MLCC")
    (attr smd)
    (fp_text reference "C52" (at 0.4 9.33125) (layer "B.SilkS")
        (effects (font (size 0.7 0.7) (thickness 0.127)) (justify mirror))
    )
    (fp_text value "C_100n_0402" (at 0 -1.17) (layer "B.Fab")
        (effects (font (size 1 1) (thickness 0.15)) (justify mirror))
    )
    (fp_text user "License: Apache-2.0" (at -0.939 -5.799) (layer "B.Fab") hide
        (effects (font (size 0.7 0.7) (thickness 0.15)) (justify left bottom mirror))
    )
    (fp_text user "${REFERENCE}" (at 0 0) (layer "B.Fab")
        (effects (font (size 0.25 0.25) (thickness 0.04)) (justify mirror))
    )
    (fp_text user "Author: Antmicro" (at -0.939 -3.399) (layer "B.Fab") hide
        (effects (font (size 0.7 0.7) (thickness 0.15)) (justify left bottom mirror))
    )
    (fp_rect (start -0.925 0.47) (end 0.925 -0.47)
      (stroke (width 0.05) (type default)) (fill none) (layer "B.CrtYd"))
    (fp_line (start -0.494 -0.248) (end -0.494 0.25)
      (stroke (width 0.15) (type solid)) (layer "B.Fab"))
    (fp_line (start -0.494 0.25) (end 0.504 0.25)
      (stroke (width 0.15) (type solid)) (layer "B.Fab"))
    (fp_line (start 0.504 -0.248) (end -0.494 -0.248)
      (stroke (width 0.15) (type solid)) (layer "B.Fab"))
    (fp_line (start 0.504 0.25) (end 0.504 -0.248)
      (stroke (width 0.15) (type solid)) (layer "B.Fab"))
    (pad "1" smd roundrect (at -0.48 0 180) (size 0.59 0.64) (layers "B.Cu" "B.Paste" "B.Mask") (roundrect_rratio 0.25)
      (net 1 "GND") (pintype "passive"))
    (pad "2" smd roundrect (at 0.48 0 180) (size 0.59 0.64) (layers "B.Cu" "B.Paste" "B.Mask") (roundrect_rratio 0.25)
      (net 2 "VCC3V3") (pintype "passive"))
  )

  (footprint "antmicro-footprints:C_0402_1005Metric" (layer "B.Cu")
    (at 83.31 100.22 90)
    (descr "Capacitor SMD 0402")
    (tags "capacitor SMD 0402")
    (property "Author" "Antmicro")
    (property "Dielectric" "")
    (property "License" "Apache-2.0")
    (property "MPN" "GRM155R61A475MEAAD")
    (property "Manufacturer" "Murata")
    (property "Public" "False")
    (property "Sheetfile" "interfaces.kicad_sch")
    (property "Sheetname" "Interfaces")
    (property "Val" "4u7")
    (property "Voltage" "")
    (property "ki_description" "SMD Multilayer Ceramic Capacitor, 4.7 µF, 10 V, 0402 [1005 Metric], ± 20%, X5R, GRM Series")
    (property "ki_keywords" "0402, SMT, CAPACITOR, PASSIVE")
    (attr smd)
    (fp_text reference "C53" (at 0 1.17 90) (layer "B.SilkS")
        (effects (font (size 0.7 0.7) (thickness 0.127)) (justify mirror))
    )
    (fp_text value "C_4u7_0402" (at 0 -1.17 90) (layer "B.Fab")
        (effects (font (size 1 1) (thickness 0.15)) (justify mirror))
    )
    (fp_text user "License: Apache-2.0" (at -0.939 -5.799 270) (layer "B.Fab") hide
        (effects (font (size 0.7 0.7) (thickness 0.15)) (justify left bottom mirror))
    )
    (fp_text user "${REFERENCE}" (at 0 0 90) (layer "B.Fab")
        (effects (font (size 0.25 0.25) (thickness 0.04)) (justify mirror))
    )
    (fp_text user "Author: Antmicro" (at -0.939 -3.399 270) (layer "B.Fab") hide
        (effects (font (size 0.7 0.7) (thickness 0.15)) (justify left bottom mirror))
    )
    (fp_rect (start -0.925 0.47) (end 0.925 -0.47)
      (stroke (width 0.05) (type default)) (fill none) (layer "B.CrtYd"))
    (fp_line (start -0.494 -0.248) (end -0.494 0.25)
      (stroke (width 0.15) (type solid)) (layer "B.Fab"))
    (fp_line (start -0.494 0.25) (end 0.504 0.25)
      (stroke (width 0.15) (type solid)) (layer "B.Fab"))
    (fp_line (start 0.504 -0.248) (end -0.494 -0.248)
      (stroke (width 0.15) (type solid)) (layer "B.Fab"))
    (fp_line (start 0.504 0.25) (end 0.504 -0.248)
      (stroke (width 0.15) (type solid)) (layer "B.Fab"))
    (pad "1" smd roundrect (at -0.48 0 90) (size 0.59 0.64) (layers "B.Cu" "B.Paste" "B.Mask") (roundrect_rratio 0.25)
      (net 1 "GND") (pintype "passive"))
    (pad "2" smd roundrect (at 0.48 0 90) (size 0.59 0.64) (layers "B.Cu" "B.Paste" "B.Mask") (roundrect_rratio 0.25)
      (net 219 "Net-(U6-VDDIM)") (pintype "passive"))
  )

  (footprint "antmicro-footprints:C_0402_1005Metric" (layer "B.Cu")
    (at 123.355 118.335 -90)
    (descr "Capacitor SMD 0402")
    (tags "capacitor SMD 0402")
    (property "Author" "Antmicro")
    (property "Dielectric" "X5R")
    (property "License" "Apache-2.0")
    (property "MPN" "GRM155R61H104KE14D")
    (property "Manufacturer" "Murata")
    (property "Public" "False")
    (property "Sheetfile" "interfaces.kicad_sch")
    (property "Sheetname" "Interfaces")
    (property "Val" "100n")
    (property "Voltage" "50V")
    (property "ki_description" "SMD Multilayer Ceramic Capacitor, 0.1 µF, 50 V, 0402 [1005 Metric], ± 10%, X5R, GRM Series")
    (property "ki_keywords" "0402, SMT, CAPACITOR, PASSIVE, CERAMIC, MLCC")
    (attr smd)
    (fp_text reference "C64" (at 1.93 -0.065 90) (layer "B.SilkS")
        (effects (font (size 0.7 0.7) (thickness 0.127)) (justify mirror))
    )
    (fp_text value "C_100n_0402" (at 0 -1.17 90) (layer "B.Fab")
        (effects (font (size 1 1) (thickness 0.15)) (justify mirror))
    )
    (fp_text user "License: Apache-2.0" (at -0.939 -5.799 90) (layer "B.Fab") hide
        (effects (font (size 0.7 0.7) (thickness 0.15)) (justify left bottom mirror))
    )
    (fp_text user "${REFERENCE}" (at 0 0 90) (layer "B.Fab")
        (effects (font (size 0.25 0.25) (thickness 0.04)) (justify mirror))
    )
    (fp_text user "Author: Antmicro" (at -0.939 -3.399 90) (layer "B.Fab") hide
        (effects (font (size 0.7 0.7) (thickness 0.15)) (justify left bottom mirror))
    )
    (fp_rect (start -0.925 0.47) (end 0.925 -0.47)
      (stroke (width 0.05) (type default)) (fill none) (layer "B.CrtYd"))
    (fp_line (start -0.494 -0.248) (end -0.494 0.25)
      (stroke (width 0.15) (type solid)) (layer "B.Fab"))
    (fp_line (start -0.494 0.25) (end 0.504 0.25)
      (stroke (width 0.15) (type solid)) (layer "B.Fab"))
    (fp_line (start 0.504 -0.248) (end -0.494 -0.248)
      (stroke (width 0.15) (type solid)) (layer "B.Fab"))
    (fp_line (start 0.504 0.25) (end 0.504 -0.248)
      (stroke (width 0.15) (type solid)) (layer "B.Fab"))
    (pad "1" smd roundrect (at -0.48 0 270) (size 0.59 0.64) (layers "B.Cu" "B.Paste" "B.Mask") (roundrect_rratio 0.25)
      (net 2 "VCC3V3") (pintype "passive"))
    (pad "2" smd roundrect (at 0.48 0 270) (size 0.59 0.64) (layers "B.Cu" "B.Paste" "B.Mask") (roundrect_rratio 0.25)
      (net 1 "GND") (pintype "passive"))
  )

  (footprint "antmicro-footprints:C_0402_1005Metric" (layer "B.Cu")
    (at 128.625 118.55)
    (descr "Capacitor SMD 0402")
    (tags "capacitor SMD 0402")
    (property "Author" "Antmicro")
    (property "Dielectric" "X5R")
    (property "License" "Apache-2.0")
    (property "MPN" "GRM155R61H104KE14D")
    (property "Manufacturer" "Murata")
    (property "Public" "False")
    (property "Sheetfile" "interfaces.kicad_sch")
    (property "Sheetname" "Interfaces")
    (property "Val" "100n")
    (property "Voltage" "50V")
    (property "ki_description" "SMD Multilayer Ceramic Capacitor, 0.1 µF, 50 V, 0402 [1005 Metric], ± 10%, X5R, GRM Series")
    (property "ki_keywords" "0402, SMT, CAPACITOR, PASSIVE, CERAMIC, MLCC")
    (attr smd)
    (fp_text reference "C67" (at -3.025 -0.025) (layer "B.SilkS")
        (effects (font (size 0.7 0.7) (thickness 0.127)) (justify mirror))
    )
    (fp_text value "C_100n_0402" (at 0 -1.17) (layer "B.Fab")
        (effects (font (size 1 1) (thickness 0.15)) (justify mirror))
    )
    (fp_text user "Author: Antmicro" (at -0.939 -3.399 180) (layer "B.Fab") hide
        (effects (font (size 0.7 0.7) (thickness 0.15)) (justify left bottom mirror))
    )
    (fp_text user "License: Apache-2.0" (at -0.939 -5.799 180) (layer "B.Fab") hide
        (effects (font (size 0.7 0.7) (thickness 0.15)) (justify left bottom mirror))
    )
    (fp_text user "${REFERENCE}" (at 0 0) (layer "B.Fab")
        (effects (font (size 0.25 0.25) (thickness 0.04)) (justify mirror))
    )
    (fp_rect (start -0.925 0.47) (end 0.925 -0.47)
      (stroke (width 0.05) (type default)) (fill none) (layer "B.CrtYd"))
    (fp_line (start -0.494 -0.248) (end -0.494 0.25)
      (stroke (width 0.15) (type solid)) (layer "B.Fab"))
    (fp_line (start -0.494 0.25) (end 0.504 0.25)
      (stroke (width 0.15) (type solid)) (layer "B.Fab"))
    (fp_line (start 0.504 -0.248) (end -0.494 -0.248)
      (stroke (width 0.15) (type solid)) (layer "B.Fab"))
    (fp_line (start 0.504 0.25) (end 0.504 -0.248)
      (stroke (width 0.15) (type solid)) (layer "B.Fab"))
    (pad "1" smd roundrect (at -0.48 0) (size 0.59 0.64) (layers "B.Cu" "B.Paste" "B.Mask") (roundrect_rratio 0.25)
      (net 2 "VCC3V3") (pintype "passive"))
    (pad "2" smd roundrect (at 0.48 0) (size 0.59 0.64) (layers "B.Cu" "B.Paste" "B.Mask") (roundrect_rratio 0.25)
      (net 1 "GND") (pintype "passive"))
  )

  (footprint "antmicro-footprints:C_0402_1005Metric" (layer "B.Cu")
    (at 122.35 118.335 90)
    (descr "Capacitor SMD 0402")
    (tags "capacitor SMD 0402")
    (property "Author" "Antmicro")
    (property "Dielectric" "")
    (property "License" "Apache-2.0")
    (property "MPN" "GRM155R61A475MEAAD")
    (property "Manufacturer" "Murata")
    (property "Public" "False")
    (property "Sheetfile" "interfaces.kicad_sch")
    (property "Sheetname" "Interfaces")
    (property "Val" "4u7")
    (property "Voltage" "")
    (property "ki_description" "SMD Multilayer Ceramic Capacitor, 4.7 µF, 10 V, 0402 [1005 Metric], ± 20%, X5R, GRM Series")
    (property "ki_keywords" "0402, SMT, CAPACITOR, PASSIVE")
    (attr smd)
    (fp_text reference "C72" (at -1.92 0 90) (layer "B.SilkS")
        (effects (font (size 0.7 0.7) (thickness 0.127)) (justify mirror))
    )
    (fp_text value "C_4u7_0402" (at 0 -1.17 90) (layer "B.Fab")
        (effects (font (size 1 1) (thickness 0.15)) (justify mirror))
    )
    (fp_text user "Author: Antmicro" (at -0.939 -3.399 270) (layer "B.Fab") hide
        (effects (font (size 0.7 0.7) (thickness 0.15)) (justify left bottom mirror))
    )
    (fp_text user "${REFERENCE}" (at 0 0 90) (layer "B.Fab")
        (effects (font (size 0.25 0.25) (thickness 0.04)) (justify mirror))
    )
    (fp_text user "License: Apache-2.0" (at -0.939 -5.799 270) (layer "B.Fab") hide
        (effects (font (size 0.7 0.7) (thickness 0.15)) (justify left bottom mirror))
    )
    (fp_rect (start -0.925 0.47) (end 0.925 -0.47)
      (stroke (width 0.05) (type default)) (fill none) (layer "B.CrtYd"))
    (fp_line (start -0.494 -0.248) (end -0.494 0.25)
      (stroke (width 0.15) (type solid)) (layer "B.Fab"))
    (fp_line (start -0.494 0.25) (end 0.504 0.25)
      (stroke (width 0.15) (type solid)) (layer "B.Fab"))
    (fp_line (start 0.504 -0.248) (end -0.494 -0.248)
      (stroke (width 0.15) (type solid)) (layer "B.Fab"))
    (fp_line (start 0.504 0.25) (end 0.504 -0.248)
      (stroke (width 0.15) (type solid)) (layer "B.Fab"))
    (pad "1" smd roundrect (at -0.48 0 90) (size 0.59 0.64) (layers "B.Cu" "B.Paste" "B.Mask") (roundrect_rratio 0.25)
      (net 1 "GND") (pintype "passive"))
    (pad "2" smd roundrect (at 0.48 0 90) (size 0.59 0.64) (layers "B.Cu" "B.Paste" "B.Mask") (roundrect_rratio 0.25)
      (net 2 "VCC3V3") (pintype "passive"))
  )

  (footprint "antmicro-footprints:C_0402_1005Metric" (layer "B.Cu")
    (at 78 124.7 90)
    (descr "Capacitor SMD 0402")
    (tags "capacitor SMD 0402")
    (property "Author" "Antmicro")
    (property "Dielectric" "")
    (property "License" "Apache-2.0")
    (property "MPN" "GRM155R61A475MEAAD")
    (property "Manufacturer" "Murata")
    (property "Public" "False")
    (property "Sheetfile" "ddr3.kicad_sch")
    (property "Sheetname" "DDR3")
    (property "Val" "4u7")
    (property "Voltage" "")
    (property "ki_description" "SMD Multilayer Ceramic Capacitor, 4.7 µF, 10 V, 0402 [1005 Metric], ± 20%, X5R, GRM Series")
    (property "ki_keywords" "0402, SMT, CAPACITOR, PASSIVE")
    (attr smd)
    (fp_text reference "C79" (at 0.005 -2.5 90) (layer "B.SilkS")
        (effects (font (size 0.7 0.7) (thickness 0.127)) (justify mirror))
    )
    (fp_text value "C_4u7_0402" (at 0 -1.17 90) (layer "B.Fab")
        (effects (font (size 1 1) (thickness 0.15)) (justify mirror))
    )
    (fp_text user "${REFERENCE}" (at 0 0 90) (layer "B.Fab")
        (effects (font (size 0.25 0.25) (thickness 0.04)) (justify mirror))
    )
    (fp_text user "Author: Antmicro" (at -0.939 -3.399 270) (layer "B.Fab") hide
        (effects (font (size 0.7 0.7) (thickness 0.15)) (justify left bottom mirror))
    )
    (fp_text user "License: Apache-2.0" (at -0.939 -5.799 270) (layer "B.Fab") hide
        (effects (font (size 0.7 0.7) (thickness 0.15)) (justify left bottom mirror))
    )
    (fp_rect (start -0.925 0.47) (end 0.925 -0.47)
      (stroke (width 0.05) (type default)) (fill none) (layer "B.CrtYd"))
    (fp_line (start -0.494 -0.248) (end -0.494 0.25)
      (stroke (width 0.15) (type solid)) (layer "B.Fab"))
    (fp_line (start -0.494 0.25) (end 0.504 0.25)
      (stroke (width 0.15) (type solid)) (layer "B.Fab"))
    (fp_line (start 0.504 -0.248) (end -0.494 -0.248)
      (stroke (width 0.15) (type solid)) (layer "B.Fab"))
    (fp_line (start 0.504 0.25) (end 0.504 -0.248)
      (stroke (width 0.15) (type solid)) (layer "B.Fab"))
    (pad "1" smd roundrect (at -0.48 0 90) (size 0.59 0.64) (layers "B.Cu" "B.Paste" "B.Mask") (roundrect_rratio 0.25)
      (net 1 "GND") (pintype "passive"))
    (pad "2" smd roundrect (at 0.48 0 90) (size 0.59 0.64) (layers "B.Cu" "B.Paste" "B.Mask") (roundrect_rratio 0.25)
      (net 3 "VCC1V35") (pintype "passive"))
  )

  (footprint "antmicro-footprints:C_0402_1005Metric" (layer "B.Cu")
    (at 85.9 129.75)
    (descr "Capacitor SMD 0402")
    (tags "capacitor SMD 0402")
    (property "Author" "Antmicro")
    (property "Dielectric" "")
    (property "License" "Apache-2.0")
    (property "MPN" "C1005X5R1E474M050BB")
    (property "Manufacturer" "TDK")
    (property "Public" "False")
    (property "Sheetfile" "ddr3.kicad_sch")
    (property "Sheetname" "DDR3")
    (property "Val" "470n")
    (property "Voltage" "")
    (property "ki_description" "SMD Multilayer Ceramic Capacitor, 0.47 µF, 25 V, 0402 [1005 Metric], ± 20%, X5R, C")
    (property "ki_keywords" "0402, SMT, CAPACITOR, PASSIVE, CERAMIC, MLCC")
    (attr smd)
    (fp_text reference "C80" (at -0.03 1.425) (layer "B.SilkS")
        (effects (font (size 0.7 0.7) (thickness 0.127)) (justify mirror))
    )
    (fp_text value "C_470n_0402" (at 0 -1.17) (layer "B.Fab")
        (effects (font (size 1 1) (thickness 0.15)) (justify mirror))
    )
    (fp_text user "License: Apache-2.0" (at -0.939 -5.799 180) (layer "B.Fab") hide
        (effects (font (size 0.7 0.7) (thickness 0.15)) (justify left bottom mirror))
    )
    (fp_text user "${REFERENCE}" (at 0 0) (layer "B.Fab")
        (effects (font (size 0.25 0.25) (thickness 0.04)) (justify mirror))
    )
    (fp_text user "Author: Antmicro" (at -0.939 -3.399 180) (layer "B.Fab") hide
        (effects (font (size 0.7 0.7) (thickness 0.15)) (justify left bottom mirror))
    )
    (fp_rect (start -0.925 0.47) (end 0.925 -0.47)
      (stroke (width 0.05) (type default)) (fill none) (layer "B.CrtYd"))
    (fp_line (start -0.494 -0.248) (end -0.494 0.25)
      (stroke (width 0.15) (type solid)) (layer "B.Fab"))
    (fp_line (start -0.494 0.25) (end 0.504 0.25)
      (stroke (width 0.15) (type solid)) (layer "B.Fab"))
    (fp_line (start 0.504 -0.248) (end -0.494 -0.248)
      (stroke (width 0.15) (type solid)) (layer "B.Fab"))
    (fp_line (start 0.504 0.25) (end 0.504 -0.248)
      (stroke (width 0.15) (type solid)) (layer "B.Fab"))
    (pad "1" smd roundrect (at -0.48 0) (size 0.59 0.64) (layers "B.Cu" "B.Paste" "B.Mask") (roundrect_rratio 0.25)
      (net 1 "GND") (pintype "passive"))
    (pad "2" smd roundrect (at 0.48 0) (size 0.59 0.64) (layers "B.Cu" "B.Paste" "B.Mask") (roundrect_rratio 0.25)
      (net 3 "VCC1V35") (pintype "passive"))
  )

  (footprint "antmicro-footprints:C_0402_1005Metric" (layer "B.Cu")
    (at 79.05 126.75 -90)
    (descr "Capacitor SMD 0402")
    (tags "capacitor SMD 0402")
    (property "Author" "Antmicro")
    (property "Dielectric" "")
    (property "License" "Apache-2.0")
    (property "MPN" "C1005X5R1E474M050BB")
    (property "Manufacturer" "TDK")
    (property "Public" "False")
    (property "Sheetfile" "ddr3.kicad_sch")
    (property "Sheetname" "DDR3")
    (property "Val" "470n")
    (property "Voltage" "")
    (property "ki_description" "SMD Multilayer Ceramic Capacitor, 0.47 µF, 25 V, 0402 [1005 Metric], ± 20%, X5R, C")
    (property "ki_keywords" "0402, SMT, CAPACITOR, PASSIVE, CERAMIC, MLCC")
    (attr smd)
    (fp_text reference "C81" (at 0.445 0.83 90) (layer "B.SilkS")
        (effects (font (size 0.7 0.7) (thickness 0.127)) (justify mirror))
    )
    (fp_text value "C_470n_0402" (at 0 -1.17 90) (layer "B.Fab")
        (effects (font (size 1 1) (thickness 0.15)) (justify mirror))
    )
    (fp_text user "${REFERENCE}" (at 0 0 90) (layer "B.Fab")
        (effects (font (size 0.25 0.25) (thickness 0.04)) (justify mirror))
    )
    (fp_text user "Author: Antmicro" (at -0.939 -3.399 90) (layer "B.Fab") hide
        (effects (font (size 0.7 0.7) (thickness 0.15)) (justify left bottom mirror))
    )
    (fp_text user "License: Apache-2.0" (at -0.939 -5.799 90) (layer "B.Fab") hide
        (effects (font (size 0.7 0.7) (thickness 0.15)) (justify left bottom mirror))
    )
    (fp_rect (start -0.925 0.47) (end 0.925 -0.47)
      (stroke (width 0.05) (type default)) (fill none) (layer "B.CrtYd"))
    (fp_line (start -0.494 -0.248) (end -0.494 0.25)
      (stroke (width 0.15) (type solid)) (layer "B.Fab"))
    (fp_line (start -0.494 0.25) (end 0.504 0.25)
      (stroke (width 0.15) (type solid)) (layer "B.Fab"))
    (fp_line (start 0.504 -0.248) (end -0.494 -0.248)
      (stroke (width 0.15) (type solid)) (layer "B.Fab"))
    (fp_line (start 0.504 0.25) (end 0.504 -0.248)
      (stroke (width 0.15) (type solid)) (layer "B.Fab"))
    (pad "1" smd roundrect (at -0.48 0 270) (size 0.59 0.64) (layers "B.Cu" "B.Paste" "B.Mask") (roundrect_rratio 0.25)
      (net 1 "GND") (pintype "passive"))
    (pad "2" smd roundrect (at 0.48 0 270) (size 0.59 0.64) (layers "B.Cu" "B.Paste" "B.Mask") (roundrect_rratio 0.25)
      (net 3 "VCC1V35") (pintype "passive"))
  )

  (footprint "antmicro-footprints:C_0402_1005Metric" (layer "B.Cu")
    (at 79.04 128.72 90)
    (descr "Capacitor SMD 0402")
    (tags "capacitor SMD 0402")
    (property "Author" "Antmicro")
    (property "Dielectric" "")
    (property "License" "Apache-2.0")
    (property "MPN" "C1005X5R1E474M050BB")
    (property "Manufacturer" "TDK")
    (property "Public" "False")
    (property "Sheetfile" "ddr3.kicad_sch")
    (property "Sheetname" "DDR3")
    (property "Val" "470n")
    (property "Voltage" "")
    (property "ki_description" "SMD Multilayer Ceramic Capacitor, 0.47 µF, 25 V, 0402 [1005 Metric], ± 20%, X5R, C")
    (property "ki_keywords" "0402, SMT, CAPACITOR, PASSIVE, CERAMIC, MLCC")
    (attr smd)
    (fp_text reference "C82" (at -0.745 -0.89 90) (layer "B.SilkS")
        (effects (font (size 0.7 0.7) (thickness 0.127)) (justify mirror))
    )
    (fp_text value "C_470n_0402" (at 0 -1.17 90) (layer "B.Fab")
        (effects (font (size 1 1) (thickness 0.15)) (justify mirror))
    )
    (fp_text user "Author: Antmicro" (at -0.939 -3.399 270) (layer "B.Fab") hide
        (effects (font (size 0.7 0.7) (thickness 0.15)) (justify left bottom mirror))
    )
    (fp_text user "License: Apache-2.0" (at -0.939 -5.799 270) (layer "B.Fab") hide
        (effects (font (size 0.7 0.7) (thickness 0.15)) (justify left bottom mirror))
    )
    (fp_text user "${REFERENCE}" (at 0 0 90) (layer "B.Fab")
        (effects (font (size 0.25 0.25) (thickness 0.04)) (justify mirror))
    )
    (fp_rect (start -0.925 0.47) (end 0.925 -0.47)
      (stroke (width 0.05) (type default)) (fill none) (layer "B.CrtYd"))
    (fp_line (start -0.494 -0.248) (end -0.494 0.25)
      (stroke (width 0.15) (type solid)) (layer "B.Fab"))
    (fp_line (start -0.494 0.25) (end 0.504 0.25)
      (stroke (width 0.15) (type solid)) (layer "B.Fab"))
    (fp_line (start 0.504 -0.248) (end -0.494 -0.248)
      (stroke (width 0.15) (type solid)) (layer "B.Fab"))
    (fp_line (start 0.504 0.25) (end 0.504 -0.248)
      (stroke (width 0.15) (type solid)) (layer "B.Fab"))
    (pad "1" smd roundrect (at -0.48 0 90) (size 0.59 0.64) (layers "B.Cu" "B.Paste" "B.Mask") (roundrect_rratio 0.25)
      (net 1 "GND") (pintype "passive"))
    (pad "2" smd roundrect (at 0.48 0 90) (size 0.59 0.64) (layers "B.Cu" "B.Paste" "B.Mask") (roundrect_rratio 0.25)
      (net 3 "VCC1V35") (pintype "passive"))
  )

  (footprint "antmicro-footprints:C_0402_1005Metric" (layer "B.Cu")
    (at 85.9 128.25)
    (descr "Capacitor SMD 0402")
    (tags "capacitor SMD 0402")
    (property "Author" "Antmicro")
    (property "Dielectric" "")
    (property "License" "Apache-2.0")
    (property "MPN" "C1005X5R1E474M050BB")
    (property "Manufacturer" "TDK")
    (property "Public" "False")
    (property "Sheetfile" "ddr3.kicad_sch")
    (property "Sheetname" "DDR3")
    (property "Val" "470n")
    (property "Voltage" "")
    (property "ki_description" "SMD Multilayer Ceramic Capacitor, 0.47 µF, 25 V, 0402 [1005 Metric], ± 20%, X5R, C")
    (property "ki_keywords" "0402, SMT, CAPACITOR, PASSIVE, CERAMIC, MLCC")
    (attr smd)
    (fp_text reference "C83" (at 2.43 -0.045) (layer "B.SilkS")
        (effects (font (size 0.7 0.7) (thickness 0.127)) (justify mirror))
    )
    (fp_text value "C_470n_0402" (at 0 -1.17) (layer "B.Fab")
        (effects (font (size 1 1) (thickness 0.15)) (justify mirror))
    )
    (fp_text user "Author: Antmicro" (at -0.939 -3.399 180) (layer "B.Fab") hide
        (effects (font (size 0.7 0.7) (thickness 0.15)) (justify left bottom mirror))
    )
    (fp_text user "${REFERENCE}" (at 0 0) (layer "B.Fab")
        (effects (font (size 0.25 0.25) (thickness 0.04)) (justify mirror))
    )
    (fp_text user "License: Apache-2.0" (at -0.939 -5.799 180) (layer "B.Fab") hide
        (effects (font (size 0.7 0.7) (thickness 0.15)) (justify left bottom mirror))
    )
    (fp_rect (start -0.925 0.47) (end 0.925 -0.47)
      (stroke (width 0.05) (type default)) (fill none) (layer "B.CrtYd"))
    (fp_line (start -0.494 -0.248) (end -0.494 0.25)
      (stroke (width 0.15) (type solid)) (layer "B.Fab"))
    (fp_line (start -0.494 0.25) (end 0.504 0.25)
      (stroke (width 0.15) (type solid)) (layer "B.Fab"))
    (fp_line (start 0.504 -0.248) (end -0.494 -0.248)
      (stroke (width 0.15) (type solid)) (layer "B.Fab"))
    (fp_line (start 0.504 0.25) (end 0.504 -0.248)
      (stroke (width 0.15) (type solid)) (layer "B.Fab"))
    (pad "1" smd roundrect (at -0.48 0) (size 0.59 0.64) (layers "B.Cu" "B.Paste" "B.Mask") (roundrect_rratio 0.25)
      (net 1 "GND") (pintype "passive"))
    (pad "2" smd roundrect (at 0.48 0) (size 0.59 0.64) (layers "B.Cu" "B.Paste" "B.Mask") (roundrect_rratio 0.25)
      (net 3 "VCC1V35") (pintype "passive"))
  )

  (footprint "antmicro-footprints:C_0402_1005Metric" (layer "B.Cu")
    (at 87.85 127.25)
    (descr "Capacitor SMD 0402")
    (tags "capacitor SMD 0402")
    (property "Author" "Antmicro")
    (property "Dielectric" "")
    (property "License" "Apache-2.0")
    (property "MPN" "C1005X5R1E474M050BB")
    (property "Manufacturer" "TDK")
    (property "Public" "False")
    (property "Sheetfile" "ddr3.kicad_sch")
    (property "Sheetname" "DDR3")
    (property "Val" "470n")
    (property "Voltage" "")
    (property "ki_description" "SMD Multilayer Ceramic Capacitor, 0.47 µF, 25 V, 0402 [1005 Metric], ± 20%, X5R, C")
    (property "ki_keywords" "0402, SMT, CAPACITOR, PASSIVE, CERAMIC, MLCC")
    (attr smd)
    (fp_text reference "C84" (at 1.98 -0.025) (layer "B.SilkS")
        (effects (font (size 0.7 0.7) (thickness 0.127)) (justify mirror))
    )
    (fp_text value "C_470n_0402" (at 0 -1.17) (layer "B.Fab")
        (effects (font (size 1 1) (thickness 0.15)) (justify mirror))
    )
    (fp_text user "${REFERENCE}" (at 0 0) (layer "B.Fab")
        (effects (font (size 0.25 0.25) (thickness 0.04)) (justify mirror))
    )
    (fp_text user "Author: Antmicro" (at -0.939 -3.399 180) (layer "B.Fab") hide
        (effects (font (size 0.7 0.7) (thickness 0.15)) (justify left bottom mirror))
    )
    (fp_text user "License: Apache-2.0" (at -0.939 -5.799 180) (layer "B.Fab") hide
        (effects (font (size 0.7 0.7) (thickness 0.15)) (justify left bottom mirror))
    )
    (fp_rect (start -0.925 0.47) (end 0.925 -0.47)
      (stroke (width 0.05) (type default)) (fill none) (layer "B.CrtYd"))
    (fp_line (start -0.494 -0.248) (end -0.494 0.25)
      (stroke (width 0.15) (type solid)) (layer "B.Fab"))
    (fp_line (start -0.494 0.25) (end 0.504 0.25)
      (stroke (width 0.15) (type solid)) (layer "B.Fab"))
    (fp_line (start 0.504 -0.248) (end -0.494 -0.248)
      (stroke (width 0.15) (type solid)) (layer "B.Fab"))
    (fp_line (start 0.504 0.25) (end 0.504 -0.248)
      (stroke (width 0.15) (type solid)) (layer "B.Fab"))
    (pad "1" smd roundrect (at -0.48 0) (size 0.59 0.64) (layers "B.Cu" "B.Paste" "B.Mask") (roundrect_rratio 0.25)
      (net 1 "GND") (pintype "passive"))
    (pad "2" smd roundrect (at 0.48 0) (size 0.59 0.64) (layers "B.Cu" "B.Paste" "B.Mask") (roundrect_rratio 0.25)
      (net 3 "VCC1V35") (pintype "passive"))
  )

  (footprint "antmicro-footprints:C_0402_1005Metric" (layer "B.Cu")
    (at 84.8 121.4 -90)
    (descr "Capacitor SMD 0402")
    (tags "capacitor SMD 0402")
    (property "Author" "Antmicro")
    (property "Dielectric" "")
    (property "License" "Apache-2.0")
    (property "MPN" "C1005X5R1E474M050BB")
    (property "Manufacturer" "TDK")
    (property "Public" "False")
    (property "Sheetfile" "ddr3.kicad_sch")
    (property "Sheetname" "DDR3")
    (property "Val" "470n")
    (property "Voltage" "")
    (property "ki_description" "SMD Multilayer Ceramic Capacitor, 0.47 µF, 25 V, 0402 [1005 Metric], ± 20%, X5R, C")
    (property "ki_keywords" "0402, SMT, CAPACITOR, PASSIVE, CERAMIC, MLCC")
    (attr smd)
    (fp_text reference "C85" (at -1.225 -0.53 -180) (layer "B.SilkS")
        (effects (font (size 0.7 0.7) (thickness 0.127)) (justify mirror))
    )
    (fp_text value "C_470n_0402" (at 0 -1.17 90) (layer "B.Fab")
        (effects (font (size 1 1) (thickness 0.15)) (justify mirror))
    )
    (fp_text user "Author: Antmicro" (at -0.939 -3.399 90) (layer "B.Fab") hide
        (effects (font (size 0.7 0.7) (thickness 0.15)) (justify left bottom mirror))
    )
    (fp_text user "License: Apache-2.0" (at -0.939 -5.799 90) (layer "B.Fab") hide
        (effects (font (size 0.7 0.7) (thickness 0.15)) (justify left bottom mirror))
    )
    (fp_text user "${REFERENCE}" (at 0 0 90) (layer "B.Fab")
        (effects (font (size 0.25 0.25) (thickness 0.04)) (justify mirror))
    )
    (fp_rect (start -0.925 0.47) (end 0.925 -0.47)
      (stroke (width 0.05) (type default)) (fill none) (layer "B.CrtYd"))
    (fp_line (start -0.494 -0.248) (end -0.494 0.25)
      (stroke (width 0.15) (type solid)) (layer "B.Fab"))
    (fp_line (start -0.494 0.25) (end 0.504 0.25)
      (stroke (width 0.15) (type solid)) (layer "B.Fab"))
    (fp_line (start 0.504 -0.248) (end -0.494 -0.248)
      (stroke (width 0.15) (type solid)) (layer "B.Fab"))
    (fp_line (start 0.504 0.25) (end 0.504 -0.248)
      (stroke (width 0.15) (type solid)) (layer "B.Fab"))
    (pad "1" smd roundrect (at -0.48 0 270) (size 0.59 0.64) (layers "B.Cu" "B.Paste" "B.Mask") (roundrect_rratio 0.25)
      (net 1 "GND") (pintype "passive"))
    (pad "2" smd roundrect (at 0.48 0 270) (size 0.59 0.64) (layers "B.Cu" "B.Paste" "B.Mask") (roundrect_rratio 0.25)
      (net 3 "VCC1V35") (pintype "passive"))
  )

  (footprint "antmicro-footprints:C_0402_1005Metric" (layer "B.Cu")
    (at 85.9 127.25 180)
    (descr "Capacitor SMD 0402")
    (tags "capacitor SMD 0402")
    (property "Author" "Antmicro")
    (property "Dielectric" "")
    (property "License" "Apache-2.0")
    (property "MPN" "C1005X5R1E474M050BB")
    (property "Manufacturer" "TDK")
    (property "Public" "False")
    (property "Sheetfile" "ddr3.kicad_sch")
    (property "Sheetname" "DDR3")
    (property "Val" "470n")
    (property "Voltage" "")
    (property "ki_description" "SMD Multilayer Ceramic Capacitor, 0.47 µF, 25 V, 0402 [1005 Metric], ± 20%, X5R, C")
    (property "ki_keywords" "0402, SMT, CAPACITOR, PASSIVE, CERAMIC, MLCC")
    (attr smd)
    (fp_text reference "C86" (at 1.89 0.045) (layer "B.SilkS")
        (effects (font (size 0.7 0.7) (thickness 0.127)) (justify mirror))
    )
    (fp_text value "C_470n_0402" (at 0 -1.17) (layer "B.Fab")
        (effects (font (size 1 1) (thickness 0.15)) (justify mirror))
    )
    (fp_text user "License: Apache-2.0" (at -0.939 -5.799) (layer "B.Fab") hide
        (effects (font (size 0.7 0.7) (thickness 0.15)) (justify left bottom mirror))
    )
    (fp_text user "${REFERENCE}" (at 0 0) (layer "B.Fab")
        (effects (font (size 0.25 0.25) (thickness 0.04)) (justify mirror))
    )
    (fp_text user "Author: Antmicro" (at -0.939 -3.399) (layer "B.Fab") hide
        (effects (font (size 0.7 0.7) (thickness 0.15)) (justify left bottom mirror))
    )
    (fp_rect (start -0.925 0.47) (end 0.925 -0.47)
      (stroke (width 0.05) (type default)) (fill none) (layer "B.CrtYd"))
    (fp_line (start -0.494 -0.248) (end -0.494 0.25)
      (stroke (width 0.15) (type solid)) (layer "B.Fab"))
    (fp_line (start -0.494 0.25) (end 0.504 0.25)
      (stroke (width 0.15) (type solid)) (layer "B.Fab"))
    (fp_line (start 0.504 -0.248) (end -0.494 -0.248)
      (stroke (width 0.15) (type solid)) (layer "B.Fab"))
    (fp_line (start 0.504 0.25) (end 0.504 -0.248)
      (stroke (width 0.15) (type solid)) (layer "B.Fab"))
    (pad "1" smd roundrect (at -0.48 0 180) (size 0.59 0.64) (layers "B.Cu" "B.Paste" "B.Mask") (roundrect_rratio 0.25)
      (net 1 "GND") (pintype "passive"))
    (pad "2" smd roundrect (at 0.48 0 180) (size 0.59 0.64) (layers "B.Cu" "B.Paste" "B.Mask") (roundrect_rratio 0.25)
      (net 3 "VCC1V35") (pintype "passive"))
  )

  (footprint "antmicro-footprints:C_0402_1005Metric" (layer "B.Cu")
    (at 87.75 121.6 -90)
    (descr "Capacitor SMD 0402")
    (tags "capacitor SMD 0402")
    (property "Author" "Antmicro")
    (property "Dielectric" "X5R")
    (property "License" "Apache-2.0")
    (property "MPN" "GRM155R61H104KE14D")
    (property "Manufacturer" "Murata")
    (property "Public" "False")
    (property "Sheetfile" "ddr3.kicad_sch")
    (property "Sheetname" "DDR3")
    (property "Val" "100n")
    (property "Voltage" "50V")
    (property "ki_description" "SMD Multilayer Ceramic Capacitor, 0.1 µF, 50 V, 0402 [1005 Metric], ± 10%, X5R, GRM Series")
    (property "ki_keywords" "0402, SMT, CAPACITOR, PASSIVE, CERAMIC, MLCC")
    (attr smd)
    (fp_text reference "C88" (at -0.025 0.99 90) (layer "B.SilkS")
        (effects (font (size 0.7 0.7) (thickness 0.127)) (justify mirror))
    )
    (fp_text value "C_100n_0402" (at 0 -1.17 90) (layer "B.Fab")
        (effects (font (size 1 1) (thickness 0.15)) (justify mirror))
    )
    (fp_text user "Author: Antmicro" (at -0.939 -3.399 90) (layer "B.Fab") hide
        (effects (font (size 0.7 0.7) (thickness 0.15)) (justify left bottom mirror))
    )
    (fp_text user "License: Apache-2.0" (at -0.939 -5.799 90) (layer "B.Fab") hide
        (effects (font (size 0.7 0.7) (thickness 0.15)) (justify left bottom mirror))
    )
    (fp_text user "${REFERENCE}" (at 0 0 90) (layer "B.Fab")
        (effects (font (size 0.25 0.25) (thickness 0.04)) (justify mirror))
    )
    (fp_rect (start -0.925 0.47) (end 0.925 -0.47)
      (stroke (width 0.05) (type default)) (fill none) (layer "B.CrtYd"))
    (fp_line (start -0.494 -0.248) (end -0.494 0.25)
      (stroke (width 0.15) (type solid)) (layer "B.Fab"))
    (fp_line (start -0.494 0.25) (end 0.504 0.25)
      (stroke (width 0.15) (type solid)) (layer "B.Fab"))
    (fp_line (start 0.504 -0.248) (end -0.494 -0.248)
      (stroke (width 0.15) (type solid)) (layer "B.Fab"))
    (fp_line (start 0.504 0.25) (end 0.504 -0.248)
      (stroke (width 0.15) (type solid)) (layer "B.Fab"))
    (pad "1" smd roundrect (at -0.48 0 270) (size 0.59 0.64) (layers "B.Cu" "B.Paste" "B.Mask") (roundrect_rratio 0.25)
      (net 1 "GND") (pintype "passive"))
    (pad "2" smd roundrect (at 0.48 0 270) (size 0.59 0.64) (layers "B.Cu" "B.Paste" "B.Mask") (roundrect_rratio 0.25)
      (net 217 "DDR3_VREF") (pintype "passive"))
  )

  (footprint "antmicro-footprints:C_0402_1005Metric" (layer "B.Cu")
    (at 88.45 119.395 180)
    (descr "Capacitor SMD 0402")
    (tags "capacitor SMD 0402")
    (property "Author" "Antmicro")
    (property "Dielectric" "")
    (property "License" "Apache-2.0")
    (property "MPN" "C1005X5R1E474M050BB")
    (property "Manufacturer" "TDK")
    (property "Public" "False")
    (property "Sheetfile" "ddr3.kicad_sch")
    (property "Sheetname" "DDR3")
    (property "Val" "470n")
    (property "Voltage" "")
    (property "ki_description" "SMD Multilayer Ceramic Capacitor, 0.47 µF, 25 V, 0402 [1005 Metric], ± 20%, X5R, C")
    (property "ki_keywords" "0402, SMT, CAPACITOR, PASSIVE, CERAMIC, MLCC")
    (attr smd)
    (fp_text reference "C89" (at -1.89 0.025) (layer "B.SilkS")
        (effects (font (size 0.7 0.7) (thickness 0.127)) (justify mirror))
    )
    (fp_text value "C_470n_0402" (at 0 -1.17) (layer "B.Fab")
        (effects (font (size 1 1) (thickness 0.15)) (justify mirror))
    )
    (fp_text user "Author: Antmicro" (at -0.939 -3.399) (layer "B.Fab") hide
        (effects (font (size 0.7 0.7) (thickness 0.15)) (justify left bottom mirror))
    )
    (fp_text user "License: Apache-2.0" (at -0.939 -5.799) (layer "B.Fab") hide
        (effects (font (size 0.7 0.7) (thickness 0.15)) (justify left bottom mirror))
    )
    (fp_text user "${REFERENCE}" (at 0 0) (layer "B.Fab")
        (effects (font (size 0.25 0.25) (thickness 0.04)) (justify mirror))
    )
    (fp_rect (start -0.925 0.47) (end 0.925 -0.47)
      (stroke (width 0.05) (type default)) (fill none) (layer "B.CrtYd"))
    (fp_line (start -0.494 -0.248) (end -0.494 0.25)
      (stroke (width 0.15) (type solid)) (layer "B.Fab"))
    (fp_line (start -0.494 0.25) (end 0.504 0.25)
      (stroke (width 0.15) (type solid)) (layer "B.Fab"))
    (fp_line (start 0.504 -0.248) (end -0.494 -0.248)
      (stroke (width 0.15) (type solid)) (layer "B.Fab"))
    (fp_line (start 0.504 0.25) (end 0.504 -0.248)
      (stroke (width 0.15) (type solid)) (layer "B.Fab"))
    (pad "1" smd roundrect (at -0.48 0 180) (size 0.59 0.64) (layers "B.Cu" "B.Paste" "B.Mask") (roundrect_rratio 0.25)
      (net 1 "GND") (pintype "passive"))
    (pad "2" smd roundrect (at 0.48 0 180) (size 0.59 0.64) (layers "B.Cu" "B.Paste" "B.Mask") (roundrect_rratio 0.25)
      (net 3 "VCC1V35") (pintype "passive"))
  )

  (footprint "antmicro-footprints:C_0402_1005Metric" (layer "B.Cu")
    (at 80.29 130.545)
    (descr "Capacitor SMD 0402")
    (tags "capacitor SMD 0402")
    (property "Author" "Antmicro")
    (property "Dielectric" "")
    (property "License" "Apache-2.0")
    (property "MPN" "C1005X5R1E474M050BB")
    (property "Manufacturer" "TDK")
    (property "Public" "False")
    (property "Sheetfile" "ddr3.kicad_sch")
    (property "Sheetname" "DDR3")
    (property "Val" "470n")
    (property "Voltage" "")
    (property "ki_description" "SMD Multilayer Ceramic Capacitor, 0.47 µF, 25 V, 0402 [1005 Metric], ± 20%, X5R, C")
    (property "ki_keywords" "0402, SMT, CAPACITOR, PASSIVE, CERAMIC, MLCC")
    (attr smd)
    (fp_text reference "C92" (at -0.01 0.9) (layer "B.SilkS")
        (effects (font (size 0.7 0.7) (thickness 0.127)) (justify mirror))
    )
    (fp_text value "C_470n_0402" (at 0 -1.17) (layer "B.Fab")
        (effects (font (size 1 1) (thickness 0.15)) (justify mirror))
    )
    (fp_text user "License: Apache-2.0" (at -0.939 -5.799 180) (layer "B.Fab") hide
        (effects (font (size 0.7 0.7) (thickness 0.15)) (justify left bottom mirror))
    )
    (fp_text user "Author: Antmicro" (at -0.939 -3.399 180) (layer "B.Fab") hide
        (effects (font (size 0.7 0.7) (thickness 0.15)) (justify left bottom mirror))
    )
    (fp_text user "${REFERENCE}" (at 0 0) (layer "B.Fab")
        (effects (font (size 0.25 0.25) (thickness 0.04)) (justify mirror))
    )
    (fp_rect (start -0.925 0.47) (end 0.925 -0.47)
      (stroke (width 0.05) (type default)) (fill none) (layer "B.CrtYd"))
    (fp_line (start -0.494 -0.248) (end -0.494 0.25)
      (stroke (width 0.15) (type solid)) (layer "B.Fab"))
    (fp_line (start -0.494 0.25) (end 0.504 0.25)
      (stroke (width 0.15) (type solid)) (layer "B.Fab"))
    (fp_line (start 0.504 -0.248) (end -0.494 -0.248)
      (stroke (width 0.15) (type solid)) (layer "B.Fab"))
    (fp_line (start 0.504 0.25) (end 0.504 -0.248)
      (stroke (width 0.15) (type solid)) (layer "B.Fab"))
    (pad "1" smd roundrect (at -0.48 0) (size 0.59 0.64) (layers "B.Cu" "B.Paste" "B.Mask") (roundrect_rratio 0.25)
      (net 1 "GND") (pintype "passive"))
    (pad "2" smd roundrect (at 0.48 0) (size 0.59 0.64) (layers "B.Cu" "B.Paste" "B.Mask") (roundrect_rratio 0.25)
      (net 3 "VCC1V35") (pintype "passive"))
  )

  (footprint "antmicro-footprints:C_0402_1005Metric" (layer "B.Cu")
    (at 80.64 125.095 -90)
    (descr "Capacitor SMD 0402")
    (tags "capacitor SMD 0402")
    (property "Author" "Antmicro")
    (property "Dielectric" "X5R")
    (property "License" "Apache-2.0")
    (property "MPN" "GRM155R61H104KE14D")
    (property "Manufacturer" "Murata")
    (property "Public" "False")
    (property "Sheetfile" "ddr3.kicad_sch")
    (property "Sheetname" "DDR3")
    (property "Val" "100n")
    (property "Voltage" "50V")
    (property "ki_description" "SMD Multilayer Ceramic Capacitor, 0.1 µF, 50 V, 0402 [1005 Metric], ± 10%, X5R, GRM Series")
    (property "ki_keywords" "0402, SMT, CAPACITOR, PASSIVE, CERAMIC, MLCC")
    (attr smd)
    (fp_text reference "C94" (at 2.58 4.64 90) (layer "B.SilkS")
        (effects (font (size 0.7 0.7) (thickness 0.127)) (justify mirror))
    )
    (fp_text value "C_100n_0402" (at 0 -1.17 90) (layer "B.Fab")
        (effects (font (size 1 1) (thickness 0.15)) (justify mirror))
    )
    (fp_text user "${REFERENCE}" (at 0 0 90) (layer "B.Fab")
        (effects (font (size 0.25 0.25) (thickness 0.04)) (justify mirror))
    )
    (fp_text user "Author: Antmicro" (at -0.939 -3.399 90) (layer "B.Fab") hide
        (effects (font (size 0.7 0.7) (thickness 0.15)) (justify left bottom mirror))
    )
    (fp_text user "License: Apache-2.0" (at -0.939 -5.799 90) (layer "B.Fab") hide
        (effects (font (size 0.7 0.7) (thickness 0.15)) (justify left bottom mirror))
    )
    (fp_rect (start -0.925 0.47) (end 0.925 -0.47)
      (stroke (width 0.05) (type default)) (fill none) (layer "B.CrtYd"))
    (fp_line (start -0.494 -0.248) (end -0.494 0.25)
      (stroke (width 0.15) (type solid)) (layer "B.Fab"))
    (fp_line (start -0.494 0.25) (end 0.504 0.25)
      (stroke (width 0.15) (type solid)) (layer "B.Fab"))
    (fp_line (start 0.504 -0.248) (end -0.494 -0.248)
      (stroke (width 0.15) (type solid)) (layer "B.Fab"))
    (fp_line (start 0.504 0.25) (end 0.504 -0.248)
      (stroke (width 0.15) (type solid)) (layer "B.Fab"))
    (pad "1" smd roundrect (at -0.48 0 270) (size 0.59 0.64) (layers "B.Cu" "B.Paste" "B.Mask") (roundrect_rratio 0.25)
      (net 228 "Net-(C94-Pad1)") (pintype "passive"))
    (pad "2" smd roundrect (at 0.48 0 270) (size 0.59 0.64) (layers "B.Cu" "B.Paste" "B.Mask") (roundrect_rratio 0.25)
      (net 1 "GND") (pintype "passive"))
  )

  (footprint "antmicro-footprints:R_0402_1005Metric" (layer "B.Cu")
    (at 125.225 111.425 180)
    (descr "Resistor SMD 0402")
    (tags "resistor SMD 0402")
    (property "Author" "Antmicro")
    (property "License" "Apache-2.0")
    (property "MPN" "CR0402-FX-1001GLF")
    (property "Manufacturer" "Bourns")
    (property "Public" "False")
    (property "Sheetfile" "interfaces.kicad_sch")
    (property "Sheetname" "Interfaces")
    (property "Tolerance" "1%")
    (property "Val" "1k")
    (property "ki_description" "SMD Chip Resistor, 1 kohm, ± 1%, 63 mW, 0402 [1005 Metric], Thick Film, General Purpose")
    (property "ki_keywords" "0402, SMT, RESISTOR, PASSIVE")
    (attr smd)
    (fp_text reference "R76" (at 0.025 1.025) (layer "B.SilkS")
        (effects (font (size 0.7 0.7) (thickness 0.127)) (justify mirror))
    )
    (fp_text value "R_1k_0402" (at 0 -1.17) (layer "B.Fab")
        (effects (font (size 1 1) (thickness 0.15)) (justify mirror))
    )
    (fp_text user "${REFERENCE}" (at 0 0) (layer "B.Fab")
        (effects (font (size 0.25 0.25) (thickness 0.04)) (justify mirror))
    )
    (fp_text user "Author: Antmicro" (at -0.95 -4.169) (layer "B.Fab") hide
        (effects (font (size 0.7 0.7) (thickness 0.15)) (justify left bottom mirror))
    )
    (fp_text user "License: Apache-2.0" (at -0.95 -5.169) (layer "B.Fab") hide
        (effects (font (size 0.7 0.7) (thickness 0.15)) (justify left bottom mirror))
    )
    (fp_rect (start -0.925 0.47) (end 0.925 -0.47)
      (stroke (width 0.05) (type default)) (fill none) (layer "B.CrtYd"))
    (fp_rect (start -0.5 0.25) (end 0.5 -0.25)
      (stroke (width 0.15) (type solid)) (fill none) (layer "B.Fab"))
    (pad "1" smd roundrect (at -0.48 0 180) (size 0.59 0.64) (layers "B.Cu" "B.Paste" "B.Mask") (roundrect_rratio 0.25)
      (net 11 "VCC5V0") (pintype "passive"))
    (pad "2" smd roundrect (at 0.48 0 180) (size 0.59 0.64) (layers "B.Cu" "B.Paste" "B.Mask") (roundrect_rratio 0.25)
      (net 406 "Net-(U9-VBUS)") (pintype "passive"))
  )

  (footprint "antmicro-footprints:R_0402_1005Metric" (layer "B.Cu")
    (at 78.615 123.195 180)
    (descr "Resistor SMD 0402")
    (tags "resistor SMD 0402")
    (property "Author" "Antmicro")
    (property "License" "Apache-2.0")
    (property "MPN" "CR0402-FX-2400GLF")
    (property "Manufacturer" "Bourns")
    (property "Public" "False")
    (property "Sheetfile" "ddr3.kicad_sch")
    (property "Sheetname" "DDR3")
    (property "Tolerance" "1%")
    (property "Val" "240R")
    (property "ki_description" "SMD Chip Resistor, 240 ohm, ± 1%, 63 mW, 0402 [1005 Metric], Thick Film, General Purpose")
    (property "ki_keywords" "0402, SMT, RESISTOR, PASSIVE")
    (attr smd)
    (fp_text reference "R81" (at 2.365 0.11) (layer "B.SilkS")
        (effects (font (size 0.7 0.7) (thickness 0.127)) (justify mirror))
    )
    (fp_text value "R_240R_0402" (at 0 -1.17) (layer "B.Fab")
        (effects (font (size 1 1) (thickness 0.15)) (justify mirror))
    )
    (fp_text user "Author: Antmicro" (at -0.95 -4.169) (layer "B.Fab") hide
        (effects (font (size 0.7 0.7) (thickness 0.15)) (justify left bottom mirror))
    )
    (fp_text user "License: Apache-2.0" (at -0.95 -5.169) (layer "B.Fab") hide
        (effects (font (size 0.7 0.7) (thickness 0.15)) (justify left bottom mirror))
    )
    (fp_text user "${REFERENCE}" (at 0 0) (layer "B.Fab")
        (effects (font (size 0.25 0.25) (thickness 0.04)) (justify mirror))
    )
    (fp_rect (start -0.925 0.47) (end 0.925 -0.47)
      (stroke (width 0.05) (type default)) (fill none) (layer "B.CrtYd"))
    (fp_rect (start -0.5 0.25) (end 0.5 -0.25)
      (stroke (width 0.15) (type solid)) (fill none) (layer "B.Fab"))
    (pad "1" smd roundrect (at -0.48 0 180) (size 0.59 0.64) (layers "B.Cu" "B.Paste" "B.Mask") (roundrect_rratio 0.25)
      (net 418 "Net-(U10-ZQ)") (pintype "passive"))
    (pad "2" smd roundrect (at 0.48 0 180) (size 0.59 0.64) (layers "B.Cu" "B.Paste" "B.Mask") (roundrect_rratio 0.25)
      (net 1 "GND") (pintype "passive"))
  )

  (footprint "antmicro-footprints:R_0402_1005Metric" (layer "B.Cu")
    (at 81.09 123.595 180)
    (descr "Resistor SMD 0402")
    (tags "resistor SMD 0402")
    (property "Author" "Antmicro")
    (property "License" "Apache-2.0")
    (property "MPN" "CR0402-FX-51R0GLF")
    (property "Manufacturer" "Bourns")
    (property "Public" "False")
    (property "Sheetfile" "ddr3.kicad_sch")
    (property "Sheetname" "DDR3")
    (property "Tolerance" "1%")
    (property "Val" "51R")
    (property "ki_description" "SMD Chip Resistor, 51 ohm, ± 1%, 63 mW, 0402 [1005 Metric], Thick Film, General Purpose")
    (property "ki_keywords" "0402, SMT, RESISTOR, PASSIVE")
    (attr smd)
    (fp_text reference "R82" (at 0.01 -3.79) (layer "B.SilkS")
        (effects (font (size 0.7 0.7) (thickness 0.127)) (justify mirror))
    )
    (fp_text value "R_51R_0402" (at 0 -1.17) (layer "B.Fab")
        (effects (font (size 1 1) (thickness 0.15)) (justify mirror))
    )
    (fp_text user "${REFERENCE}" (at 0 0) (layer "B.Fab")
        (effects (font (size 0.25 0.25) (thickness 0.04)) (justify mirror))
    )
    (fp_text user "License: Apache-2.0" (at -0.95 -5.169) (layer "B.Fab") hide
        (effects (font (size 0.7 0.7) (thickness 0.15)) (justify left bottom mirror))
    )
    (fp_text user "Author: Antmicro" (at -0.95 -4.169) (layer "B.Fab") hide
        (effects (font (size 0.7 0.7) (thickness 0.15)) (justify left bottom mirror))
    )
    (fp_rect (start -0.925 0.47) (end 0.925 -0.47)
      (stroke (width 0.05) (type default)) (fill none) (layer "B.CrtYd"))
    (fp_rect (start -0.5 0.25) (end 0.5 -0.25)
      (stroke (width 0.15) (type solid)) (fill none) (layer "B.Fab"))
    (pad "1" smd roundrect (at -0.48 0 180) (size 0.59 0.64) (layers "B.Cu" "B.Paste" "B.Mask") (roundrect_rratio 0.25)
      (net 261 "DDR3_CLK+") (pintype "passive"))
    (pad "2" smd roundrect (at 0.48 0 180) (size 0.59 0.64) (layers "B.Cu" "B.Paste" "B.Mask") (roundrect_rratio 0.25)
      (net 228 "Net-(C94-Pad1)") (pintype "passive"))
  )

  (footprint "antmicro-footprints:C_0603_1608Metric" (layer "B.Cu")
    (at 99.65 132.55 90)
    (descr "Capacitor SMD 0603")
    (tags "capacitor 0603")
    (property "Author" "Antmicro")
    (property "Dielectric" "")
    (property "License" "Apache-2.0")
    (property "MPN" "GRM188R60J476ME15D")
    (property "Manufacturer" "Murata")
    (property "Public" "False")
    (property "Sheetfile" "fpga-power-supply.kicad_sch")
    (property "Sheetname" "FPGA power supply")
    (property "Val" "47u")
    (property "Voltage" "")
    (property "ki_description" "SMD Multilayer Ceramic Capacitor, 47 µF, 6.3 V, 0603 [1608 Metric], ± 20%, X5R, GRM Series")
    (property "ki_keywords" "0603, SMT, CAPACITOR, PASSIVE, CERAMIC, MLCC")
    (attr smd)
    (fp_text reference "C133" (at -20.385 1.25 90) (layer "B.SilkS")
        (effects (font (size 0.7 0.7) (thickness 0.127)) (justify mirror))
    )
    (fp_text value "C_47u_0603" (at 0 -1.9 90) (layer "B.Fab")
        (effects (font (size 1 1) (thickness 0.15)) (justify mirror))
    )
    (fp_text user "${REFERENCE}" (at -1.682 -3.895 270) (layer "B.Fab") hide
        (effects (font (size 0.7 0.7) (thickness 0.15)) (justify left bottom mirror))
    )
    (fp_text user "Author: Antmicro" (at -1.682 -4.894 270) (layer "B.Fab") hide
        (effects (font (size 0.7 0.7) (thickness 0.15)) (justify left bottom mirror))
    )
    (fp_text user "License: Apache-2.0" (at -1.682 -5.895 270) (layer "B.Fab") hide
        (effects (font (size 0.7 0.7) (thickness 0.15)) (justify left bottom mirror))
    )
    (fp_line (start -0.15 -0.4) (end 0.15 -0.4)
      (stroke (width 0.15) (type solid)) (layer "B.SilkS"))
    (fp_line (start -0.15 0.4) (end 0.15 0.4)
      (stroke (width 0.15) (type solid)) (layer "B.SilkS"))
    (fp_rect (start -1.25 0.65) (end 1.25 -0.65)
      (stroke (width 0.05) (type solid)) (fill none) (layer "B.CrtYd"))
    (fp_rect (start -0.8 0.4) (end 0.8 -0.4)
      (stroke (width 0.15) (type solid)) (fill none) (layer "B.Fab"))
    (pad "1" smd roundrect (at -0.7 0 90) (size 0.8 1) (layers "B.Cu" "B.Paste" "B.Mask") (roundrect_rratio 0.2)
      (net 1 "GND") (pintype "passive"))
    (pad "2" smd roundrect (at 0.7 0 90) (size 0.8 1) (layers "B.Cu" "B.Paste" "B.Mask") (roundrect_rratio 0.2)
      (net 302 "/FPGA power supply/VCCA0") (pintype "passive"))
  )

  (footprint "antmicro-footprints:C_0402_1005Metric" (layer "B.Cu")
    (at 96.85 130.8)
    (descr "Capacitor SMD 0402")
    (tags "capacitor SMD 0402")
    (property "Author" "Antmicro")
    (property "Dielectric" "")
    (property "License" "Apache-2.0")
    (property "MPN" "GRM155R61A475MEAAD")
    (property "Manufacturer" "Murata")
    (property "Public" "False")
    (property "Sheetfile" "fpga-power-supply.kicad_sch")
    (property "Sheetname" "FPGA power supply")
    (property "Val" "4u7")
    (property "Voltage" "")
    (property "ki_description" "SMD Multilayer Ceramic Capacitor, 4.7 µF, 10 V, 0402 [1005 Metric], ± 20%, X5R, GRM Series")
    (property "ki_keywords" "0402, SMT, CAPACITOR, PASSIVE")
    (attr smd)
    (fp_text reference "C134" (at -2.74 0.085) (layer "B.SilkS")
        (effects (font (size 0.7 0.7) (thickness 0.127)) (justify mirror))
    )
    (fp_text value "C_4u7_0402" (at 0 -1.17) (layer "B.Fab")
        (effects (font (size 1 1) (thickness 0.15)) (justify mirror))
    )
    (fp_text user "${REFERENCE}" (at 0 0) (layer "B.Fab")
        (effects (font (size 0.25 0.25) (thickness 0.04)) (justify mirror))
    )
    (fp_text user "License: Apache-2.0" (at -0.939 -5.799 180) (layer "B.Fab") hide
        (effects (font (size 0.7 0.7) (thickness 0.15)) (justify left bottom mirror))
    )
    (fp_text user "Author: Antmicro" (at -0.939 -3.399 180) (layer "B.Fab") hide
        (effects (font (size 0.7 0.7) (thickness 0.15)) (justify left bottom mirror))
    )
    (fp_rect (start -0.925 0.47) (end 0.925 -0.47)
      (stroke (width 0.05) (type default)) (fill none) (layer "B.CrtYd"))
    (fp_line (start -0.494 -0.248) (end -0.494 0.25)
      (stroke (width 0.15) (type solid)) (layer "B.Fab"))
    (fp_line (start -0.494 0.25) (end 0.504 0.25)
      (stroke (width 0.15) (type solid)) (layer "B.Fab"))
    (fp_line (start 0.504 -0.248) (end -0.494 -0.248)
      (stroke (width 0.15) (type solid)) (layer "B.Fab"))
    (fp_line (start 0.504 0.25) (end 0.504 -0.248)
      (stroke (width 0.15) (type solid)) (layer "B.Fab"))
    (pad "1" smd roundrect (at -0.48 0) (size 0.59 0.64) (layers "B.Cu" "B.Paste" "B.Mask") (roundrect_rratio 0.25)
      (net 1 "GND") (pintype "passive"))
    (pad "2" smd roundrect (at 0.48 0) (size 0.59 0.64) (layers "B.Cu" "B.Paste" "B.Mask") (roundrect_rratio 0.25)
      (net 302 "/FPGA power supply/VCCA0") (pintype "passive"))
  )

  (footprint "antmicro-footprints:C_0402_1005Metric" (layer "B.Cu")
    (at 96.85 129.8)
    (descr "Capacitor SMD 0402")
    (tags "capacitor SMD 0402")
    (property "Author" "Antmicro")
    (property "Dielectric" "")
    (property "License" "Apache-2.0")
    (property "MPN" "C1005X5R1E474M050BB")
    (property "Manufacturer" "TDK")
    (property "Public" "False")
    (property "Sheetfile" "fpga-power-supply.kicad_sch")
    (property "Sheetname" "FPGA power supply")
    (property "Val" "470n")
    (property "Voltage" "")
    (property "ki_description" "SMD Multilayer Ceramic Capacitor, 0.47 µF, 25 V, 0402 [1005 Metric], ± 20%, X5R, C")
    (property "ki_keywords" "0402, SMT, CAPACITOR, PASSIVE, CERAMIC, MLCC")
    (attr smd)
    (fp_text reference "C136" (at -2.17 -0.305) (layer "B.SilkS")
        (effects (font (size 0.7 0.7) (thickness 0.127)) (justify mirror))
    )
    (fp_text value "C_470n_0402" (at 0 -1.17) (layer "B.Fab")
        (effects (font (size 1 1) (thickness 0.15)) (justify mirror))
    )
    (fp_text user "Author: Antmicro" (at -0.939 -3.399 180) (layer "B.Fab") hide
        (effects (font (size 0.7 0.7) (thickness 0.15)) (justify left bottom mirror))
    )
    (fp_text user "${REFERENCE}" (at 0 0) (layer "B.Fab")
        (effects (font (size 0.25 0.25) (thickness 0.04)) (justify mirror))
    )
    (fp_text user "License: Apache-2.0" (at -0.939 -5.799 180) (layer "B.Fab") hide
        (effects (font (size 0.7 0.7) (thickness 0.15)) (justify left bottom mirror))
    )
    (fp_rect (start -0.925 0.47) (end 0.925 -0.47)
      (stroke (width 0.05) (type default)) (fill none) (layer "B.CrtYd"))
    (fp_line (start -0.494 -0.248) (end -0.494 0.25)
      (stroke (width 0.15) (type solid)) (layer "B.Fab"))
    (fp_line (start -0.494 0.25) (end 0.504 0.25)
      (stroke (width 0.15) (type solid)) (layer "B.Fab"))
    (fp_line (start 0.504 -0.248) (end -0.494 -0.248)
      (stroke (width 0.15) (type solid)) (layer "B.Fab"))
    (fp_line (start 0.504 0.25) (end 0.504 -0.248)
      (stroke (width 0.15) (type solid)) (layer "B.Fab"))
    (pad "1" smd roundrect (at -0.48 0) (size 0.59 0.64) (layers "B.Cu" "B.Paste" "B.Mask") (roundrect_rratio 0.25)
      (net 1 "GND") (pintype "passive"))
    (pad "2" smd roundrect (at 0.48 0) (size 0.59 0.64) (layers "B.Cu" "B.Paste" "B.Mask") (roundrect_rratio 0.25)
      (net 302 "/FPGA power supply/VCCA0") (pintype "passive"))
  )

  (footprint "antmicro-footprints:C_0402_1005Metric" (layer "B.Cu")
    (at 102.335 129.25 180)
    (descr "Capacitor SMD 0402")
    (tags "capacitor SMD 0402")
    (property "Author" "Antmicro")
    (property "Dielectric" "X5R")
    (property "License" "Apache-2.0")
    (property "MPN" "GRM155R61H104KE14D")
    (property "Manufacturer" "Murata")
    (property "Public" "False")
    (property "Sheetfile" "fpga-power-supply.kicad_sch")
    (property "Sheetname" "FPGA power supply")
    (property "Val" "100n")
    (property "Voltage" "50V")
    (property "ki_description" "SMD Multilayer Ceramic Capacitor, 0.1 µF, 50 V, 0402 [1005 Metric], ± 10%, X5R, GRM Series")
    (property "ki_keywords" "0402, SMT, CAPACITOR, PASSIVE, CERAMIC, MLCC")
    (attr smd)
    (fp_text reference "C137" (at -0.145 -20.705) (layer "B.SilkS")
        (effects (font (size 0.7 0.7) (thickness 0.127)) (justify mirror))
    )
    (fp_text value "C_100n_0402" (at 0 -1.17) (layer "B.Fab")
        (effects (font (size 1 1) (thickness 0.15)) (justify mirror))
    )
    (fp_text user "${REFERENCE}" (at 0 0) (layer "B.Fab")
        (effects (font (size 0.25 0.25) (thickness 0.04)) (justify mirror))
    )
    (fp_text user "License: Apache-2.0" (at -0.939 -5.799) (layer "B.Fab") hide
        (effects (font (size 0.7 0.7) (thickness 0.15)) (justify left bottom mirror))
    )
    (fp_text user "Author: Antmicro" (at -0.939 -3.399) (layer "B.Fab") hide
        (effects (font (size 0.7 0.7) (thickness 0.15)) (justify left bottom mirror))
    )
    (fp_rect (start -0.925 0.47) (end 0.925 -0.47)
      (stroke (width 0.05) (type default)) (fill none) (layer "B.CrtYd"))
    (fp_line (start -0.494 -0.248) (end -0.494 0.25)
      (stroke (width 0.15) (type solid)) (layer "B.Fab"))
    (fp_line (start -0.494 0.25) (end 0.504 0.25)
      (stroke (width 0.15) (type solid)) (layer "B.Fab"))
    (fp_line (start 0.504 -0.248) (end -0.494 -0.248)
      (stroke (width 0.15) (type solid)) (layer "B.Fab"))
    (fp_line (start 0.504 0.25) (end 0.504 -0.248)
      (stroke (width 0.15) (type solid)) (layer "B.Fab"))
    (pad "1" smd roundrect (at -0.48 0 180) (size 0.59 0.64) (layers "B.Cu" "B.Paste" "B.Mask") (roundrect_rratio 0.25)
      (net 1 "GND") (pintype "passive"))
    (pad "2" smd roundrect (at 0.48 0 180) (size 0.59 0.64) (layers "B.Cu" "B.Paste" "B.Mask") (roundrect_rratio 0.25)
      (net 302 "/FPGA power supply/VCCA0") (pintype "passive"))
  )

  (footprint "antmicro-footprints:C_0402_1005Metric" (layer "B.Cu")
    (at 98.4 132.25 90)
    (descr "Capacitor SMD 0402")
    (tags "capacitor SMD 0402")
    (property "Author" "Antmicro")
    (property "Dielectric" "X7R")
    (property "License" "Apache-2.0")
    (property "MPN" "GRM155R71H103KA88D")
    (property "Manufacturer" "Murata")
    (property "Public" "False")
    (property "Sheetfile" "fpga-power-supply.kicad_sch")
    (property "Sheetname" "FPGA power supply")
    (property "Val" "10n")
    (property "Voltage" "50V")
    (property "ki_description" "SMD Multilayer Ceramic Capacitor, 10000 pF, 50 V, 0402 [1005 Metric], ± 10%, X7R, GRM Series")
    (property "ki_keywords" "0402, SMT, CAPACITOR, PASSIVE")
    (attr smd)
    (fp_text reference "C138" (at -20.685 1.5 90) (layer "B.SilkS")
        (effects (font (size 0.7 0.7) (thickness 0.127)) (justify mirror))
    )
    (fp_text value "C_10n_0402" (at 0 -1.17 90) (layer "B.Fab")
        (effects (font (size 1 1) (thickness 0.15)) (justify mirror))
    )
    (fp_text user "Author: Antmicro" (at -0.939 -3.399 270) (layer "B.Fab") hide
        (effects (font (size 0.7 0.7) (thickness 0.15)) (justify left bottom mirror))
    )
    (fp_text user "License: Apache-2.0" (at -0.939 -5.799 270) (layer "B.Fab") hide
        (effects (font (size 0.7 0.7) (thickness 0.15)) (justify left bottom mirror))
    )
    (fp_text user "${REFERENCE}" (at 0 0 90) (layer "B.Fab")
        (effects (font (size 0.25 0.25) (thickness 0.04)) (justify mirror))
    )
    (fp_rect (start -0.925 0.47) (end 0.925 -0.47)
      (stroke (width 0.05) (type default)) (fill none) (layer "B.CrtYd"))
    (fp_line (start -0.494 -0.248) (end -0.494 0.25)
      (stroke (width 0.15) (type solid)) (layer "B.Fab"))
    (fp_line (start -0.494 0.25) (end 0.504 0.25)
      (stroke (width 0.15) (type solid)) (layer "B.Fab"))
    (fp_line (start 0.504 -0.248) (end -0.494 -0.248)
      (stroke (width 0.15) (type solid)) (layer "B.Fab"))
    (fp_line (start 0.504 0.25) (end 0.504 -0.248)
      (stroke (width 0.15) (type solid)) (layer "B.Fab"))
    (pad "1" smd roundrect (at -0.48 0 90) (size 0.59 0.64) (layers "B.Cu" "B.Paste" "B.Mask") (roundrect_rratio 0.25)
      (net 1 "GND") (pintype "passive"))
    (pad "2" smd roundrect (at 0.48 0 90) (size 0.59 0.64) (layers "B.Cu" "B.Paste" "B.Mask") (roundrect_rratio 0.25)
      (net 302 "/FPGA power supply/VCCA0") (pintype "passive"))
  )

  (footprint "antmicro-footprints:C_0402_1005Metric" (layer "B.Cu")
    (at 100.9 132.25 90)
    (descr "Capacitor SMD 0402")
    (tags "capacitor SMD 0402")
    (property "Author" "Antmicro")
    (property "Dielectric" "X7R")
    (property "License" "Apache-2.0")
    (property "MPN" "GRM155R71H103KA88D")
    (property "Manufacturer" "Murata")
    (property "Public" "False")
    (property "Sheetfile" "fpga-power-supply.kicad_sch")
    (property "Sheetname" "FPGA power supply")
    (property "Val" "10n")
    (property "Voltage" "50V")
    (property "ki_description" "SMD Multilayer Ceramic Capacitor, 10000 pF, 50 V, 0402 [1005 Metric], ± 10%, X7R, GRM Series")
    (property "ki_keywords" "0402, SMT, CAPACITOR, PASSIVE")
    (attr smd)
    (fp_text reference "C143" (at -20.675 0.98 90) (layer "B.SilkS")
        (effects (font (size 0.7 0.7) (thickness 0.127)) (justify mirror))
    )
    (fp_text value "C_10n_0402" (at 0 -1.17 90) (layer "B.Fab")
        (effects (font (size 1 1) (thickness 0.15)) (justify mirror))
    )
    (fp_text user "License: Apache-2.0" (at -0.939 -5.799 270) (layer "B.Fab") hide
        (effects (font (size 0.7 0.7) (thickness 0.15)) (justify left bottom mirror))
    )
    (fp_text user "${REFERENCE}" (at 0 0 90) (layer "B.Fab")
        (effects (font (size 0.25 0.25) (thickness 0.04)) (justify mirror))
    )
    (fp_text user "Author: Antmicro" (at -0.939 -3.399 270) (layer "B.Fab") hide
        (effects (font (size 0.7 0.7) (thickness 0.15)) (justify left bottom mirror))
    )
    (fp_rect (start -0.925 0.47) (end 0.925 -0.47)
      (stroke (width 0.05) (type default)) (fill none) (layer "B.CrtYd"))
    (fp_line (start -0.494 -0.248) (end -0.494 0.25)
      (stroke (width 0.15) (type solid)) (layer "B.Fab"))
    (fp_line (start -0.494 0.25) (end 0.504 0.25)
      (stroke (width 0.15) (type solid)) (layer "B.Fab"))
    (fp_line (start 0.504 -0.248) (end -0.494 -0.248)
      (stroke (width 0.15) (type solid)) (layer "B.Fab"))
    (fp_line (start 0.504 0.25) (end 0.504 -0.248)
      (stroke (width 0.15) (type solid)) (layer "B.Fab"))
    (pad "1" smd roundrect (at -0.48 0 90) (size 0.59 0.64) (layers "B.Cu" "B.Paste" "B.Mask") (roundrect_rratio 0.25)
      (net 1 "GND") (pintype "passive"))
    (pad "2" smd roundrect (at 0.48 0 90) (size 0.59 0.64) (layers "B.Cu" "B.Paste" "B.Mask") (roundrect_rratio 0.25)
      (net 302 "/FPGA power supply/VCCA0") (pintype "passive"))
  )

  (footprint "antmicro-footprints:C_0402_1005Metric" (layer "B.Cu")
    (at 97.4 132.25 90)
    (descr "Capacitor SMD 0402")
    (tags "capacitor SMD 0402")
    (property "Author" "Antmicro")
    (property "Dielectric" "X7R")
    (property "License" "Apache-2.0")
    (property "MPN" "GRM155R71H103KA88D")
    (property "Manufacturer" "Murata")
    (property "Public" "False")
    (property "Sheetfile" "fpga-power-supply.kicad_sch")
    (property "Sheetname" "FPGA power supply")
    (property "Val" "10n")
    (property "Voltage" "50V")
    (property "ki_description" "SMD Multilayer Ceramic Capacitor, 10000 pF, 50 V, 0402 [1005 Metric], ± 10%, X7R, GRM Series")
    (property "ki_keywords" "0402, SMT, CAPACITOR, PASSIVE")
    (attr smd)
    (fp_text reference "C145" (at -20.685 1.47 90) (layer "B.SilkS")
        (effects (font (size 0.7 0.7) (thickness 0.127)) (justify mirror))
    )
    (fp_text value "C_10n_0402" (at 0 -1.17 90) (layer "B.Fab")
        (effects (font (size 1 1) (thickness 0.15)) (justify mirror))
    )
    (fp_text user "Author: Antmicro" (at -0.939 -3.399 270) (layer "B.Fab") hide
        (effects (font (size 0.7 0.7) (thickness 0.15)) (justify left bottom mirror))
    )
    (fp_text user "License: Apache-2.0" (at -0.939 -5.799 270) (layer "B.Fab") hide
        (effects (font (size 0.7 0.7) (thickness 0.15)) (justify left bottom mirror))
    )
    (fp_text user "${REFERENCE}" (at 0 0 90) (layer "B.Fab")
        (effects (font (size 0.25 0.25) (thickness 0.04)) (justify mirror))
    )
    (fp_rect (start -0.925 0.47) (end 0.925 -0.47)
      (stroke (width 0.05) (type default)) (fill none) (layer "B.CrtYd"))
    (fp_line (start -0.494 -0.248) (end -0.494 0.25)
      (stroke (width 0.15) (type solid)) (layer "B.Fab"))
    (fp_line (start -0.494 0.25) (end 0.504 0.25)
      (stroke (width 0.15) (type solid)) (layer "B.Fab"))
    (fp_line (start 0.504 -0.248) (end -0.494 -0.248)
      (stroke (width 0.15) (type solid)) (layer "B.Fab"))
    (fp_line (start 0.504 0.25) (end 0.504 -0.248)
      (stroke (width 0.15) (type solid)) (layer "B.Fab"))
    (pad "1" smd roundrect (at -0.48 0 90) (size 0.59 0.64) (layers "B.Cu" "B.Paste" "B.Mask") (roundrect_rratio 0.25)
      (net 1 "GND") (pintype "passive"))
    (pad "2" smd roundrect (at 0.48 0 90) (size 0.59 0.64) (layers "B.Cu" "B.Paste" "B.Mask") (roundrect_rratio 0.25)
      (net 302 "/FPGA power supply/VCCA0") (pintype "passive"))
  )

  (footprint "antmicro-footprints:C_0402_1005Metric" (layer "B.Cu")
    (at 103.55 127.4 90)
    (descr "Capacitor SMD 0402")
    (tags "capacitor SMD 0402")
    (property "Author" "Antmicro")
    (property "Dielectric" "X7R")
    (property "License" "Apache-2.0")
    (property "MPN" "GRM155R71H103KA88D")
    (property "Manufacturer" "Murata")
    (property "Public" "False")
    (property "Sheetfile" "fpga-power-supply.kicad_sch")
    (property "Sheetname" "FPGA power supply")
    (property "Val" "10n")
    (property "Voltage" "50V")
    (property "ki_description" "SMD Multilayer Ceramic Capacitor, 10000 pF, 50 V, 0402 [1005 Metric], ± 10%, X7R, GRM Series")
    (property "ki_keywords" "0402, SMT, CAPACITOR, PASSIVE")
    (attr smd)
    (fp_text reference "C147" (at 22.8 -0.1 90) (layer "B.SilkS")
        (effects (font (size 0.7 0.7) (thickness 0.127)) (justify mirror))
    )
    (fp_text value "C_10n_0402" (at 0 -1.17 90) (layer "B.Fab")
        (effects (font (size 1 1) (thickness 0.15)) (justify mirror))
    )
    (fp_text user "Author: Antmicro" (at -0.939 -3.399 270) (layer "B.Fab") hide
        (effects (font (size 0.7 0.7) (thickness 0.15)) (justify left bottom mirror))
    )
    (fp_text user "License: Apache-2.0" (at -0.939 -5.799 270) (layer "B.Fab") hide
        (effects (font (size 0.7 0.7) (thickness 0.15)) (justify left bottom mirror))
    )
    (fp_text user "${REFERENCE}" (at 0 0 90) (layer "B.Fab")
        (effects (font (size 0.25 0.25) (thickness 0.04)) (justify mirror))
    )
    (fp_rect (start -0.925 0.47) (end 0.925 -0.47)
      (stroke (width 0.05) (type default)) (fill none) (layer "B.CrtYd"))
    (fp_line (start -0.494 -0.248) (end -0.494 0.25)
      (stroke (width 0.15) (type solid)) (layer "B.Fab"))
    (fp_line (start -0.494 0.25) (end 0.504 0.25)
      (stroke (width 0.15) (type solid)) (layer "B.Fab"))
    (fp_line (start 0.504 -0.248) (end -0.494 -0.248)
      (stroke (width 0.15) (type solid)) (layer "B.Fab"))
    (fp_line (start 0.504 0.25) (end 0.504 -0.248)
      (stroke (width 0.15) (type solid)) (layer "B.Fab"))
    (pad "1" smd roundrect (at -0.48 0 90) (size 0.59 0.64) (layers "B.Cu" "B.Paste" "B.Mask") (roundrect_rratio 0.25)
      (net 1 "GND") (pintype "passive"))
    (pad "2" smd roundrect (at 0.48 0 90) (size 0.59 0.64) (layers "B.Cu" "B.Paste" "B.Mask") (roundrect_rratio 0.25)
      (net 303 "/FPGA power supply/VCCA1") (pintype "passive"))
  )

  (footprint "antmicro-footprints:C_0402_1005Metric" (layer "B.Cu")
    (at 102.35 130.2 180)
    (descr "Capacitor SMD 0402")
    (tags "capacitor SMD 0402")
    (property "Author" "Antmicro")
    (property "Dielectric" "C0G")
    (property "License" "Apache-2.0")
    (property "MPN" "GRM1555C1H102JA01D")
    (property "Manufacturer" "Murata")
    (property "Public" "False")
    (property "Sheetfile" "fpga-power-supply.kicad_sch")
    (property "Sheetname" "FPGA power supply")
    (property "Val" "1n")
    (property "Voltage" "50V")
    (property "ki_description" "SMD Multilayer Ceramic Capacitor, 1000 pF, 50 V, 0402 [1005 Metric], ± 5%, C0G / NP0, GRM Series")
    (property "ki_keywords" "0402, SMT, CAPACITOR, PASSIVE, CERAMIC, MLCC")
    (attr smd)
    (fp_text reference "C148" (at -0.08 -20.805) (layer "B.SilkS")
        (effects (font (size 0.7 0.7) (thickness 0.127)) (justify mirror))
    )
    (fp_text value "C_1n_0402" (at 0 -1.17) (layer "B.Fab")
        (effects (font (size 1 1) (thickness 0.15)) (justify mirror))
    )
    (fp_text user "License: Apache-2.0" (at -0.939 -5.799) (layer "B.Fab") hide
        (effects (font (size 0.7 0.7) (thickness 0.15)) (justify left bottom mirror))
    )
    (fp_text user "${REFERENCE}" (at 0 0) (layer "B.Fab")
        (effects (font (size 0.25 0.25) (thickness 0.04)) (justify mirror))
    )
    (fp_text user "Author: Antmicro" (at -0.939 -3.399) (layer "B.Fab") hide
        (effects (font (size 0.7 0.7) (thickness 0.15)) (justify left bottom mirror))
    )
    (fp_rect (start -0.925 0.47) (end 0.925 -0.47)
      (stroke (width 0.05) (type default)) (fill none) (layer "B.CrtYd"))
    (fp_line (start -0.494 -0.248) (end -0.494 0.25)
      (stroke (width 0.15) (type solid)) (layer "B.Fab"))
    (fp_line (start -0.494 0.25) (end 0.504 0.25)
      (stroke (width 0.15) (type solid)) (layer "B.Fab"))
    (fp_line (start 0.504 -0.248) (end -0.494 -0.248)
      (stroke (width 0.15) (type solid)) (layer "B.Fab"))
    (fp_line (start 0.504 0.25) (end 0.504 -0.248)
      (stroke (width 0.15) (type solid)) (layer "B.Fab"))
    (pad "1" smd roundrect (at -0.48 0 180) (size 0.59 0.64) (layers "B.Cu" "B.Paste" "B.Mask") (roundrect_rratio 0.25)
      (net 1 "GND") (pintype "passive"))
    (pad "2" smd roundrect (at 0.48 0 180) (size 0.59 0.64) (layers "B.Cu" "B.Paste" "B.Mask") (roundrect_rratio 0.25)
      (net 302 "/FPGA power supply/VCCA0") (pintype "passive"))
  )

  (footprint "antmicro-footprints:C_0402_1005Metric" (layer "B.Cu")
    (at 106.55 127.4 90)
    (descr "Capacitor SMD 0402")
    (tags "capacitor SMD 0402")
    (property "Author" "Antmicro")
    (property "Dielectric" "C0G")
    (property "License" "Apache-2.0")
    (property "MPN" "GRM1555C1H102JA01D")
    (property "Manufacturer" "Murata")
    (property "Public" "False")
    (property "Sheetfile" "fpga-power-supply.kicad_sch")
    (property "Sheetname" "FPGA power supply")
    (property "Val" "1n")
    (property "Voltage" "50V")
    (property "ki_description" "SMD Multilayer Ceramic Capacitor, 1000 pF, 50 V, 0402 [1005 Metric], ± 5%, C0G / NP0, GRM Series")
    (property "ki_keywords" "0402, SMT, CAPACITOR, PASSIVE, CERAMIC, MLCC")
    (attr smd)
    (fp_text reference "C150" (at -20.765 1.13 90) (layer "B.SilkS")
        (effects (font (size 0.7 0.7) (thickness 0.127)) (justify mirror))
    )
    (fp_text value "C_1n_0402" (at 0 -1.17 90) (layer "B.Fab")
        (effects (font (size 1 1) (thickness 0.15)) (justify mirror))
    )
    (fp_text user "${REFERENCE}" (at 0 0 90) (layer "B.Fab")
        (effects (font (size 0.25 0.25) (thickness 0.04)) (justify mirror))
    )
    (fp_text user "License: Apache-2.0" (at -0.939 -5.799 270) (layer "B.Fab") hide
        (effects (font (size 0.7 0.7) (thickness 0.15)) (justify left bottom mirror))
    )
    (fp_text user "Author: Antmicro" (at -0.939 -3.399 270) (layer "B.Fab") hide
        (effects (font (size 0.7 0.7) (thickness 0.15)) (justify left bottom mirror))
    )
    (fp_rect (start -0.925 0.47) (end 0.925 -0.47)
      (stroke (width 0.05) (type default)) (fill none) (layer "B.CrtYd"))
    (fp_line (start -0.494 -0.248) (end -0.494 0.25)
      (stroke (width 0.15) (type solid)) (layer "B.Fab"))
    (fp_line (start -0.494 0.25) (end 0.504 0.25)
      (stroke (width 0.15) (type solid)) (layer "B.Fab"))
    (fp_line (start 0.504 -0.248) (end -0.494 -0.248)
      (stroke (width 0.15) (type solid)) (layer "B.Fab"))
    (fp_line (start 0.504 0.25) (end 0.504 -0.248)
      (stroke (width 0.15) (type solid)) (layer "B.Fab"))
    (pad "1" smd roundrect (at -0.48 0 90) (size 0.59 0.64) (layers "B.Cu" "B.Paste" "B.Mask") (roundrect_rratio 0.25)
      (net 1 "GND") (pintype "passive"))
    (pad "2" smd roundrect (at 0.48 0 90) (size 0.59 0.64) (layers "B.Cu" "B.Paste" "B.Mask") (roundrect_rratio 0.25)
      (net 302 "/FPGA power supply/VCCA0") (pintype "passive"))
  )

  (footprint "antmicro-footprints:C_0402_1005Metric" (layer "B.Cu")
    (at 107.55 127.4 90)
    (descr "Capacitor SMD 0402")
    (tags "capacitor SMD 0402")
    (property "Author" "Antmicro")
    (property "Dielectric" "C0G")
    (property "License" "Apache-2.0")
    (property "MPN" "GRM1555C1H102JA01D")
    (property "Manufacturer" "Murata")
    (property "Public" "False")
    (property "Sheetfile" "fpga-power-supply.kicad_sch")
    (property "Sheetname" "FPGA power supply")
    (property "Val" "1n")
    (property "Voltage" "50V")
    (property "ki_description" "SMD Multilayer Ceramic Capacitor, 1000 pF, 50 V, 0402 [1005 Metric], ± 5%, C0G / NP0, GRM Series")
    (property "ki_keywords" "0402, SMT, CAPACITOR, PASSIVE, CERAMIC, MLCC")
    (attr smd)
    (fp_text reference "C152" (at 22.8 0.05 90) (layer "B.SilkS")
        (effects (font (size 0.7 0.7) (thickness 0.127)) (justify mirror))
    )
    (fp_text value "C_1n_0402" (at 0 -1.17 90) (layer "B.Fab")
        (effects (font (size 1 1) (thickness 0.15)) (justify mirror))
    )
    (fp_text user "Author: Antmicro" (at -0.939 -3.399 270) (layer "B.Fab") hide
        (effects (font (size 0.7 0.7) (thickness 0.15)) (justify left bottom mirror))
    )
    (fp_text user "${REFERENCE}" (at 0 0 90) (layer "B.Fab")
        (effects (font (size 0.25 0.25) (thickness 0.04)) (justify mirror))
    )
    (fp_text user "License: Apache-2.0" (at -0.939 -5.799 270) (layer "B.Fab") hide
        (effects (font (size 0.7 0.7) (thickness 0.15)) (justify left bottom mirror))
    )
    (fp_rect (start -0.925 0.47) (end 0.925 -0.47)
      (stroke (width 0.05) (type default)) (fill none) (layer "B.CrtYd"))
    (fp_line (start -0.494 -0.248) (end -0.494 0.25)
      (stroke (width 0.15) (type solid)) (layer "B.Fab"))
    (fp_line (start -0.494 0.25) (end 0.504 0.25)
      (stroke (width 0.15) (type solid)) (layer "B.Fab"))
    (fp_line (start 0.504 -0.248) (end -0.494 -0.248)
      (stroke (width 0.15) (type solid)) (layer "B.Fab"))
    (fp_line (start 0.504 0.25) (end 0.504 -0.248)
      (stroke (width 0.15) (type solid)) (layer "B.Fab"))
    (pad "1" smd roundrect (at -0.48 0 90) (size 0.59 0.64) (layers "B.Cu" "B.Paste" "B.Mask") (roundrect_rratio 0.25)
      (net 1 "GND") (pintype "passive"))
    (pad "2" smd roundrect (at 0.48 0 90) (size 0.59 0.64) (layers "B.Cu" "B.Paste" "B.Mask") (roundrect_rratio 0.25)
      (net 303 "/FPGA power supply/VCCA1") (pintype "passive"))
  )

  (footprint "antmicro-footprints:C_0603_1608Metric" (layer "B.Cu")
    (at 104.4 120.945 -90)
    (descr "Capacitor SMD 0603")
    (tags "capacitor 0603")
    (property "Author" "Antmicro")
    (property "Dielectric" "")
    (property "License" "Apache-2.0")
    (property "MPN" "GRM188R60J476ME15D")
    (property "Manufacturer" "Murata")
    (property "Public" "False")
    (property "Sheetfile" "fpga-power-supply.kicad_sch")
    (property "Sheetname" "FPGA power supply")
    (property "Val" "47u")
    (property "Voltage" "")
    (property "ki_description" "SMD Multilayer Ceramic Capacitor, 47 µF, 6.3 V, 0603 [1608 Metric], ± 20%, X5R, GRM Series")
    (property "ki_keywords" "0603, SMT, CAPACITOR, PASSIVE, CERAMIC, MLCC")
    (attr smd)
    (fp_text reference "C154" (at 22.27 0.03 90) (layer "B.SilkS")
        (effects (font (size 0.7 0.7) (thickness 0.127)) (justify mirror))
    )
    (fp_text value "C_47u_0603" (at 0 -1.9 90) (layer "B.Fab")
        (effects (font (size 1 1) (thickness 0.15)) (justify mirror))
    )
    (fp_text user "${REFERENCE}" (at -1.682 -3.895 90) (layer "B.Fab") hide
        (effects (font (size 0.7 0.7) (thickness 0.15)) (justify left bottom mirror))
    )
    (fp_text user "Author: Antmicro" (at -1.682 -4.894 90) (layer "B.Fab") hide
        (effects (font (size 0.7 0.7) (thickness 0.15)) (justify left bottom mirror))
    )
    (fp_text user "License: Apache-2.0" (at -1.682 -5.895 90) (layer "B.Fab") hide
        (effects (font (size 0.7 0.7) (thickness 0.15)) (justify left bottom mirror))
    )
    (fp_line (start -0.15 -0.4) (end 0.15 -0.4)
      (stroke (width 0.15) (type solid)) (layer "B.SilkS"))
    (fp_line (start -0.15 0.4) (end 0.15 0.4)
      (stroke (width 0.15) (type solid)) (layer "B.SilkS"))
    (fp_rect (start -1.25 0.65) (end 1.25 -0.65)
      (stroke (width 0.05) (type solid)) (fill none) (layer "B.CrtYd"))
    (fp_rect (start -0.8 0.4) (end 0.8 -0.4)
      (stroke (width 0.15) (type solid)) (fill none) (layer "B.Fab"))
    (pad "1" smd roundrect (at -0.7 0 270) (size 0.8 1) (layers "B.Cu" "B.Paste" "B.Mask") (roundrect_rratio 0.2)
      (net 211 "VCC1V2") (pintype "passive"))
    (pad "2" smd roundrect (at 0.7 0 270) (size 0.8 1) (layers "B.Cu" "B.Paste" "B.Mask") (roundrect_rratio 0.2)
      (net 1 "GND") (pintype "passive"))
  )

  (footprint "antmicro-footprints:C_0603_1608Metric" (layer "B.Cu")
    (at 109.4 132.55 90)
    (descr "Capacitor SMD 0603")
    (tags "capacitor 0603")
    (property "Author" "Antmicro")
    (property "Dielectric" "")
    (property "License" "Apache-2.0")
    (property "MPN" "GRM188R60J476ME15D")
    (property "Manufacturer" "Murata")
    (property "Public" "False")
    (property "Sheetfile" "fpga-power-supply.kicad_sch")
    (property "Sheetname" "FPGA power supply")
    (property "Val" "47u")
    (property "Voltage" "")
    (property "ki_description" "SMD Multilayer Ceramic Capacitor, 47 µF, 6.3 V, 0603 [1608 Metric], ± 20%, X5R, GRM Series")
    (property "ki_keywords" "0603, SMT, CAPACITOR, PASSIVE, CERAMIC, MLCC")
    (attr smd)
    (fp_text reference "C157" (at -20.465 0.32 90) (layer "B.SilkS")
        (effects (font (size 0.7 0.7) (thickness 0.127)) (justify mirror))
    )
    (fp_text value "C_47u_0603" (at 0 -1.9 90) (layer "B.Fab")
        (effects (font (size 1 1) (thickness 0.15)) (justify mirror))
    )
    (fp_text user "Author: Antmicro" (at -1.682 -4.894 270) (layer "B.Fab") hide
        (effects (font (size 0.7 0.7) (thickness 0.15)) (justify left bottom mirror))
    )
    (fp_text user "${REFERENCE}" (at -1.682 -3.895 270) (layer "B.Fab") hide
        (effects (font (size 0.7 0.7) (thickness 0.15)) (justify left bottom mirror))
    )
    (fp_text user "License: Apache-2.0" (at -1.682 -5.895 270) (layer "B.Fab") hide
        (effects (font (size 0.7 0.7) (thickness 0.15)) (justify left bottom mirror))
    )
    (fp_line (start -0.15 -0.4) (end 0.15 -0.4)
      (stroke (width 0.15) (type solid)) (layer "B.SilkS"))
    (fp_line (start -0.15 0.4) (end 0.15 0.4)
      (stroke (width 0.15) (type solid)) (layer "B.SilkS"))
    (fp_rect (start -1.25 0.65) (end 1.25 -0.65)
      (stroke (width 0.05) (type solid)) (fill none) (layer "B.CrtYd"))
    (fp_rect (start -0.8 0.4) (end 0.8 -0.4)
      (stroke (width 0.15) (type solid)) (fill none) (layer "B.Fab"))
    (pad "1" smd roundrect (at -0.7 0 90) (size 0.8 1) (layers "B.Cu" "B.Paste" "B.Mask") (roundrect_rratio 0.2)
      (net 1 "GND") (pintype "passive"))
    (pad "2" smd roundrect (at 0.7 0 90) (size 0.8 1) (layers "B.Cu" "B.Paste" "B.Mask") (roundrect_rratio 0.2)
      (net 303 "/FPGA power supply/VCCA1") (pintype "passive"))
  )

  (footprint "antmicro-footprints:C_0603_1608Metric" (layer "B.Cu")
    (at 112.4 132.55 90)
    (descr "Capacitor SMD 0603")
    (tags "capacitor 0603")
    (property "Author" "Antmicro")
    (property "Dielectric" "")
    (property "License" "Apache-2.0")
    (property "MPN" "GRM188R60J476ME15D")
    (property "Manufacturer" "Murata")
    (property "Public" "False")
    (property "Sheetfile" "fpga-power-supply.kicad_sch")
    (property "Sheetname" "FPGA power supply")
    (property "Val" "47u")
    (property "Voltage" "")
    (property "ki_description" "SMD Multilayer Ceramic Capacitor, 47 µF, 6.3 V, 0603 [1608 Metric], ± 20%, X5R, GRM Series")
    (property "ki_keywords" "0603, SMT, CAPACITOR, PASSIVE, CERAMIC, MLCC")
    (attr smd)
    (fp_text reference "C155" (at -20.545 -0.99 90) (layer "B.SilkS")
        (effects (font (size 0.7 0.7) (thickness 0.127)) (justify mirror))
    )
    (fp_text value "C_47u_0603" (at 0 -1.9 90) (layer "B.Fab")
        (effects (font (size 1 1) (thickness 0.15)) (justify mirror))
    )
    (fp_text user "${REFERENCE}" (at -1.682 -3.895 270) (layer "B.Fab") hide
        (effects (font (size 0.7 0.7) (thickness 0.15)) (justify left bottom mirror))
    )
    (fp_text user "License: Apache-2.0" (at -1.682 -5.895 270) (layer "B.Fab") hide
        (effects (font (size 0.7 0.7) (thickness 0.15)) (justify left bottom mirror))
    )
    (fp_text user "Author: Antmicro" (at -1.682 -4.894 270) (layer "B.Fab") hide
        (effects (font (size 0.7 0.7) (thickness 0.15)) (justify left bottom mirror))
    )
    (fp_line (start -0.15 -0.4) (end 0.15 -0.4)
      (stroke (width 0.15) (type solid)) (layer "B.SilkS"))
    (fp_line (start -0.15 0.4) (end 0.15 0.4)
      (stroke (width 0.15) (type solid)) (layer "B.SilkS"))
    (fp_rect (start -1.25 0.65) (end 1.25 -0.65)
      (stroke (width 0.05) (type solid)) (fill none) (layer "B.CrtYd"))
    (fp_rect (start -0.8 0.4) (end 0.8 -0.4)
      (stroke (width 0.15) (type solid)) (fill none) (layer "B.Fab"))
    (pad "1" smd roundrect (at -0.7 0 90) (size 0.8 1) (layers "B.Cu" "B.Paste" "B.Mask") (roundrect_rratio 0.2)
      (net 1 "GND") (pintype "passive"))
    (pad "2" smd roundrect (at 0.7 0 90) (size 0.8 1) (layers "B.Cu" "B.Paste" "B.Mask") (roundrect_rratio 0.2)
      (net 304 "/FPGA power supply/VCCAUX") (pintype "passive"))
  )

  (footprint "antmicro-footprints:C_0402_1005Metric" (layer "B.Cu")
    (at 96.4 127.75 180)
    (descr "Capacitor SMD 0402")
    (tags "capacitor SMD 0402")
    (property "Author" "Antmicro")
    (property "Dielectric" "")
    (property "License" "Apache-2.0")
    (property "MPN" "GRM155R61A475MEAAD")
    (property "Manufacturer" "Murata")
    (property "Public" "False")
    (property "Sheetfile" "fpga-power-supply.kicad_sch")
    (property "Sheetname" "FPGA power supply")
    (property "Val" "4u7")
    (property "Voltage" "")
    (property "ki_description" "SMD Multilayer Ceramic Capacitor, 4.7 µF, 10 V, 0402 [1005 Metric], ± 20%, X5R, GRM Series")
    (property "ki_keywords" "0402, SMT, CAPACITOR, PASSIVE")
    (attr smd)
    (fp_text reference "C156" (at 2.45 0) (layer "B.SilkS")
        (effects (font (size 0.7 0.7) (thickness 0.127)) (justify mirror))
    )
    (fp_text value "C_4u7_0402" (at 0 -1.17) (layer "B.Fab")
        (effects (font (size 1 1) (thickness 0.15)) (justify mirror))
    )
    (fp_text user "License: Apache-2.0" (at -0.939 -5.799) (layer "B.Fab") hide
        (effects (font (size 0.7 0.7) (thickness 0.15)) (justify left bottom mirror))
    )
    (fp_text user "${REFERENCE}" (at 0 0) (layer "B.Fab")
        (effects (font (size 0.25 0.25) (thickness 0.04)) (justify mirror))
    )
    (fp_text user "Author: Antmicro" (at -0.939 -3.399) (layer "B.Fab") hide
        (effects (font (size 0.7 0.7) (thickness 0.15)) (justify left bottom mirror))
    )
    (fp_rect (start -0.925 0.47) (end 0.925 -0.47)
      (stroke (width 0.05) (type default)) (fill none) (layer "B.CrtYd"))
    (fp_line (start -0.494 -0.248) (end -0.494 0.25)
      (stroke (width 0.15) (type solid)) (layer "B.Fab"))
    (fp_line (start -0.494 0.25) (end 0.504 0.25)
      (stroke (width 0.15) (type solid)) (layer "B.Fab"))
    (fp_line (start 0.504 -0.248) (end -0.494 -0.248)
      (stroke (width 0.15) (type solid)) (layer "B.Fab"))
    (fp_line (start 0.504 0.25) (end 0.504 -0.248)
      (stroke (width 0.15) (type solid)) (layer "B.Fab"))
    (pad "1" smd roundrect (at -0.48 0 180) (size 0.59 0.64) (layers "B.Cu" "B.Paste" "B.Mask") (roundrect_rratio 0.25)
      (net 211 "VCC1V2") (pintype "passive"))
    (pad "2" smd roundrect (at 0.48 0 180) (size 0.59 0.64) (layers "B.Cu" "B.Paste" "B.Mask") (roundrect_rratio 0.25)
      (net 1 "GND") (pintype "passive"))
  )

  (footprint "antmicro-footprints:C_0402_1005Metric" (layer "B.Cu")
    (at 108.1 132.25 90)
    (descr "Capacitor SMD 0402")
    (tags "capacitor SMD 0402")
    (property "Author" "Antmicro")
    (property "Dielectric" "")
    (property "License" "Apache-2.0")
    (property "MPN" "GRM155R61A475MEAAD")
    (property "Manufacturer" "Murata")
    (property "Public" "False")
    (property "Sheetfile" "fpga-power-supply.kicad_sch")
    (property "Sheetname" "FPGA power supply")
    (property "Val" "4u7")
    (property "Voltage" "")
    (property "ki_description" "SMD Multilayer Ceramic Capacitor, 4.7 µF, 10 V, 0402 [1005 Metric], ± 20%, X5R, GRM Series")
    (property "ki_keywords" "0402, SMT, CAPACITOR, PASSIVE")
    (attr smd)
    (fp_text reference "C160" (at -20.845 0.75 90) (layer "B.SilkS")
        (effects (font (size 0.7 0.7) (thickness 0.127)) (justify mirror))
    )
    (fp_text value "C_4u7_0402" (at 0 -1.17 90) (layer "B.Fab")
        (effects (font (size 1 1) (thickness 0.15)) (justify mirror))
    )
    (fp_text user "Author: Antmicro" (at -0.939 -3.399 270) (layer "B.Fab") hide
        (effects (font (size 0.7 0.7) (thickness 0.15)) (justify left bottom mirror))
    )
    (fp_text user "License: Apache-2.0" (at -0.939 -5.799 270) (layer "B.Fab") hide
        (effects (font (size 0.7 0.7) (thickness 0.15)) (justify left bottom mirror))
    )
    (fp_text user "${REFERENCE}" (at 0 0 90) (layer "B.Fab")
        (effects (font (size 0.25 0.25) (thickness 0.04)) (justify mirror))
    )
    (fp_rect (start -0.925 0.47) (end 0.925 -0.47)
      (stroke (width 0.05) (type default)) (fill none) (layer "B.CrtYd"))
    (fp_line (start -0.494 -0.248) (end -0.494 0.25)
      (stroke (width 0.15) (type solid)) (layer "B.Fab"))
    (fp_line (start -0.494 0.25) (end 0.504 0.25)
      (stroke (width 0.15) (type solid)) (layer "B.Fab"))
    (fp_line (start 0.504 -0.248) (end -0.494 -0.248)
      (stroke (width 0.15) (type solid)) (layer "B.Fab"))
    (fp_line (start 0.504 0.25) (end 0.504 -0.248)
      (stroke (width 0.15) (type solid)) (layer "B.Fab"))
    (pad "1" smd roundrect (at -0.48 0 90) (size 0.59 0.64) (layers "B.Cu" "B.Paste" "B.Mask") (roundrect_rratio 0.25)
      (net 1 "GND") (pintype "passive"))
    (pad "2" smd roundrect (at 0.48 0 90) (size 0.59 0.64) (layers "B.Cu" "B.Paste" "B.Mask") (roundrect_rratio 0.25)
      (net 303 "/FPGA power supply/VCCA1") (pintype "passive"))
  )

  (footprint "antmicro-footprints:C_0402_1005Metric" (layer "B.Cu")
    (at 110.7 132.2 90)
    (descr "Capacitor SMD 0402")
    (tags "capacitor SMD 0402")
    (property "Author" "Antmicro")
    (property "Dielectric" "")
    (property "License" "Apache-2.0")
    (property "MPN" "GRM155R61A475MEAAD")
    (property "Manufacturer" "Murata")
    (property "Public" "False")
    (property "Sheetfile" "fpga-power-supply.kicad_sch")
    (property "Sheetname" "FPGA power supply")
    (property "Val" "4u7")
    (property "Voltage" "")
    (property "ki_description" "SMD Multilayer Ceramic Capacitor, 4.7 µF, 10 V, 0402 [1005 Metric], ± 20%, X5R, GRM Series")
    (property "ki_keywords" "0402, SMT, CAPACITOR, PASSIVE")
    (attr smd)
    (fp_text reference "C158" (at -20.875 -0.13 90) (layer "B.SilkS")
        (effects (font (size 0.7 0.7) (thickness 0.127)) (justify mirror))
    )
    (fp_text value "C_4u7_0402" (at 0 -1.17 90) (layer "B.Fab")
        (effects (font (size 1 1) (thickness 0.15)) (justify mirror))
    )
    (fp_text user "Author: Antmicro" (at -0.939 -3.399 270) (layer "B.Fab") hide
        (effects (font (size 0.7 0.7) (thickness 0.15)) (justify left bottom mirror))
    )
    (fp_text user "${REFERENCE}" (at 0 0 90) (layer "B.Fab")
        (effects (font (size 0.25 0.25) (thickness 0.04)) (justify mirror))
    )
    (fp_text user "License: Apache-2.0" (at -0.939 -5.799 270) (layer "B.Fab") hide
        (effects (font (size 0.7 0.7) (thickness 0.15)) (justify left bottom mirror))
    )
    (fp_rect (start -0.925 0.47) (end 0.925 -0.47)
      (stroke (width 0.05) (type default)) (fill none) (layer "B.CrtYd"))
    (fp_line (start -0.494 -0.248) (end -0.494 0.25)
      (stroke (width 0.15) (type solid)) (layer "B.Fab"))
    (fp_line (start -0.494 0.25) (end 0.504 0.25)
      (stroke (width 0.15) (type solid)) (layer "B.Fab"))
    (fp_line (start 0.504 -0.248) (end -0.494 -0.248)
      (stroke (width 0.15) (type solid)) (layer "B.Fab"))
    (fp_line (start 0.504 0.25) (end 0.504 -0.248)
      (stroke (width 0.15) (type solid)) (layer "B.Fab"))
    (pad "1" smd roundrect (at -0.48 0 90) (size 0.59 0.64) (layers "B.Cu" "B.Paste" "B.Mask") (roundrect_rratio 0.25)
      (net 1 "GND") (pintype "passive"))
    (pad "2" smd roundrect (at 0.48 0 90) (size 0.59 0.64) (layers "B.Cu" "B.Paste" "B.Mask") (roundrect_rratio 0.25)
      (net 304 "/FPGA power supply/VCCAUX") (pintype "passive"))
  )

  (footprint "antmicro-footprints:C_0402_1005Metric" (layer "B.Cu")
    (at 112.75 126.3 90)
    (descr "Capacitor SMD 0402")
    (tags "capacitor SMD 0402")
    (property "Author" "Antmicro")
    (property "Dielectric" "")
    (property "License" "Apache-2.0")
    (property "MPN" "GRM155R61A475MEAAD")
    (property "Manufacturer" "Murata")
    (property "Public" "False")
    (property "Sheetfile" "fpga-power-supply.kicad_sch")
    (property "Sheetname" "FPGA power supply")
    (property "Val" "4u7")
    (property "Voltage" "")
    (property "ki_description" "SMD Multilayer Ceramic Capacitor, 4.7 µF, 10 V, 0402 [1005 Metric], ± 20%, X5R, GRM Series")
    (property "ki_keywords" "0402, SMT, CAPACITOR, PASSIVE")
    (attr smd)
    (fp_text reference "C159" (at -0.25 3.8 90) (layer "B.SilkS")
        (effects (font (size 0.7 0.7) (thickness 0.127)) (justify mirror))
    )
    (fp_text value "C_4u7_0402" (at 0 -1.17 90) (layer "B.Fab")
        (effects (font (size 1 1) (thickness 0.15)) (justify mirror))
    )
    (fp_text user "Author: Antmicro" (at -0.939 -3.399 270) (layer "B.Fab") hide
        (effects (font (size 0.7 0.7) (thickness 0.15)) (justify left bottom mirror))
    )
    (fp_text user "${REFERENCE}" (at 0 0 90) (layer "B.Fab")
        (effects (font (size 0.25 0.25) (thickness 0.04)) (justify mirror))
    )
    (fp_text user "License: Apache-2.0" (at -0.939 -5.799 270) (layer "B.Fab") hide
        (effects (font (size 0.7 0.7) (thickness 0.15)) (justify left bottom mirror))
    )
    (fp_rect (start -0.925 0.47) (end 0.925 -0.47)
      (stroke (width 0.05) (type default)) (fill none) (layer "B.CrtYd"))
    (fp_line (start -0.494 -0.248) (end -0.494 0.25)
      (stroke (width 0.15) (type solid)) (layer "B.Fab"))
    (fp_line (start -0.494 0.25) (end 0.504 0.25)
      (stroke (width 0.15) (type solid)) (layer "B.Fab"))
    (fp_line (start 0.504 -0.248) (end -0.494 -0.248)
      (stroke (width 0.15) (type solid)) (layer "B.Fab"))
    (fp_line (start 0.504 0.25) (end 0.504 -0.248)
      (stroke (width 0.15) (type solid)) (layer "B.Fab"))
    (pad "1" smd roundrect (at -0.48 0 90) (size 0.59 0.64) (layers "B.Cu" "B.Paste" "B.Mask") (roundrect_rratio 0.25)
      (net 211 "VCC1V2") (pintype "passive"))
    (pad "2" smd roundrect (at 0.48 0 90) (size 0.59 0.64) (layers "B.Cu" "B.Paste" "B.Mask") (roundrect_rratio 0.25)
      (net 1 "GND") (pintype "passive"))
  )

  (footprint "antmicro-footprints:C_0402_1005Metric" (layer "B.Cu")
    (at 107.05 132.25 90)
    (descr "Capacitor SMD 0402")
    (tags "capacitor SMD 0402")
    (property "Author" "Antmicro")
    (property "Dielectric" "")
    (property "License" "Apache-2.0")
    (property "MPN" "C1005X5R1E474M050BB")
    (property "Manufacturer" "TDK")
    (property "Public" "False")
    (property "Sheetfile" "fpga-power-supply.kicad_sch")
    (property "Sheetname" "FPGA power supply")
    (property "Val" "470n")
    (property "Voltage" "")
    (property "ki_description" "SMD Multilayer Ceramic Capacitor, 0.47 µF, 25 V, 0402 [1005 Metric], ± 20%, X5R, C")
    (property "ki_keywords" "0402, SMT, CAPACITOR, PASSIVE, CERAMIC, MLCC")
    (attr smd)
    (fp_text reference "C163" (at -20.845 0.87 90) (layer "B.SilkS")
        (effects (font (size 0.7 0.7) (thickness 0.127)) (justify mirror))
    )
    (fp_text value "C_470n_0402" (at 0 -1.17 90) (layer "B.Fab")
        (effects (font (size 1 1) (thickness 0.15)) (justify mirror))
    )
    (fp_text user "${REFERENCE}" (at 0 0 90) (layer "B.Fab")
        (effects (font (size 0.25 0.25) (thickness 0.04)) (justify mirror))
    )
    (fp_text user "Author: Antmicro" (at -0.939 -3.399 270) (layer "B.Fab") hide
        (effects (font (size 0.7 0.7) (thickness 0.15)) (justify left bottom mirror))
    )
    (fp_text user "License: Apache-2.0" (at -0.939 -5.799 270) (layer "B.Fab") hide
        (effects (font (size 0.7 0.7) (thickness 0.15)) (justify left bottom mirror))
    )
    (fp_rect (start -0.925 0.47) (end 0.925 -0.47)
      (stroke (width 0.05) (type default)) (fill none) (layer "B.CrtYd"))
    (fp_line (start -0.494 -0.248) (end -0.494 0.25)
      (stroke (width 0.15) (type solid)) (layer "B.Fab"))
    (fp_line (start -0.494 0.25) (end 0.504 0.25)
      (stroke (width 0.15) (type solid)) (layer "B.Fab"))
    (fp_line (start 0.504 -0.248) (end -0.494 -0.248)
      (stroke (width 0.15) (type solid)) (layer "B.Fab"))
    (fp_line (start 0.504 0.25) (end 0.504 -0.248)
      (stroke (width 0.15) (type solid)) (layer "B.Fab"))
    (pad "1" smd roundrect (at -0.48 0 90) (size 0.59 0.64) (layers "B.Cu" "B.Paste" "B.Mask") (roundrect_rratio 0.25)
      (net 1 "GND") (pintype "passive"))
    (pad "2" smd roundrect (at 0.48 0 90) (size 0.59 0.64) (layers "B.Cu" "B.Paste" "B.Mask") (roundrect_rratio 0.25)
      (net 303 "/FPGA power supply/VCCA1") (pintype "passive"))
  )

  (footprint "antmicro-footprints:C_0402_1005Metric" (layer "B.Cu")
    (at 97.6 117.135714)
    (descr "Capacitor SMD 0402")
    (tags "capacitor SMD 0402")
    (property "Author" "Antmicro")
    (property "Dielectric" "")
    (property "License" "Apache-2.0")
    (property "MPN" "C1005X5R1E474M050BB")
    (property "Manufacturer" "TDK")
    (property "Public" "False")
    (property "Sheetfile" "fpga-power-supply.kicad_sch")
    (property "Sheetname" "FPGA power supply")
    (property "Val" "470n")
    (property "Voltage" "")
    (property "ki_description" "SMD Multilayer Ceramic Capacitor, 0.47 µF, 25 V, 0402 [1005 Metric], ± 20%, X5R, C")
    (property "ki_keywords" "0402, SMT, CAPACITOR, PASSIVE, CERAMIC, MLCC")
    (attr smd)
    (fp_text reference "C161" (at -2.58 -0.190714) (layer "B.SilkS")
        (effects (font (size 0.7 0.7) (thickness 0.127)) (justify mirror))
    )
    (fp_text value "C_470n_0402" (at 0 -1.17) (layer "B.Fab")
        (effects (font (size 1 1) (thickness 0.15)) (justify mirror))
    )
    (fp_text user "Author: Antmicro" (at -0.939 -3.399 180) (layer "B.Fab") hide
        (effects (font (size 0.7 0.7) (thickness 0.15)) (justify left bottom mirror))
    )
    (fp_text user "${REFERENCE}" (at 0 0) (layer "B.Fab")
        (effects (font (size 0.25 0.25) (thickness 0.04)) (justify mirror))
    )
    (fp_text user "License: Apache-2.0" (at -0.939 -5.799 180) (layer "B.Fab") hide
        (effects (font (size 0.7 0.7) (thickness 0.15)) (justify left bottom mirror))
    )
    (fp_rect (start -0.925 0.47) (end 0.925 -0.47)
      (stroke (width 0.05) (type default)) (fill none) (layer "B.CrtYd"))
    (fp_line (start -0.494 -0.248) (end -0.494 0.25)
      (stroke (width 0.15) (type solid)) (layer "B.Fab"))
    (fp_line (start -0.494 0.25) (end 0.504 0.25)
      (stroke (width 0.15) (type solid)) (layer "B.Fab"))
    (fp_line (start 0.504 -0.248) (end -0.494 -0.248)
      (stroke (width 0.15) (type solid)) (layer "B.Fab"))
    (fp_line (start 0.504 0.25) (end 0.504 -0.248)
      (stroke (width 0.15) (type solid)) (layer "B.Fab"))
    (pad "1" smd roundrect (at -0.48 0) (size 0.59 0.64) (layers "B.Cu" "B.Paste" "B.Mask") (roundrect_rratio 0.25)
      (net 1 "GND") (pintype "passive"))
    (pad "2" smd roundrect (at 0.48 0) (size 0.59 0.64) (layers "B.Cu" "B.Paste" "B.Mask") (roundrect_rratio 0.25)
      (net 304 "/FPGA power supply/VCCAUX") (pintype "passive"))
  )

  (footprint "antmicro-footprints:C_0402_1005Metric" (layer "B.Cu")
    (at 107.2 122 180)
    (descr "Capacitor SMD 0402")
    (tags "capacitor SMD 0402")
    (property "Author" "Antmicro")
    (property "Dielectric" "")
    (property "License" "Apache-2.0")
    (property "MPN" "C1005X5R1E474M050BB")
    (property "Manufacturer" "TDK")
    (property "Public" "False")
    (property "Sheetfile" "fpga-power-supply.kicad_sch")
    (property "Sheetname" "FPGA power supply")
    (property "Val" "470n")
    (property "Voltage" "")
    (property "ki_description" "SMD Multilayer Ceramic Capacitor, 0.47 µF, 25 V, 0402 [1005 Metric], ± 20%, X5R, C")
    (property "ki_keywords" "0402, SMT, CAPACITOR, PASSIVE, CERAMIC, MLCC")
    (attr smd)
    (fp_text reference "C162" (at 0.71 -22.315) (layer "B.SilkS")
        (effects (font (size 0.7 0.7) (thickness 0.127)) (justify mirror))
    )
    (fp_text value "C_470n_0402" (at 0 -1.17) (layer "B.Fab")
        (effects (font (size 1 1) (thickness 0.15)) (justify mirror))
    )
    (fp_text user "${REFERENCE}" (at 0 0) (layer "B.Fab")
        (effects (font (size 0.25 0.25) (thickness 0.04)) (justify mirror))
    )
    (fp_text user "Author: Antmicro" (at -0.939 -3.399) (layer "B.Fab") hide
        (effects (font (size 0.7 0.7) (thickness 0.15)) (justify left bottom mirror))
    )
    (fp_text user "License: Apache-2.0" (at -0.939 -5.799) (layer "B.Fab") hide
        (effects (font (size 0.7 0.7) (thickness 0.15)) (justify left bottom mirror))
    )
    (fp_rect (start -0.925 0.47) (end 0.925 -0.47)
      (stroke (width 0.05) (type default)) (fill none) (layer "B.CrtYd"))
    (fp_line (start -0.494 -0.248) (end -0.494 0.25)
      (stroke (width 0.15) (type solid)) (layer "B.Fab"))
    (fp_line (start -0.494 0.25) (end 0.504 0.25)
      (stroke (width 0.15) (type solid)) (layer "B.Fab"))
    (fp_line (start 0.504 -0.248) (end -0.494 -0.248)
      (stroke (width 0.15) (type solid)) (layer "B.Fab"))
    (fp_line (start 0.504 0.25) (end 0.504 -0.248)
      (stroke (width 0.15) (type solid)) (layer "B.Fab"))
    (pad "1" smd roundrect (at -0.48 0 180) (size 0.59 0.64) (layers "B.Cu" "B.Paste" "B.Mask") (roundrect_rratio 0.25)
      (net 211 "VCC1V2") (pintype "passive"))
    (pad "2" smd roundrect (at 0.48 0 180) (size 0.59 0.64) (layers "B.Cu" "B.Paste" "B.Mask") (roundrect_rratio 0.25)
      (net 1 "GND") (pintype "passive"))
  )

  (footprint "antmicro-footprints:C_0402_1005Metric" (layer "B.Cu")
    (at 100.75 113.8 -90)
    (descr "Capacitor SMD 0402")
    (tags "capacitor SMD 0402")
    (property "Author" "Antmicro")
    (property "Dielectric" "")
    (property "License" "Apache-2.0")
    (property "MPN" "C1005X5R1E474M050BB")
    (property "Manufacturer" "TDK")
    (property "Public" "False")
    (property "Sheetfile" "fpga-power-supply.kicad_sch")
    (property "Sheetname" "FPGA power supply")
    (property "Val" "470n")
    (property "Voltage" "")
    (property "ki_description" "SMD Multilayer Ceramic Capacitor, 0.47 µF, 25 V, 0402 [1005 Metric], ± 20%, X5R, C")
    (property "ki_keywords" "0402, SMT, CAPACITOR, PASSIVE, CERAMIC, MLCC")
    (attr smd)
    (fp_text reference "C164" (at -2.795 -0.01 90) (layer "B.SilkS")
        (effects (font (size 0.7 0.7) (thickness 0.127)) (justify mirror))
    )
    (fp_text value "C_470n_0402" (at 0 -1.17 90) (layer "B.Fab")
        (effects (font (size 1 1) (thickness 0.15)) (justify mirror))
    )
    (fp_text user "${REFERENCE}" (at 0 0 90) (layer "B.Fab")
        (effects (font (size 0.25 0.25) (thickness 0.04)) (justify mirror))
    )
    (fp_text user "Author: Antmicro" (at -0.939 -3.399 90) (layer "B.Fab") hide
        (effects (font (size 0.7 0.7) (thickness 0.15)) (justify left bottom mirror))
    )
    (fp_text user "License: Apache-2.0" (at -0.939 -5.799 90) (layer "B.Fab") hide
        (effects (font (size 0.7 0.7) (thickness 0.15)) (justify left bottom mirror))
    )
    (fp_rect (start -0.925 0.47) (end 0.925 -0.47)
      (stroke (width 0.05) (type default)) (fill none) (layer "B.CrtYd"))
    (fp_line (start -0.494 -0.248) (end -0.494 0.25)
      (stroke (width 0.15) (type solid)) (layer "B.Fab"))
    (fp_line (start -0.494 0.25) (end 0.504 0.25)
      (stroke (width 0.15) (type solid)) (layer "B.Fab"))
    (fp_line (start 0.504 -0.248) (end -0.494 -0.248)
      (stroke (width 0.15) (type solid)) (layer "B.Fab"))
    (fp_line (start 0.504 0.25) (end 0.504 -0.248)
      (stroke (width 0.15) (type solid)) (layer "B.Fab"))
    (pad "1" smd roundrect (at -0.48 0 270) (size 0.59 0.64) (layers "B.Cu" "B.Paste" "B.Mask") (roundrect_rratio 0.25)
      (net 1 "GND") (pintype "passive"))
    (pad "2" smd roundrect (at 0.48 0 270) (size 0.59 0.64) (layers "B.Cu" "B.Paste" "B.Mask") (roundrect_rratio 0.25)
      (net 304 "/FPGA power supply/VCCAUX") (pintype "passive"))
  )

  (footprint "antmicro-footprints:C_0402_1005Metric" (layer "B.Cu")
    (at 107.15 120.45 180)
    (descr "Capacitor SMD 0402")
    (tags "capacitor SMD 0402")
    (property "Author" "Antmicro")
    (property "Dielectric" "")
    (property "License" "Apache-2.0")
    (property "MPN" "C1005X5R1E474M050BB")
    (property "Manufacturer" "TDK")
    (property "Public" "False")
    (property "Sheetfile" "fpga-power-supply.kicad_sch")
    (property "Sheetname" "FPGA power supply")
    (property "Val" "470n")
    (property "Voltage" "")
    (property "ki_description" "SMD Multilayer Ceramic Capacitor, 0.47 µF, 25 V, 0402 [1005 Metric], ± 20%, X5R, C")
    (property "ki_keywords" "0402, SMT, CAPACITOR, PASSIVE, CERAMIC, MLCC")
    (attr smd)
    (fp_text reference "C165" (at 0.6 -22.9) (layer "B.SilkS")
        (effects (font (size 0.7 0.7) (thickness 0.127)) (justify mirror))
    )
    (fp_text value "C_470n_0402" (at 0 -1.17) (layer "B.Fab")
        (effects (font (size 1 1) (thickness 0.15)) (justify mirror))
    )
    (fp_text user "Author: Antmicro" (at -0.939 -3.399) (layer "B.Fab") hide
        (effects (font (size 0.7 0.7) (thickness 0.15)) (justify left bottom mirror))
    )
    (fp_text user "License: Apache-2.0" (at -0.939 -5.799) (layer "B.Fab") hide
        (effects (font (size 0.7 0.7) (thickness 0.15)) (justify left bottom mirror))
    )
    (fp_text user "${REFERENCE}" (at 0 0) (layer "B.Fab")
        (effects (font (size 0.25 0.25) (thickness 0.04)) (justify mirror))
    )
    (fp_rect (start -0.925 0.47) (end 0.925 -0.47)
      (stroke (width 0.05) (type default)) (fill none) (layer "B.CrtYd"))
    (fp_line (start -0.494 -0.248) (end -0.494 0.25)
      (stroke (width 0.15) (type solid)) (layer "B.Fab"))
    (fp_line (start -0.494 0.25) (end 0.504 0.25)
      (stroke (width 0.15) (type solid)) (layer "B.Fab"))
    (fp_line (start 0.504 -0.248) (end -0.494 -0.248)
      (stroke (width 0.15) (type solid)) (layer "B.Fab"))
    (fp_line (start 0.504 0.25) (end 0.504 -0.248)
      (stroke (width 0.15) (type solid)) (layer "B.Fab"))
    (pad "1" smd roundrect (at -0.48 0 180) (size 0.59 0.64) (layers "B.Cu" "B.Paste" "B.Mask") (roundrect_rratio 0.25)
      (net 211 "VCC1V2") (pintype "passive"))
    (pad "2" smd roundrect (at 0.48 0 180) (size 0.59 0.64) (layers "B.Cu" "B.Paste" "B.Mask") (roundrect_rratio 0.25)
      (net 1 "GND") (pintype "passive"))
  )

  (footprint "antmicro-footprints:C_0402_1005Metric" (layer "B.Cu")
    (at 112.45 130 90)
    (descr "Capacitor SMD 0402")
    (tags "capacitor SMD 0402")
    (property "Author" "Antmicro")
    (property "Dielectric" "")
    (property "License" "Apache-2.0")
    (property "MPN" "C1005X5R1E474M050BB")
    (property "Manufacturer" "TDK")
    (property "Public" "False")
    (property "Sheetfile" "fpga-power-supply.kicad_sch")
    (property "Sheetname" "FPGA power supply")
    (property "Val" "470n")
    (property "Voltage" "")
    (property "ki_description" "SMD Multilayer Ceramic Capacitor, 0.47 µF, 25 V, 0402 [1005 Metric], ± 20%, X5R, C")
    (property "ki_keywords" "0402, SMT, CAPACITOR, PASSIVE, CERAMIC, MLCC")
    (attr smd)
    (fp_text reference "C166" (at -0.055 1.18 90) (layer "B.SilkS")
        (effects (font (size 0.7 0.7) (thickness 0.127)) (justify mirror))
    )
    (fp_text value "C_470n_0402" (at 0 -1.17 90) (layer "B.Fab")
        (effects (font (size 1 1) (thickness 0.15)) (justify mirror))
    )
    (fp_text user "License: Apache-2.0" (at -0.939 -5.799 270) (layer "B.Fab") hide
        (effects (font (size 0.7 0.7) (thickness 0.15)) (justify left bottom mirror))
    )
    (fp_text user "${REFERENCE}" (at 0 0 90) (layer "B.Fab")
        (effects (font (size 0.25 0.25) (thickness 0.04)) (justify mirror))
    )
    (fp_text user "Author: Antmicro" (at -0.939 -3.399 270) (layer "B.Fab") hide
        (effects (font (size 0.7 0.7) (thickness 0.15)) (justify left bottom mirror))
    )
    (fp_rect (start -0.925 0.47) (end 0.925 -0.47)
      (stroke (width 0.05) (type default)) (fill none) (layer "B.CrtYd"))
    (fp_line (start -0.494 -0.248) (end -0.494 0.25)
      (stroke (width 0.15) (type solid)) (layer "B.Fab"))
    (fp_line (start -0.494 0.25) (end 0.504 0.25)
      (stroke (width 0.15) (type solid)) (layer "B.Fab"))
    (fp_line (start 0.504 -0.248) (end -0.494 -0.248)
      (stroke (width 0.15) (type solid)) (layer "B.Fab"))
    (fp_line (start 0.504 0.25) (end 0.504 -0.248)
      (stroke (width 0.15) (type solid)) (layer "B.Fab"))
    (pad "1" smd roundrect (at -0.48 0 90) (size 0.59 0.64) (layers "B.Cu" "B.Paste" "B.Mask") (roundrect_rratio 0.25)
      (net 1 "GND") (pintype "passive"))
    (pad "2" smd roundrect (at 0.48 0 90) (size 0.59 0.64) (layers "B.Cu" "B.Paste" "B.Mask") (roundrect_rratio 0.25)
      (net 303 "/FPGA power supply/VCCA1") (pintype "passive"))
  )

  (footprint "antmicro-footprints:C_0402_1005Metric" (layer "B.Cu")
    (at 107.95 113.75 -90)
    (descr "Capacitor SMD 0402")
    (tags "capacitor SMD 0402")
    (property "Author" "Antmicro")
    (property "Dielectric" "")
    (property "License" "Apache-2.0")
    (property "MPN" "C1005X5R1E474M050BB")
    (property "Manufacturer" "TDK")
    (property "Public" "False")
    (property "Sheetfile" "fpga-power-supply.kicad_sch")
    (property "Sheetname" "FPGA power supply")
    (property "Val" "470n")
    (property "Voltage" "")
    (property "ki_description" "SMD Multilayer Ceramic Capacitor, 0.47 µF, 25 V, 0402 [1005 Metric], ± 20%, X5R, C")
    (property "ki_keywords" "0402, SMT, CAPACITOR, PASSIVE, CERAMIC, MLCC")
    (attr smd)
    (fp_text reference "C167" (at -2.325 -0.57 90) (layer "B.SilkS")
        (effects (font (size 0.7 0.7) (thickness 0.127)) (justify mirror))
    )
    (fp_text value "C_470n_0402" (at 0 -1.17 90) (layer "B.Fab")
        (effects (font (size 1 1) (thickness 0.15)) (justify mirror))
    )
    (fp_text user "${REFERENCE}" (at 0 0 90) (layer "B.Fab")
        (effects (font (size 0.25 0.25) (thickness 0.04)) (justify mirror))
    )
    (fp_text user "Author: Antmicro" (at -0.939 -3.399 90) (layer "B.Fab") hide
        (effects (font (size 0.7 0.7) (thickness 0.15)) (justify left bottom mirror))
    )
    (fp_text user "License: Apache-2.0" (at -0.939 -5.799 90) (layer "B.Fab") hide
        (effects (font (size 0.7 0.7) (thickness 0.15)) (justify left bottom mirror))
    )
    (fp_rect (start -0.925 0.47) (end 0.925 -0.47)
      (stroke (width 0.05) (type default)) (fill none) (layer "B.CrtYd"))
    (fp_line (start -0.494 -0.248) (end -0.494 0.25)
      (stroke (width 0.15) (type solid)) (layer "B.Fab"))
    (fp_line (start -0.494 0.25) (end 0.504 0.25)
      (stroke (width 0.15) (type solid)) (layer "B.Fab"))
    (fp_line (start 0.504 -0.248) (end -0.494 -0.248)
      (stroke (width 0.15) (type solid)) (layer "B.Fab"))
    (fp_line (start 0.504 0.25) (end 0.504 -0.248)
      (stroke (width 0.15) (type solid)) (layer "B.Fab"))
    (pad "1" smd roundrect (at -0.48 0 270) (size 0.59 0.64) (layers "B.Cu" "B.Paste" "B.Mask") (roundrect_rratio 0.25)
      (net 1 "GND") (pintype "passive"))
    (pad "2" smd roundrect (at 0.48 0 270) (size 0.59 0.64) (layers "B.Cu" "B.Paste" "B.Mask") (roundrect_rratio 0.25)
      (net 304 "/FPGA power supply/VCCAUX") (pintype "passive"))
  )

  (footprint "antmicro-footprints:C_0402_1005Metric" (layer "B.Cu")
    (at 107.1 118.85 180)
    (descr "Capacitor SMD 0402")
    (tags "capacitor SMD 0402")
    (property "Author" "Antmicro")
    (property "Dielectric" "")
    (property "License" "Apache-2.0")
    (property "MPN" "C1005X5R1E474M050BB")
    (property "Manufacturer" "TDK")
    (property "Public" "False")
    (property "Sheetfile" "fpga-power-supply.kicad_sch")
    (property "Sheetname" "FPGA power supply")
    (property "Val" "470n")
    (property "Voltage" "")
    (property "ki_description" "SMD Multilayer Ceramic Capacitor, 0.47 µF, 25 V, 0402 [1005 Metric], ± 20%, X5R, C")
    (property "ki_keywords" "0402, SMT, CAPACITOR, PASSIVE, CERAMIC, MLCC")
    (attr smd)
    (fp_text reference "C168" (at 0.55 -22.85) (layer "B.SilkS")
        (effects (font (size 0.7 0.7) (thickness 0.127)) (justify mirror))
    )
    (fp_text value "C_470n_0402" (at 0 -1.17) (layer "B.Fab")
        (effects (font (size 1 1) (thickness 0.15)) (justify mirror))
    )
    (fp_text user "Author: Antmicro" (at -0.939 -3.399) (layer "B.Fab") hide
        (effects (font (size 0.7 0.7) (thickness 0.15)) (justify left bottom mirror))
    )
    (fp_text user "License: Apache-2.0" (at -0.939 -5.799) (layer "B.Fab") hide
        (effects (font (size 0.7 0.7) (thickness 0.15)) (justify left bottom mirror))
    )
    (fp_text user "${REFERENCE}" (at 0 0) (layer "B.Fab")
        (effects (font (size 0.25 0.25) (thickness 0.04)) (justify mirror))
    )
    (fp_rect (start -0.925 0.47) (end 0.925 -0.47)
      (stroke (width 0.05) (type default)) (fill none) (layer "B.CrtYd"))
    (fp_line (start -0.494 -0.248) (end -0.494 0.25)
      (stroke (width 0.15) (type solid)) (layer "B.Fab"))
    (fp_line (start -0.494 0.25) (end 0.504 0.25)
      (stroke (width 0.15) (type solid)) (layer "B.Fab"))
    (fp_line (start 0.504 -0.248) (end -0.494 -0.248)
      (stroke (width 0.15) (type solid)) (layer "B.Fab"))
    (fp_line (start 0.504 0.25) (end 0.504 -0.248)
      (stroke (width 0.15) (type solid)) (layer "B.Fab"))
    (pad "1" smd roundrect (at -0.48 0 180) (size 0.59 0.64) (layers "B.Cu" "B.Paste" "B.Mask") (roundrect_rratio 0.25)
      (net 211 "VCC1V2") (pintype "passive"))
    (pad "2" smd roundrect (at 0.48 0 180) (size 0.59 0.64) (layers "B.Cu" "B.Paste" "B.Mask") (roundrect_rratio 0.25)
      (net 1 "GND") (pintype "passive"))
  )

  (footprint "antmicro-footprints:C_0402_1005Metric" (layer "B.Cu")
    (at 107.95 129.2)
    (descr "Capacitor SMD 0402")
    (tags "capacitor SMD 0402")
    (property "Author" "Antmicro")
    (property "Dielectric" "X5R")
    (property "License" "Apache-2.0")
    (property "MPN" "GRM155R61H104KE14D")
    (property "Manufacturer" "Murata")
    (property "Public" "False")
    (property "Sheetfile" "fpga-power-supply.kicad_sch")
    (property "Sheetname" "FPGA power supply")
    (property "Val" "100n")
    (property "Voltage" "50V")
    (property "ki_description" "SMD Multilayer Ceramic Capacitor, 0.1 µF, 50 V, 0402 [1005 Metric], ± 10%, X5R, GRM Series")
    (property "ki_keywords" "0402, SMT, CAPACITOR, PASSIVE, CERAMIC, MLCC")
    (attr smd)
    (fp_text reference "C169" (at 0.71 20.785) (layer "B.SilkS")
        (effects (font (size 0.7 0.7) (thickness 0.127)) (justify mirror))
    )
    (fp_text value "C_100n_0402" (at 0 -1.17) (layer "B.Fab")
        (effects (font (size 1 1) (thickness 0.15)) (justify mirror))
    )
    (fp_text user "${REFERENCE}" (at 0 0) (layer "B.Fab")
        (effects (font (size 0.25 0.25) (thickness 0.04)) (justify mirror))
    )
    (fp_text user "Author: Antmicro" (at -0.939 -3.399 180) (layer "B.Fab") hide
        (effects (font (size 0.7 0.7) (thickness 0.15)) (justify left bottom mirror))
    )
    (fp_text user "License: Apache-2.0" (at -0.939 -5.799 180) (layer "B.Fab") hide
        (effects (font (size 0.7 0.7) (thickness 0.15)) (justify left bottom mirror))
    )
    (fp_rect (start -0.925 0.47) (end 0.925 -0.47)
      (stroke (width 0.05) (type default)) (fill none) (layer "B.CrtYd"))
    (fp_line (start -0.494 -0.248) (end -0.494 0.25)
      (stroke (width 0.15) (type solid)) (layer "B.Fab"))
    (fp_line (start -0.494 0.25) (end 0.504 0.25)
      (stroke (width 0.15) (type solid)) (layer "B.Fab"))
    (fp_line (start 0.504 -0.248) (end -0.494 -0.248)
      (stroke (width 0.15) (type solid)) (layer "B.Fab"))
    (fp_line (start 0.504 0.25) (end 0.504 -0.248)
      (stroke (width 0.15) (type solid)) (layer "B.Fab"))
    (pad "1" smd roundrect (at -0.48 0) (size 0.59 0.64) (layers "B.Cu" "B.Paste" "B.Mask") (roundrect_rratio 0.25)
      (net 1 "GND") (pintype "passive"))
    (pad "2" smd roundrect (at 0.48 0) (size 0.59 0.64) (layers "B.Cu" "B.Paste" "B.Mask") (roundrect_rratio 0.25)
      (net 303 "/FPGA power supply/VCCA1") (pintype "passive"))
  )

  (footprint "antmicro-footprints:C_0402_1005Metric" (layer "B.Cu")
    (at 111.2 117.1 180)
    (descr "Capacitor SMD 0402")
    (tags "capacitor SMD 0402")
    (property "Author" "Antmicro")
    (property "Dielectric" "")
    (property "License" "Apache-2.0")
    (property "MPN" "C1005X5R1E474M050BB")
    (property "Manufacturer" "TDK")
    (property "Public" "False")
    (property "Sheetfile" "fpga-power-supply.kicad_sch")
    (property "Sheetname" "FPGA power supply")
    (property "Val" "470n")
    (property "Voltage" "")
    (property "ki_description" "SMD Multilayer Ceramic Capacitor, 0.47 µF, 25 V, 0402 [1005 Metric], ± 20%, X5R, C")
    (property "ki_keywords" "0402, SMT, CAPACITOR, PASSIVE, CERAMIC, MLCC")
    (attr smd)
    (fp_text reference "C170" (at -2.57 -0.075) (layer "B.SilkS")
        (effects (font (size 0.7 0.7) (thickness 0.127)) (justify mirror))
    )
    (fp_text value "C_470n_0402" (at 0 -1.17) (layer "B.Fab")
        (effects (font (size 1 1) (thickness 0.15)) (justify mirror))
    )
    (fp_text user "${REFERENCE}" (at 0 0) (layer "B.Fab")
        (effects (font (size 0.25 0.25) (thickness 0.04)) (justify mirror))
    )
    (fp_text user "License: Apache-2.0" (at -0.939 -5.799) (layer "B.Fab") hide
        (effects (font (size 0.7 0.7) (thickness 0.15)) (justify left bottom mirror))
    )
    (fp_text user "Author: Antmicro" (at -0.939 -3.399) (layer "B.Fab") hide
        (effects (font (size 0.7 0.7) (thickness 0.15)) (justify left bottom mirror))
    )
    (fp_rect (start -0.925 0.47) (end 0.925 -0.47)
      (stroke (width 0.05) (type default)) (fill none) (layer "B.CrtYd"))
    (fp_line (start -0.494 -0.248) (end -0.494 0.25)
      (stroke (width 0.15) (type solid)) (layer "B.Fab"))
    (fp_line (start -0.494 0.25) (end 0.504 0.25)
      (stroke (width 0.15) (type solid)) (layer "B.Fab"))
    (fp_line (start 0.504 -0.248) (end -0.494 -0.248)
      (stroke (width 0.15) (type solid)) (layer "B.Fab"))
    (fp_line (start 0.504 0.25) (end 0.504 -0.248)
      (stroke (width 0.15) (type solid)) (layer "B.Fab"))
    (pad "1" smd roundrect (at -0.48 0 180) (size 0.59 0.64) (layers "B.Cu" "B.Paste" "B.Mask") (roundrect_rratio 0.25)
      (net 1 "GND") (pintype "passive"))
    (pad "2" smd roundrect (at 0.48 0 180) (size 0.59 0.64) (layers "B.Cu" "B.Paste" "B.Mask") (roundrect_rratio 0.25)
      (net 304 "/FPGA power supply/VCCAUX") (pintype "passive"))
  )

  (footprint "antmicro-footprints:C_0402_1005Metric" (layer "B.Cu")
    (at 108.35 116.55 -90)
    (descr "Capacitor SMD 0402")
    (tags "capacitor SMD 0402")
    (property "Author" "Antmicro")
    (property "Dielectric" "")
    (property "License" "Apache-2.0")
    (property "MPN" "C1005X5R1E474M050BB")
    (property "Manufacturer" "TDK")
    (property "Public" "False")
    (property "Sheetfile" "fpga-power-supply.kicad_sch")
    (property "Sheetname" "FPGA power supply")
    (property "Val" "470n")
    (property "Voltage" "")
    (property "ki_description" "SMD Multilayer Ceramic Capacitor, 0.47 µF, 25 V, 0402 [1005 Metric], ± 20%, X5R, C")
    (property "ki_keywords" "0402, SMT, CAPACITOR, PASSIVE, CERAMIC, MLCC")
    (attr smd)
    (fp_text reference "C171" (at 22.6 -0.1 90) (layer "B.SilkS")
        (effects (font (size 0.7 0.7) (thickness 0.127)) (justify mirror))
    )
    (fp_text value "C_470n_0402" (at 0 -1.17 90) (layer "B.Fab")
        (effects (font (size 1 1) (thickness 0.15)) (justify mirror))
    )
    (fp_text user "${REFERENCE}" (at 0 0 90) (layer "B.Fab")
        (effects (font (size 0.25 0.25) (thickness 0.04)) (justify mirror))
    )
    (fp_text user "License: Apache-2.0" (at -0.939 -5.799 90) (layer "B.Fab") hide
        (effects (font (size 0.7 0.7) (thickness 0.15)) (justify left bottom mirror))
    )
    (fp_text user "Author: Antmicro" (at -0.939 -3.399 90) (layer "B.Fab") hide
        (effects (font (size 0.7 0.7) (thickness 0.15)) (justify left bottom mirror))
    )
    (fp_rect (start -0.925 0.47) (end 0.925 -0.47)
      (stroke (width 0.05) (type default)) (fill none) (layer "B.CrtYd"))
    (fp_line (start -0.494 -0.248) (end -0.494 0.25)
      (stroke (width 0.15) (type solid)) (layer "B.Fab"))
    (fp_line (start -0.494 0.25) (end 0.504 0.25)
      (stroke (width 0.15) (type solid)) (layer "B.Fab"))
    (fp_line (start 0.504 -0.248) (end -0.494 -0.248)
      (stroke (width 0.15) (type solid)) (layer "B.Fab"))
    (fp_line (start 0.504 0.25) (end 0.504 -0.248)
      (stroke (width 0.15) (type solid)) (layer "B.Fab"))
    (pad "1" smd roundrect (at -0.48 0 270) (size 0.59 0.64) (layers "B.Cu" "B.Paste" "B.Mask") (roundrect_rratio 0.25)
      (net 211 "VCC1V2") (pintype "passive"))
    (pad "2" smd roundrect (at 0.48 0 270) (size 0.59 0.64) (layers "B.Cu" "B.Paste" "B.Mask") (roundrect_rratio 0.25)
      (net 1 "GND") (pintype "passive"))
  )

  (footprint "antmicro-footprints:C_0402_1005Metric" (layer "B.Cu")
    (at 105 132.25 90)
    (descr "Capacitor SMD 0402")
    (tags "capacitor SMD 0402")
    (property "Author" "Antmicro")
    (property "Dielectric" "X7R")
    (property "License" "Apache-2.0")
    (property "MPN" "GRM155R71H103KA88D")
    (property "Manufacturer" "Murata")
    (property "Public" "False")
    (property "Sheetfile" "fpga-power-supply.kicad_sch")
    (property "Sheetname" "FPGA power supply")
    (property "Val" "10n")
    (property "Voltage" "50V")
    (property "ki_description" "SMD Multilayer Ceramic Capacitor, 10000 pF, 50 V, 0402 [1005 Metric], ± 10%, X7R, GRM Series")
    (property "ki_keywords" "0402, SMT, CAPACITOR, PASSIVE")
    (attr smd)
    (fp_text reference "C172" (at -20.825 0.89 90) (layer "B.SilkS")
        (effects (font (size 0.7 0.7) (thickness 0.127)) (justify mirror))
    )
    (fp_text value "C_10n_0402" (at 0 -1.17 90) (layer "B.Fab")
        (effects (font (size 1 1) (thickness 0.15)) (justify mirror))
    )
    (fp_text user "License: Apache-2.0" (at -0.939 -5.799 270) (layer "B.Fab") hide
        (effects (font (size 0.7 0.7) (thickness 0.15)) (justify left bottom mirror))
    )
    (fp_text user "${REFERENCE}" (at 0 0 90) (layer "B.Fab")
        (effects (font (size 0.25 0.25) (thickness 0.04)) (justify mirror))
    )
    (fp_text user "Author: Antmicro" (at -0.939 -3.399 270) (layer "B.Fab") hide
        (effects (font (size 0.7 0.7) (thickness 0.15)) (justify left bottom mirror))
    )
    (fp_rect (start -0.925 0.47) (end 0.925 -0.47)
      (stroke (width 0.05) (type default)) (fill none) (layer "B.CrtYd"))
    (fp_line (start -0.494 -0.248) (end -0.494 0.25)
      (stroke (width 0.15) (type solid)) (layer "B.Fab"))
    (fp_line (start -0.494 0.25) (end 0.504 0.25)
      (stroke (width 0.15) (type solid)) (layer "B.Fab"))
    (fp_line (start 0.504 -0.248) (end -0.494 -0.248)
      (stroke (width 0.15) (type solid)) (layer "B.Fab"))
    (fp_line (start 0.504 0.25) (end 0.504 -0.248)
      (stroke (width 0.15) (type solid)) (layer "B.Fab"))
    (pad "1" smd roundrect (at -0.48 0 90) (size 0.59 0.64) (layers "B.Cu" "B.Paste" "B.Mask") (roundrect_rratio 0.25)
      (net 1 "GND") (pintype "passive"))
    (pad "2" smd roundrect (at 0.48 0 90) (size 0.59 0.64) (layers "B.Cu" "B.Paste" "B.Mask") (roundrect_rratio 0.25)
      (net 303 "/FPGA power supply/VCCA1") (pintype "passive"))
  )

  (footprint "antmicro-footprints:C_0402_1005Metric" (layer "B.Cu")
    (at 111.25 122.725 180)
    (descr "Capacitor SMD 0402")
    (tags "capacitor SMD 0402")
    (property "Author" "Antmicro")
    (property "Dielectric" "")
    (property "License" "Apache-2.0")
    (property "MPN" "C1005X5R1E474M050BB")
    (property "Manufacturer" "TDK")
    (property "Public" "False")
    (property "Sheetfile" "fpga-power-supply.kicad_sch")
    (property "Sheetname" "FPGA power supply")
    (property "Val" "470n")
    (property "Voltage" "")
    (property "ki_description" "SMD Multilayer Ceramic Capacitor, 0.47 µF, 25 V, 0402 [1005 Metric], ± 20%, X5R, C")
    (property "ki_keywords" "0402, SMT, CAPACITOR, PASSIVE, CERAMIC, MLCC")
    (attr smd)
    (fp_text reference "C173" (at -2.58 -0.07) (layer "B.SilkS")
        (effects (font (size 0.7 0.7) (thickness 0.127)) (justify mirror))
    )
    (fp_text value "C_470n_0402" (at 0 -1.17) (layer "B.Fab")
        (effects (font (size 1 1) (thickness 0.15)) (justify mirror))
    )
    (fp_text user "${REFERENCE}" (at 0 0) (layer "B.Fab")
        (effects (font (size 0.25 0.25) (thickness 0.04)) (justify mirror))
    )
    (fp_text user "License: Apache-2.0" (at -0.939 -5.799) (layer "B.Fab") hide
        (effects (font (size 0.7 0.7) (thickness 0.15)) (justify left bottom mirror))
    )
    (fp_text user "Author: Antmicro" (at -0.939 -3.399) (layer "B.Fab") hide
        (effects (font (size 0.7 0.7) (thickness 0.15)) (justify left bottom mirror))
    )
    (fp_rect (start -0.925 0.47) (end 0.925 -0.47)
      (stroke (width 0.05) (type default)) (fill none) (layer "B.CrtYd"))
    (fp_line (start -0.494 -0.248) (end -0.494 0.25)
      (stroke (width 0.15) (type solid)) (layer "B.Fab"))
    (fp_line (start -0.494 0.25) (end 0.504 0.25)
      (stroke (width 0.15) (type solid)) (layer "B.Fab"))
    (fp_line (start 0.504 -0.248) (end -0.494 -0.248)
      (stroke (width 0.15) (type solid)) (layer "B.Fab"))
    (fp_line (start 0.504 0.25) (end 0.504 -0.248)
      (stroke (width 0.15) (type solid)) (layer "B.Fab"))
    (pad "1" smd roundrect (at -0.48 0 180) (size 0.59 0.64) (layers "B.Cu" "B.Paste" "B.Mask") (roundrect_rratio 0.25)
      (net 1 "GND") (pintype "passive"))
    (pad "2" smd roundrect (at 0.48 0 180) (size 0.59 0.64) (layers "B.Cu" "B.Paste" "B.Mask") (roundrect_rratio 0.25)
      (net 304 "/FPGA power supply/VCCAUX") (pintype "passive"))
  )

  (footprint "antmicro-footprints:C_0402_1005Metric" (layer "B.Cu")
    (at 106.85 124.05 90)
    (descr "Capacitor SMD 0402")
    (tags "capacitor SMD 0402")
    (property "Author" "Antmicro")
    (property "Dielectric" "")
    (property "License" "Apache-2.0")
    (property "MPN" "C1005X5R1E474M050BB")
    (property "Manufacturer" "TDK")
    (property "Public" "False")
    (property "Sheetfile" "fpga-power-supply.kicad_sch")
    (property "Sheetname" "FPGA power supply")
    (property "Val" "470n")
    (property "Voltage" "")
    (property "ki_description" "SMD Multilayer Ceramic Capacitor, 0.47 µF, 25 V, 0402 [1005 Metric], ± 20%, X5R, C")
    (property "ki_keywords" "0402, SMT, CAPACITOR, PASSIVE, CERAMIC, MLCC")
    (attr smd)
    (fp_text reference "C174" (at -22.165 -0.02 90) (layer "B.SilkS")
        (effects (font (size 0.7 0.7) (thickness 0.127)) (justify mirror))
    )
    (fp_text value "C_470n_0402" (at 0 -1.17 90) (layer "B.Fab")
        (effects (font (size 1 1) (thickness 0.15)) (justify mirror))
    )
    (fp_text user "License: Apache-2.0" (at -0.939 -5.799 270) (layer "B.Fab") hide
        (effects (font (size 0.7 0.7) (thickness 0.15)) (justify left bottom mirror))
    )
    (fp_text user "${REFERENCE}" (at 0 0 90) (layer "B.Fab")
        (effects (font (size 0.25 0.25) (thickness 0.04)) (justify mirror))
    )
    (fp_text user "Author: Antmicro" (at -0.939 -3.399 270) (layer "B.Fab") hide
        (effects (font (size 0.7 0.7) (thickness 0.15)) (justify left bottom mirror))
    )
    (fp_rect (start -0.925 0.47) (end 0.925 -0.47)
      (stroke (width 0.05) (type default)) (fill none) (layer "B.CrtYd"))
    (fp_line (start -0.494 -0.248) (end -0.494 0.25)
      (stroke (width 0.15) (type solid)) (layer "B.Fab"))
    (fp_line (start -0.494 0.25) (end 0.504 0.25)
      (stroke (width 0.15) (type solid)) (layer "B.Fab"))
    (fp_line (start 0.504 -0.248) (end -0.494 -0.248)
      (stroke (width 0.15) (type solid)) (layer "B.Fab"))
    (fp_line (start 0.504 0.25) (end 0.504 -0.248)
      (stroke (width 0.15) (type solid)) (layer "B.Fab"))
    (pad "1" smd roundrect (at -0.48 0 90) (size 0.59 0.64) (layers "B.Cu" "B.Paste" "B.Mask") (roundrect_rratio 0.25)
      (net 211 "VCC1V2") (pintype "passive"))
    (pad "2" smd roundrect (at 0.48 0 90) (size 0.59 0.64) (layers "B.Cu" "B.Paste" "B.Mask") (roundrect_rratio 0.25)
      (net 1 "GND") (pintype "passive"))
  )

  (footprint "antmicro-footprints:C_0402_1005Metric" (layer "B.Cu")
    (at 106.025 132.25 90)
    (descr "Capacitor SMD 0402")
    (tags "capacitor SMD 0402")
    (property "Author" "Antmicro")
    (property "Dielectric" "X7R")
    (property "License" "Apache-2.0")
    (property "MPN" "GRM155R71H103KA88D")
    (property "Manufacturer" "Murata")
    (property "Public" "False")
    (property "Sheetfile" "fpga-power-supply.kicad_sch")
    (property "Sheetname" "FPGA power supply")
    (property "Val" "10n")
    (property "Voltage" "50V")
    (property "ki_description" "SMD Multilayer Ceramic Capacitor, 10000 pF, 50 V, 0402 [1005 Metric], ± 10%, X7R, GRM Series")
    (property "ki_keywords" "0402, SMT, CAPACITOR, PASSIVE")
    (attr smd)
    (fp_text reference "C175" (at -20.855 0.875 90) (layer "B.SilkS")
        (effects (font (size 0.7 0.7) (thickness 0.127)) (justify mirror))
    )
    (fp_text value "C_10n_0402" (at 0 -1.17 90) (layer "B.Fab")
        (effects (font (size 1 1) (thickness 0.15)) (justify mirror))
    )
    (fp_text user "${REFERENCE}" (at 0 0 90) (layer "B.Fab")
        (effects (font (size 0.25 0.25) (thickness 0.04)) (justify mirror))
    )
    (fp_text user "License: Apache-2.0" (at -0.939 -5.799 270) (layer "B.Fab") hide
        (effects (font (size 0.7 0.7) (thickness 0.15)) (justify left bottom mirror))
    )
    (fp_text user "Author: Antmicro" (at -0.939 -3.399 270) (layer "B.Fab") hide
        (effects (font (size 0.7 0.7) (thickness 0.15)) (justify left bottom mirror))
    )
    (fp_rect (start -0.925 0.47) (end 0.925 -0.47)
      (stroke (width 0.05) (type default)) (fill none) (layer "B.CrtYd"))
    (fp_line (start -0.494 -0.248) (end -0.494 0.25)
      (stroke (width 0.15) (type solid)) (layer "B.Fab"))
    (fp_line (start -0.494 0.25) (end 0.504 0.25)
      (stroke (width 0.15) (type solid)) (layer "B.Fab"))
    (fp_line (start 0.504 -0.248) (end -0.494 -0.248)
      (stroke (width 0.15) (type solid)) (layer "B.Fab"))
    (fp_line (start 0.504 0.25) (end 0.504 -0.248)
      (stroke (width 0.15) (type solid)) (layer "B.Fab"))
    (pad "1" smd roundrect (at -0.48 0 90) (size 0.59 0.64) (layers "B.Cu" "B.Paste" "B.Mask") (roundrect_rratio 0.25)
      (net 1 "GND") (pintype "passive"))
    (pad "2" smd roundrect (at 0.48 0 90) (size 0.59 0.64) (layers "B.Cu" "B.Paste" "B.Mask") (roundrect_rratio 0.25)
      (net 303 "/FPGA power supply/VCCA1") (pintype "passive"))
  )

  (footprint "antmicro-footprints:C_0402_1005Metric" (layer "B.Cu")
    (at 108.715 125.5)
    (descr "Capacitor SMD 0402")
    (tags "capacitor SMD 0402")
    (property "Author" "Antmicro")
    (property "Dielectric" "")
    (property "License" "Apache-2.0")
    (property "MPN" "C1005X5R1E474M050BB")
    (property "Manufacturer" "TDK")
    (property "Public" "False")
    (property "Sheetfile" "fpga-power-supply.kicad_sch")
    (property "Sheetname" "FPGA power supply")
    (property "Val" "470n")
    (property "Voltage" "")
    (property "ki_description" "SMD Multilayer Ceramic Capacitor, 0.47 µF, 25 V, 0402 [1005 Metric], ± 20%, X5R, C")
    (property "ki_keywords" "0402, SMT, CAPACITOR, PASSIVE, CERAMIC, MLCC")
    (attr smd)
    (fp_text reference "C176" (at -0.385 -22.95) (layer "B.SilkS")
        (effects (font (size 0.7 0.7) (thickness 0.127)) (justify mirror))
    )
    (fp_text value "C_470n_0402" (at 0 -1.17) (layer "B.Fab")
        (effects (font (size 1 1) (thickness 0.15)) (justify mirror))
    )
    (fp_text user "${REFERENCE}" (at 0 0) (layer "B.Fab")
        (effects (font (size 0.25 0.25) (thickness 0.04)) (justify mirror))
    )
    (fp_text user "Author: Antmicro" (at -0.939 -3.399 180) (layer "B.Fab") hide
        (effects (font (size 0.7 0.7) (thickness 0.15)) (justify left bottom mirror))
    )
    (fp_text user "License: Apache-2.0" (at -0.939 -5.799 180) (layer "B.Fab") hide
        (effects (font (size 0.7 0.7) (thickness 0.15)) (justify left bottom mirror))
    )
    (fp_rect (start -0.925 0.47) (end 0.925 -0.47)
      (stroke (width 0.05) (type default)) (fill none) (layer "B.CrtYd"))
    (fp_line (start -0.494 -0.248) (end -0.494 0.25)
      (stroke (width 0.15) (type solid)) (layer "B.Fab"))
    (fp_line (start -0.494 0.25) (end 0.504 0.25)
      (stroke (width 0.15) (type solid)) (layer "B.Fab"))
    (fp_line (start 0.504 -0.248) (end -0.494 -0.248)
      (stroke (width 0.15) (type solid)) (layer "B.Fab"))
    (fp_line (start 0.504 0.25) (end 0.504 -0.248)
      (stroke (width 0.15) (type solid)) (layer "B.Fab"))
    (pad "1" smd roundrect (at -0.48 0) (size 0.59 0.64) (layers "B.Cu" "B.Paste" "B.Mask") (roundrect_rratio 0.25)
      (net 1 "GND") (pintype "passive"))
    (pad "2" smd roundrect (at 0.48 0) (size 0.59 0.64) (layers "B.Cu" "B.Paste" "B.Mask") (roundrect_rratio 0.25)
      (net 304 "/FPGA power supply/VCCAUX") (pintype "passive"))
  )

  (footprint "antmicro-footprints:C_0402_1005Metric" (layer "B.Cu")
    (at 108.4 124.05 -90)
    (descr "Capacitor SMD 0402")
    (tags "capacitor SMD 0402")
    (property "Author" "Antmicro")
    (property "Dielectric" "")
    (property "License" "Apache-2.0")
    (property "MPN" "C1005X5R1E474M050BB")
    (property "Manufacturer" "TDK")
    (property "Public" "False")
    (property "Sheetfile" "fpga-power-supply.kicad_sch")
    (property "Sheetname" "FPGA power supply")
    (property "Val" "470n")
    (property "Voltage" "")
    (property "ki_description" "SMD Multilayer Ceramic Capacitor, 0.47 µF, 25 V, 0402 [1005 Metric], ± 20%, X5R, C")
    (property "ki_keywords" "0402, SMT, CAPACITOR, PASSIVE, CERAMIC, MLCC")
    (attr smd)
    (fp_text reference "C177" (at 22.475 -0.16 90) (layer "B.SilkS")
        (effects (font (size 0.7 0.7) (thickness 0.127)) (justify mirror))
    )
    (fp_text value "C_470n_0402" (at 0 -1.17 90) (layer "B.Fab")
        (effects (font (size 1 1) (thickness 0.15)) (justify mirror))
    )
    (fp_text user "Author: Antmicro" (at -0.939 -3.399 90) (layer "B.Fab") hide
        (effects (font (size 0.7 0.7) (thickness 0.15)) (justify left bottom mirror))
    )
    (fp_text user "${REFERENCE}" (at 0 0 90) (layer "B.Fab")
        (effects (font (size 0.25 0.25) (thickness 0.04)) (justify mirror))
    )
    (fp_text user "License: Apache-2.0" (at -0.939 -5.799 90) (layer "B.Fab") hide
        (effects (font (size 0.7 0.7) (thickness 0.15)) (justify left bottom mirror))
    )
    (fp_rect (start -0.925 0.47) (end 0.925 -0.47)
      (stroke (width 0.05) (type default)) (fill none) (layer "B.CrtYd"))
    (fp_line (start -0.494 -0.248) (end -0.494 0.25)
      (stroke (width 0.15) (type solid)) (layer "B.Fab"))
    (fp_line (start -0.494 0.25) (end 0.504 0.25)
      (stroke (width 0.15) (type solid)) (layer "B.Fab"))
    (fp_line (start 0.504 -0.248) (end -0.494 -0.248)
      (stroke (width 0.15) (type solid)) (layer "B.Fab"))
    (fp_line (start 0.504 0.25) (end 0.504 -0.248)
      (stroke (width 0.15) (type solid)) (layer "B.Fab"))
    (pad "1" smd roundrect (at -0.48 0 270) (size 0.59 0.64) (layers "B.Cu" "B.Paste" "B.Mask") (roundrect_rratio 0.25)
      (net 211 "VCC1V2") (pintype "passive"))
    (pad "2" smd roundrect (at 0.48 0 270) (size 0.59 0.64) (layers "B.Cu" "B.Paste" "B.Mask") (roundrect_rratio 0.25)
      (net 1 "GND") (pintype "passive"))
  )

  (footprint "antmicro-footprints:C_0402_1005Metric" (layer "B.Cu")
    (at 104.85 130.2)
    (descr "Capacitor SMD 0402")
    (tags "capacitor SMD 0402")
    (property "Author" "Antmicro")
    (property "Dielectric" "C0G")
    (property "License" "Apache-2.0")
    (property "MPN" "GRM1555C1H102JA01D")
    (property "Manufacturer" "Murata")
    (property "Public" "False")
    (property "Sheetfile" "fpga-power-supply.kicad_sch")
    (property "Sheetname" "FPGA power supply")
    (property "Val" "1n")
    (property "Voltage" "50V")
    (property "ki_description" "SMD Multilayer Ceramic Capacitor, 1000 pF, 50 V, 0402 [1005 Metric], ± 5%, C0G / NP0, GRM Series")
    (property "ki_keywords" "0402, SMT, CAPACITOR, PASSIVE, CERAMIC, MLCC")
    (attr smd)
    (fp_text reference "C178" (at 0.35 20.785) (layer "B.SilkS")
        (effects (font (size 0.7 0.7) (thickness 0.127)) (justify mirror))
    )
    (fp_text value "C_1n_0402" (at 0 -1.17) (layer "B.Fab")
        (effects (font (size 1 1) (thickness 0.15)) (justify mirror))
    )
    (fp_text user "Author: Antmicro" (at -0.939 -3.399 180) (layer "B.Fab") hide
        (effects (font (size 0.7 0.7) (thickness 0.15)) (justify left bottom mirror))
    )
    (fp_text user "License: Apache-2.0" (at -0.939 -5.799 180) (layer "B.Fab") hide
        (effects (font (size 0.7 0.7) (thickness 0.15)) (justify left bottom mirror))
    )
    (fp_text user "${REFERENCE}" (at 0 0) (layer "B.Fab")
        (effects (font (size 0.25 0.25) (thickness 0.04)) (justify mirror))
    )
    (fp_rect (start -0.925 0.47) (end 0.925 -0.47)
      (stroke (width 0.05) (type default)) (fill none) (layer "B.CrtYd"))
    (fp_line (start -0.494 -0.248) (end -0.494 0.25)
      (stroke (width 0.15) (type solid)) (layer "B.Fab"))
    (fp_line (start -0.494 0.25) (end 0.504 0.25)
      (stroke (width 0.15) (type solid)) (layer "B.Fab"))
    (fp_line (start 0.504 -0.248) (end -0.494 -0.248)
      (stroke (width 0.15) (type solid)) (layer "B.Fab"))
    (fp_line (start 0.504 0.25) (end 0.504 -0.248)
      (stroke (width 0.15) (type solid)) (layer "B.Fab"))
    (pad "1" smd roundrect (at -0.48 0) (size 0.59 0.64) (layers "B.Cu" "B.Paste" "B.Mask") (roundrect_rratio 0.25)
      (net 1 "GND") (pintype "passive"))
    (pad "2" smd roundrect (at 0.48 0) (size 0.59 0.64) (layers "B.Cu" "B.Paste" "B.Mask") (roundrect_rratio 0.25)
      (net 303 "/FPGA power supply/VCCA1") (pintype "passive"))
  )

  (footprint "antmicro-footprints:C_0402_1005Metric" (layer "B.Cu")
    (at 99.5 124.95 -90)
    (descr "Capacitor SMD 0402")
    (tags "capacitor SMD 0402")
    (property "Author" "Antmicro")
    (property "Dielectric" "")
    (property "License" "Apache-2.0")
    (property "MPN" "C1005X5R1E474M050BB")
    (property "Manufacturer" "TDK")
    (property "Public" "False")
    (property "Sheetfile" "fpga-power-supply.kicad_sch")
    (property "Sheetname" "FPGA power supply")
    (property "Val" "470n")
    (property "Voltage" "")
    (property "ki_description" "SMD Multilayer Ceramic Capacitor, 0.47 µF, 25 V, 0402 [1005 Metric], ± 20%, X5R, C")
    (property "ki_keywords" "0402, SMT, CAPACITOR, PASSIVE, CERAMIC, MLCC")
    (attr smd)
    (fp_text reference "C179" (at -23 0 90) (layer "B.SilkS")
        (effects (font (size 0.7 0.7) (thickness 0.127)) (justify mirror))
    )
    (fp_text value "C_470n_0402" (at 0 -1.17 90) (layer "B.Fab")
        (effects (font (size 1 1) (thickness 0.15)) (justify mirror))
    )
    (fp_text user "Author: Antmicro" (at -0.939 -3.399 90) (layer "B.Fab") hide
        (effects (font (size 0.7 0.7) (thickness 0.15)) (justify left bottom mirror))
    )
    (fp_text user "${REFERENCE}" (at 0 0 90) (layer "B.Fab")
        (effects (font (size 0.25 0.25) (thickness 0.04)) (justify mirror))
    )
    (fp_text user "License: Apache-2.0" (at -0.939 -5.799 90) (layer "B.Fab") hide
        (effects (font (size 0.7 0.7) (thickness 0.15)) (justify left bottom mirror))
    )
    (fp_rect (start -0.925 0.47) (end 0.925 -0.47)
      (stroke (width 0.05) (type default)) (fill none) (layer "B.CrtYd"))
    (fp_line (start -0.494 -0.248) (end -0.494 0.25)
      (stroke (width 0.15) (type solid)) (layer "B.Fab"))
    (fp_line (start -0.494 0.25) (end 0.504 0.25)
      (stroke (width 0.15) (type solid)) (layer "B.Fab"))
    (fp_line (start 0.504 -0.248) (end -0.494 -0.248)
      (stroke (width 0.15) (type solid)) (layer "B.Fab"))
    (fp_line (start 0.504 0.25) (end 0.504 -0.248)
      (stroke (width 0.15) (type solid)) (layer "B.Fab"))
    (pad "1" smd roundrect (at -0.48 0 270) (size 0.59 0.64) (layers "B.Cu" "B.Paste" "B.Mask") (roundrect_rratio 0.25)
      (net 1 "GND") (pintype "passive"))
    (pad "2" smd roundrect (at 0.48 0 270) (size 0.59 0.64) (layers "B.Cu" "B.Paste" "B.Mask") (roundrect_rratio 0.25)
      (net 304 "/FPGA power supply/VCCAUX") (pintype "passive"))
  )

  (footprint "antmicro-footprints:C_0402_1005Metric" (layer "B.Cu")
    (at 100.5 124.1 90)
    (descr "Capacitor SMD 0402")
    (tags "capacitor SMD 0402")
    (property "Author" "Antmicro")
    (property "Dielectric" "")
    (property "License" "Apache-2.0")
    (property "MPN" "C1005X5R1E474M050BB")
    (property "Manufacturer" "TDK")
    (property "Public" "False")
    (property "Sheetfile" "fpga-power-supply.kicad_sch")
    (property "Sheetname" "FPGA power supply")
    (property "Val" "470n")
    (property "Voltage" "")
    (property "ki_description" "SMD Multilayer Ceramic Capacitor, 0.47 µF, 25 V, 0402 [1005 Metric], ± 20%, X5R, C")
    (property "ki_keywords" "0402, SMT, CAPACITOR, PASSIVE, CERAMIC, MLCC")
    (attr smd)
    (fp_text reference "C181" (at -21.975 0.33 90) (layer "B.SilkS")
        (effects (font (size 0.7 0.7) (thickness 0.127)) (justify mirror))
    )
    (fp_text value "C_470n_0402" (at 0 -1.17 90) (layer "B.Fab")
        (effects (font (size 1 1) (thickness 0.15)) (justify mirror))
    )
    (fp_text user "License: Apache-2.0" (at -0.939 -5.799 270) (layer "B.Fab") hide
        (effects (font (size 0.7 0.7) (thickness 0.15)) (justify left bottom mirror))
    )
    (fp_text user "${REFERENCE}" (at 0 0 90) (layer "B.Fab")
        (effects (font (size 0.25 0.25) (thickness 0.04)) (justify mirror))
    )
    (fp_text user "Author: Antmicro" (at -0.939 -3.399 270) (layer "B.Fab") hide
        (effects (font (size 0.7 0.7) (thickness 0.15)) (justify left bottom mirror))
    )
    (fp_rect (start -0.925 0.47) (end 0.925 -0.47)
      (stroke (width 0.05) (type default)) (fill none) (layer "B.CrtYd"))
    (fp_line (start -0.494 -0.248) (end -0.494 0.25)
      (stroke (width 0.15) (type solid)) (layer "B.Fab"))
    (fp_line (start -0.494 0.25) (end 0.504 0.25)
      (stroke (width 0.15) (type solid)) (layer "B.Fab"))
    (fp_line (start 0.504 -0.248) (end -0.494 -0.248)
      (stroke (width 0.15) (type solid)) (layer "B.Fab"))
    (fp_line (start 0.504 0.25) (end 0.504 -0.248)
      (stroke (width 0.15) (type solid)) (layer "B.Fab"))
    (pad "1" smd roundrect (at -0.48 0 90) (size 0.59 0.64) (layers "B.Cu" "B.Paste" "B.Mask") (roundrect_rratio 0.25)
      (net 211 "VCC1V2") (pintype "passive"))
    (pad "2" smd roundrect (at 0.48 0 90) (size 0.59 0.64) (layers "B.Cu" "B.Paste" "B.Mask") (roundrect_rratio 0.25)
      (net 1 "GND") (pintype "passive"))
  )

  (footprint "antmicro-footprints:C_0402_1005Metric" (layer "B.Cu")
    (at 97.6 123.35)
    (descr "Capacitor SMD 0402")
    (tags "capacitor SMD 0402")
    (property "Author" "Antmicro")
    (property "Dielectric" "")
    (property "License" "Apache-2.0")
    (property "MPN" "C1005X5R1E474M050BB")
    (property "Manufacturer" "TDK")
    (property "Public" "False")
    (property "Sheetfile" "fpga-power-supply.kicad_sch")
    (property "Sheetname" "FPGA power supply")
    (property "Val" "470n")
    (property "Voltage" "")
    (property "ki_description" "SMD Multilayer Ceramic Capacitor, 0.47 µF, 25 V, 0402 [1005 Metric], ± 20%, X5R, C")
    (property "ki_keywords" "0402, SMT, CAPACITOR, PASSIVE, CERAMIC, MLCC")
    (attr smd)
    (fp_text reference "C182" (at -2.45 0.525) (layer "B.SilkS")
        (effects (font (size 0.7 0.7) (thickness 0.127)) (justify mirror))
    )
    (fp_text value "C_470n_0402" (at 0 -1.17) (layer "B.Fab")
        (effects (font (size 1 1) (thickness 0.15)) (justify mirror))
    )
    (fp_text user "License: Apache-2.0" (at -0.939 -5.799 180) (layer "B.Fab") hide
        (effects (font (size 0.7 0.7) (thickness 0.15)) (justify left bottom mirror))
    )
    (fp_text user "Author: Antmicro" (at -0.939 -3.399 180) (layer "B.Fab") hide
        (effects (font (size 0.7 0.7) (thickness 0.15)) (justify left bottom mirror))
    )
    (fp_text user "${REFERENCE}" (at 0 0) (layer "B.Fab")
        (effects (font (size 0.25 0.25) (thickness 0.04)) (justify mirror))
    )
    (fp_rect (start -0.925 0.47) (end 0.925 -0.47)
      (stroke (width 0.05) (type default)) (fill none) (layer "B.CrtYd"))
    (fp_line (start -0.494 -0.248) (end -0.494 0.25)
      (stroke (width 0.15) (type solid)) (layer "B.Fab"))
    (fp_line (start -0.494 0.25) (end 0.504 0.25)
      (stroke (width 0.15) (type solid)) (layer "B.Fab"))
    (fp_line (start 0.504 -0.248) (end -0.494 -0.248)
      (stroke (width 0.15) (type solid)) (layer "B.Fab"))
    (fp_line (start 0.504 0.25) (end 0.504 -0.248)
      (stroke (width 0.15) (type solid)) (layer "B.Fab"))
    (pad "1" smd roundrect (at -0.48 0) (size 0.59 0.64) (layers "B.Cu" "B.Paste" "B.Mask") (roundrect_rratio 0.25)
      (net 1 "GND") (pintype "passive"))
    (pad "2" smd roundrect (at 0.48 0) (size 0.59 0.64) (layers "B.Cu" "B.Paste" "B.Mask") (roundrect_rratio 0.25)
      (net 304 "/FPGA power supply/VCCAUX") (pintype "passive"))
  )

  (footprint "antmicro-footprints:C_0402_1005Metric" (layer "B.Cu")
    (at 103.6 124.065 90)
    (descr "Capacitor SMD 0402")
    (tags "capacitor SMD 0402")
    (property "Author" "Antmicro")
    (property "Dielectric" "")
    (property "License" "Apache-2.0")
    (property "MPN" "C1005X5R1E474M050BB")
    (property "Manufacturer" "TDK")
    (property "Public" "False")
    (property "Sheetfile" "fpga-power-supply.kicad_sch")
    (property "Sheetname" "FPGA power supply")
    (property "Val" "470n")
    (property "Voltage" "")
    (property "ki_description" "SMD Multilayer Ceramic Capacitor, 0.47 µF, 25 V, 0402 [1005 Metric], ± 20%, X5R, C")
    (property "ki_keywords" "0402, SMT, CAPACITOR, PASSIVE, CERAMIC, MLCC")
    (attr smd)
    (fp_text reference "C183" (at -21.97 0.89 90) (layer "B.SilkS")
        (effects (font (size 0.7 0.7) (thickness 0.127)) (justify mirror))
    )
    (fp_text value "C_470n_0402" (at 0 -1.17 90) (layer "B.Fab")
        (effects (font (size 1 1) (thickness 0.15)) (justify mirror))
    )
    (fp_text user "License: Apache-2.0" (at -0.939 -5.799 270) (layer "B.Fab") hide
        (effects (font (size 0.7 0.7) (thickness 0.15)) (justify left bottom mirror))
    )
    (fp_text user "Author: Antmicro" (at -0.939 -3.399 270) (layer "B.Fab") hide
        (effects (font (size 0.7 0.7) (thickness 0.15)) (justify left bottom mirror))
    )
    (fp_text user "${REFERENCE}" (at 0 0 90) (layer "B.Fab")
        (effects (font (size 0.25 0.25) (thickness 0.04)) (justify mirror))
    )
    (fp_rect (start -0.925 0.47) (end 0.925 -0.47)
      (stroke (width 0.05) (type default)) (fill none) (layer "B.CrtYd"))
    (fp_line (start -0.494 -0.248) (end -0.494 0.25)
      (stroke (width 0.15) (type solid)) (layer "B.Fab"))
    (fp_line (start -0.494 0.25) (end 0.504 0.25)
      (stroke (width 0.15) (type solid)) (layer "B.Fab"))
    (fp_line (start 0.504 -0.248) (end -0.494 -0.248)
      (stroke (width 0.15) (type solid)) (layer "B.Fab"))
    (fp_line (start 0.504 0.25) (end 0.504 -0.248)
      (stroke (width 0.15) (type solid)) (layer "B.Fab"))
    (pad "1" smd roundrect (at -0.48 0 90) (size 0.59 0.64) (layers "B.Cu" "B.Paste" "B.Mask") (roundrect_rratio 0.25)
      (net 211 "VCC1V2") (pintype "passive"))
    (pad "2" smd roundrect (at 0.48 0 90) (size 0.59 0.64) (layers "B.Cu" "B.Paste" "B.Mask") (roundrect_rratio 0.25)
      (net 1 "GND") (pintype "passive"))
  )

  (footprint "antmicro-footprints:C_0402_1005Metric" (layer "B.Cu")
    (at 102.95 132.235 90)
    (descr "Capacitor SMD 0402")
    (tags "capacitor SMD 0402")
    (property "Author" "Antmicro")
    (property "Dielectric" "")
    (property "License" "Apache-2.0")
    (property "MPN" "C1005X5R1E474M050BB")
    (property "Manufacturer" "TDK")
    (property "Public" "False")
    (property "Sheetfile" "fpga-power-supply.kicad_sch")
    (property "Sheetname" "FPGA power supply")
    (property "Val" "470n")
    (property "Voltage" "")
    (property "ki_description" "SMD Multilayer Ceramic Capacitor, 0.47 µF, 25 V, 0402 [1005 Metric], ± 20%, X5R, C")
    (property "ki_keywords" "0402, SMT, CAPACITOR, PASSIVE, CERAMIC, MLCC")
    (attr smd)
    (fp_text reference "C184" (at -20.78 0.91 90) (layer "B.SilkS")
        (effects (font (size 0.7 0.7) (thickness 0.127)) (justify mirror))
    )
    (fp_text value "C_470n_0402" (at 0 -1.17 90) (layer "B.Fab")
        (effects (font (size 1 1) (thickness 0.15)) (justify mirror))
    )
    (fp_text user "${REFERENCE}" (at 0 0 90) (layer "B.Fab")
        (effects (font (size 0.25 0.25) (thickness 0.04)) (justify mirror))
    )
    (fp_text user "Author: Antmicro" (at -0.939 -3.399 270) (layer "B.Fab") hide
        (effects (font (size 0.7 0.7) (thickness 0.15)) (justify left bottom mirror))
    )
    (fp_text user "License: Apache-2.0" (at -0.939 -5.799 270) (layer "B.Fab") hide
        (effects (font (size 0.7 0.7) (thickness 0.15)) (justify left bottom mirror))
    )
    (fp_rect (start -0.925 0.47) (end 0.925 -0.47)
      (stroke (width 0.05) (type default)) (fill none) (layer "B.CrtYd"))
    (fp_line (start -0.494 -0.248) (end -0.494 0.25)
      (stroke (width 0.15) (type solid)) (layer "B.Fab"))
    (fp_line (start -0.494 0.25) (end 0.504 0.25)
      (stroke (width 0.15) (type solid)) (layer "B.Fab"))
    (fp_line (start 0.504 -0.248) (end -0.494 -0.248)
      (stroke (width 0.15) (type solid)) (layer "B.Fab"))
    (fp_line (start 0.504 0.25) (end 0.504 -0.248)
      (stroke (width 0.15) (type solid)) (layer "B.Fab"))
    (pad "1" smd roundrect (at -0.48 0 90) (size 0.59 0.64) (layers "B.Cu" "B.Paste" "B.Mask") (roundrect_rratio 0.25)
      (net 1 "GND") (pintype "passive"))
    (pad "2" smd roundrect (at 0.48 0 90) (size 0.59 0.64) (layers "B.Cu" "B.Paste" "B.Mask") (roundrect_rratio 0.25)
      (net 304 "/FPGA power supply/VCCAUX") (pintype "passive"))
  )

  (footprint "antmicro-footprints:C_0402_1005Metric" (layer "B.Cu")
    (at 105.2 124.05 90)
    (descr "Capacitor SMD 0402")
    (tags "capacitor SMD 0402")
    (property "Author" "Antmicro")
    (property "Dielectric" "")
    (property "License" "Apache-2.0")
    (property "MPN" "C1005X5R1E474M050BB")
    (property "Manufacturer" "TDK")
    (property "Public" "False")
    (property "Sheetfile" "fpga-power-supply.kicad_sch")
    (property "Sheetname" "FPGA power supply")
    (property "Val" "470n")
    (property "Voltage" "")
    (property "ki_description" "SMD Multilayer Ceramic Capacitor, 0.47 µF, 25 V, 0402 [1005 Metric], ± 20%, X5R, C")
    (property "ki_keywords" "0402, SMT, CAPACITOR, PASSIVE, CERAMIC, MLCC")
    (attr smd)
    (fp_text reference "C185" (at -22.005 0.43 90) (layer "B.SilkS")
        (effects (font (size 0.7 0.7) (thickness 0.127)) (justify mirror))
    )
    (fp_text value "C_470n_0402" (at 0 -1.17 90) (layer "B.Fab")
        (effects (font (size 1 1) (thickness 0.15)) (justify mirror))
    )
    (fp_text user "License: Apache-2.0" (at -0.939 -5.799 270) (layer "B.Fab") hide
        (effects (font (size 0.7 0.7) (thickness 0.15)) (justify left bottom mirror))
    )
    (fp_text user "${REFERENCE}" (at 0 0 90) (layer "B.Fab")
        (effects (font (size 0.25 0.25) (thickness 0.04)) (justify mirror))
    )
    (fp_text user "Author: Antmicro" (at -0.939 -3.399 270) (layer "B.Fab") hide
        (effects (font (size 0.7 0.7) (thickness 0.15)) (justify left bottom mirror))
    )
    (fp_rect (start -0.925 0.47) (end 0.925 -0.47)
      (stroke (width 0.05) (type default)) (fill none) (layer "B.CrtYd"))
    (fp_line (start -0.494 -0.248) (end -0.494 0.25)
      (stroke (width 0.15) (type solid)) (layer "B.Fab"))
    (fp_line (start -0.494 0.25) (end 0.504 0.25)
      (stroke (width 0.15) (type solid)) (layer "B.Fab"))
    (fp_line (start 0.504 -0.248) (end -0.494 -0.248)
      (stroke (width 0.15) (type solid)) (layer "B.Fab"))
    (fp_line (start 0.504 0.25) (end 0.504 -0.248)
      (stroke (width 0.15) (type solid)) (layer "B.Fab"))
    (pad "1" smd roundrect (at -0.48 0 90) (size 0.59 0.64) (layers "B.Cu" "B.Paste" "B.Mask") (roundrect_rratio 0.25)
      (net 211 "VCC1V2") (pintype "passive"))
    (pad "2" smd roundrect (at 0.48 0 90) (size 0.59 0.64) (layers "B.Cu" "B.Paste" "B.Mask") (roundrect_rratio 0.25)
      (net 1 "GND") (pintype "passive"))
  )

  (footprint "antmicro-footprints:C_0402_1005Metric" (layer "B.Cu")
    (at 103.975 132.25 90)
    (descr "Capacitor SMD 0402")
    (tags "capacitor SMD 0402")
    (property "Author" "Antmicro")
    (property "Dielectric" "")
    (property "License" "Apache-2.0")
    (property "MPN" "C1005X5R1E474M050BB")
    (property "Manufacturer" "TDK")
    (property "Public" "False")
    (property "Sheetfile" "fpga-power-supply.kicad_sch")
    (property "Sheetname" "FPGA power supply")
    (property "Val" "470n")
    (property "Voltage" "")
    (property "ki_description" "SMD Multilayer Ceramic Capacitor, 0.47 µF, 25 V, 0402 [1005 Metric], ± 20%, X5R, C")
    (property "ki_keywords" "0402, SMT, CAPACITOR, PASSIVE, CERAMIC, MLCC")
    (attr smd)
    (fp_text reference "C186" (at -20.785 0.855 90) (layer "B.SilkS")
        (effects (font (size 0.7 0.7) (thickness 0.127)) (justify mirror))
    )
    (fp_text value "C_470n_0402" (at 0 -1.17 90) (layer "B.Fab")
        (effects (font (size 1 1) (thickness 0.15)) (justify mirror))
    )
    (fp_text user "License: Apache-2.0" (at -0.939 -5.799 270) (layer "B.Fab") hide
        (effects (font (size 0.7 0.7) (thickness 0.15)) (justify left bottom mirror))
    )
    (fp_text user "${REFERENCE}" (at 0 0 90) (layer "B.Fab")
        (effects (font (size 0.25 0.25) (thickness 0.04)) (justify mirror))
    )
    (fp_text user "Author: Antmicro" (at -0.939 -3.399 270) (layer "B.Fab") hide
        (effects (font (size 0.7 0.7) (thickness 0.15)) (justify left bottom mirror))
    )
    (fp_rect (start -0.925 0.47) (end 0.925 -0.47)
      (stroke (width 0.05) (type default)) (fill none) (layer "B.CrtYd"))
    (fp_line (start -0.494 -0.248) (end -0.494 0.25)
      (stroke (width 0.15) (type solid)) (layer "B.Fab"))
    (fp_line (start -0.494 0.25) (end 0.504 0.25)
      (stroke (width 0.15) (type solid)) (layer "B.Fab"))
    (fp_line (start 0.504 -0.248) (end -0.494 -0.248)
      (stroke (width 0.15) (type solid)) (layer "B.Fab"))
    (fp_line (start 0.504 0.25) (end 0.504 -0.248)
      (stroke (width 0.15) (type solid)) (layer "B.Fab"))
    (pad "1" smd roundrect (at -0.48 0 90) (size 0.59 0.64) (layers "B.Cu" "B.Paste" "B.Mask") (roundrect_rratio 0.25)
      (net 1 "GND") (pintype "passive"))
    (pad "2" smd roundrect (at 0.48 0 90) (size 0.59 0.64) (layers "B.Cu" "B.Paste" "B.Mask") (roundrect_rratio 0.25)
      (net 304 "/FPGA power supply/VCCAUX") (pintype "passive"))
  )

  (footprint "antmicro-footprints:C_0402_1005Metric" (layer "B.Cu")
    (at 102 124.065 90)
    (descr "Capacitor SMD 0402")
    (tags "capacitor SMD 0402")
    (property "Author" "Antmicro")
    (property "Dielectric" "")
    (property "License" "Apache-2.0")
    (property "MPN" "C1005X5R1E474M050BB")
    (property "Manufacturer" "TDK")
    (property "Public" "False")
    (property "Sheetfile" "fpga-power-supply.kicad_sch")
    (property "Sheetname" "FPGA power supply")
    (property "Val" "470n")
    (property "Voltage" "")
    (property "ki_description" "SMD Multilayer Ceramic Capacitor, 0.47 µF, 25 V, 0402 [1005 Metric], ± 20%, X5R, C")
    (property "ki_keywords" "0402, SMT, CAPACITOR, PASSIVE, CERAMIC, MLCC")
    (attr smd)
    (fp_text reference "C187" (at -22.02 -0.18 90) (layer "B.SilkS")
        (effects (font (size 0.7 0.7) (thickness 0.127)) (justify mirror))
    )
    (fp_text value "C_470n_0402" (at 0 -1.17 90) (layer "B.Fab")
        (effects (font (size 1 1) (thickness 0.15)) (justify mirror))
    )
    (fp_text user "License: Apache-2.0" (at -0.939 -5.799 270) (layer "B.Fab") hide
        (effects (font (size 0.7 0.7) (thickness 0.15)) (justify left bottom mirror))
    )
    (fp_text user "Author: Antmicro" (at -0.939 -3.399 270) (layer "B.Fab") hide
        (effects (font (size 0.7 0.7) (thickness 0.15)) (justify left bottom mirror))
    )
    (fp_text user "${REFERENCE}" (at 0 0 90) (layer "B.Fab")
        (effects (font (size 0.25 0.25) (thickness 0.04)) (justify mirror))
    )
    (fp_rect (start -0.925 0.47) (end 0.925 -0.47)
      (stroke (width 0.05) (type default)) (fill none) (layer "B.CrtYd"))
    (fp_line (start -0.494 -0.248) (end -0.494 0.25)
      (stroke (width 0.15) (type solid)) (layer "B.Fab"))
    (fp_line (start -0.494 0.25) (end 0.504 0.25)
      (stroke (width 0.15) (type solid)) (layer "B.Fab"))
    (fp_line (start 0.504 -0.248) (end -0.494 -0.248)
      (stroke (width 0.15) (type solid)) (layer "B.Fab"))
    (fp_line (start 0.504 0.25) (end 0.504 -0.248)
      (stroke (width 0.15) (type solid)) (layer "B.Fab"))
    (pad "1" smd roundrect (at -0.48 0 90) (size 0.59 0.64) (layers "B.Cu" "B.Paste" "B.Mask") (roundrect_rratio 0.25)
      (net 211 "VCC1V2") (pintype "passive"))
    (pad "2" smd roundrect (at 0.48 0 90) (size 0.59 0.64) (layers "B.Cu" "B.Paste" "B.Mask") (roundrect_rratio 0.25)
      (net 1 "GND") (pintype "passive"))
  )

  (footprint "antmicro-footprints:C_0402_1005Metric" (layer "B.Cu")
    (at 101.4 122.15)
    (descr "Capacitor SMD 0402")
    (tags "capacitor SMD 0402")
    (property "Author" "Antmicro")
    (property "Dielectric" "")
    (property "License" "Apache-2.0")
    (property "MPN" "C1005X5R1E474M050BB")
    (property "Manufacturer" "TDK")
    (property "Public" "False")
    (property "Sheetfile" "fpga-power-supply.kicad_sch")
    (property "Sheetname" "FPGA power supply")
    (property "Val" "470n")
    (property "Voltage" "")
    (property "ki_description" "SMD Multilayer Ceramic Capacitor, 0.47 µF, 25 V, 0402 [1005 Metric], ± 20%, X5R, C")
    (property "ki_keywords" "0402, SMT, CAPACITOR, PASSIVE, CERAMIC, MLCC")
    (attr smd)
    (fp_text reference "C188" (at -0.07 22.205) (layer "B.SilkS")
        (effects (font (size 0.7 0.7) (thickness 0.127)) (justify mirror))
    )
    (fp_text value "C_470n_0402" (at 0 -1.17) (layer "B.Fab")
        (effects (font (size 1 1) (thickness 0.15)) (justify mirror))
    )
    (fp_text user "Author: Antmicro" (at -0.939 -3.399 180) (layer "B.Fab") hide
        (effects (font (size 0.7 0.7) (thickness 0.15)) (justify left bottom mirror))
    )
    (fp_text user "${REFERENCE}" (at 0 0) (layer "B.Fab")
        (effects (font (size 0.25 0.25) (thickness 0.04)) (justify mirror))
    )
    (fp_text user "License: Apache-2.0" (at -0.939 -5.799 180) (layer "B.Fab") hide
        (effects (font (size 0.7 0.7) (thickness 0.15)) (justify left bottom mirror))
    )
    (fp_rect (start -0.925 0.47) (end 0.925 -0.47)
      (stroke (width 0.05) (type default)) (fill none) (layer "B.CrtYd"))
    (fp_line (start -0.494 -0.248) (end -0.494 0.25)
      (stroke (width 0.15) (type solid)) (layer "B.Fab"))
    (fp_line (start -0.494 0.25) (end 0.504 0.25)
      (stroke (width 0.15) (type solid)) (layer "B.Fab"))
    (fp_line (start 0.504 -0.248) (end -0.494 -0.248)
      (stroke (width 0.15) (type solid)) (layer "B.Fab"))
    (fp_line (start 0.504 0.25) (end 0.504 -0.248)
      (stroke (width 0.15) (type solid)) (layer "B.Fab"))
    (pad "1" smd roundrect (at -0.48 0) (size 0.59 0.64) (layers "B.Cu" "B.Paste" "B.Mask") (roundrect_rratio 0.25)
      (net 211 "VCC1V2") (pintype "passive"))
    (pad "2" smd roundrect (at 0.48 0) (size 0.59 0.64) (layers "B.Cu" "B.Paste" "B.Mask") (roundrect_rratio 0.25)
      (net 1 "GND") (pintype "passive"))
  )

  (footprint "antmicro-footprints:C_0402_1005Metric" (layer "B.Cu")
    (at 101.4 120.5)
    (descr "Capacitor SMD 0402")
    (tags "capacitor SMD 0402")
    (property "Author" "Antmicro")
    (property "Dielectric" "")
    (property "License" "Apache-2.0")
    (property "MPN" "C1005X5R1E474M050BB")
    (property "Manufacturer" "TDK")
    (property "Public" "False")
    (property "Sheetfile" "fpga-power-supply.kicad_sch")
    (property "Sheetname" "FPGA power supply")
    (property "Val" "470n")
    (property "Voltage" "")
    (property "ki_description" "SMD Multilayer Ceramic Capacitor, 0.47 µF, 25 V, 0402 [1005 Metric], ± 20%, X5R, C")
    (property "ki_keywords" "0402, SMT, CAPACITOR, PASSIVE, CERAMIC, MLCC")
    (attr smd)
    (fp_text reference "C189" (at -0.05 22.85) (layer "B.SilkS")
        (effects (font (size 0.7 0.7) (thickness 0.127)) (justify mirror))
    )
    (fp_text value "C_470n_0402" (at 0 -1.17) (layer "B.Fab")
        (effects (font (size 1 1) (thickness 0.15)) (justify mirror))
    )
    (fp_text user "Author: Antmicro" (at -0.939 -3.399 180) (layer "B.Fab") hide
        (effects (font (size 0.7 0.7) (thickness 0.15)) (justify left bottom mirror))
    )
    (fp_text user "License: Apache-2.0" (at -0.939 -5.799 180) (layer "B.Fab") hide
        (effects (font (size 0.7 0.7) (thickness 0.15)) (justify left bottom mirror))
    )
    (fp_text user "${REFERENCE}" (at 0 0) (layer "B.Fab")
        (effects (font (size 0.25 0.25) (thickness 0.04)) (justify mirror))
    )
    (fp_rect (start -0.925 0.47) (end 0.925 -0.47)
      (stroke (width 0.05) (type default)) (fill none) (layer "B.CrtYd"))
    (fp_line (start -0.494 -0.248) (end -0.494 0.25)
      (stroke (width 0.15) (type solid)) (layer "B.Fab"))
    (fp_line (start -0.494 0.25) (end 0.504 0.25)
      (stroke (width 0.15) (type solid)) (layer "B.Fab"))
    (fp_line (start 0.504 -0.248) (end -0.494 -0.248)
      (stroke (width 0.15) (type solid)) (layer "B.Fab"))
    (fp_line (start 0.504 0.25) (end 0.504 -0.248)
      (stroke (width 0.15) (type solid)) (layer "B.Fab"))
    (pad "1" smd roundrect (at -0.48 0) (size 0.59 0.64) (layers "B.Cu" "B.Paste" "B.Mask") (roundrect_rratio 0.25)
      (net 211 "VCC1V2") (pintype "passive"))
    (pad "2" smd roundrect (at 0.48 0) (size 0.59 0.64) (layers "B.Cu" "B.Paste" "B.Mask") (roundrect_rratio 0.25)
      (net 1 "GND") (pintype "passive"))
  )

  (footprint "antmicro-footprints:C_0402_1005Metric" (layer "B.Cu")
    (at 101.4 118.95)
    (descr "Capacitor SMD 0402")
    (tags "capacitor SMD 0402")
    (property "Author" "Antmicro")
    (property "Dielectric" "")
    (property "License" "Apache-2.0")
    (property "MPN" "C1005X5R1E474M050BB")
    (property "Manufacturer" "TDK")
    (property "Public" "False")
    (property "Sheetfile" "fpga-power-supply.kicad_sch")
    (property "Sheetname" "FPGA power supply")
    (property "Val" "470n")
    (property "Voltage" "")
    (property "ki_description" "SMD Multilayer Ceramic Capacitor, 0.47 µF, 25 V, 0402 [1005 Metric], ± 20%, X5R, C")
    (property "ki_keywords" "0402, SMT, CAPACITOR, PASSIVE, CERAMIC, MLCC")
    (attr smd)
    (fp_text reference "C190" (at -0.05 22.85) (layer "B.SilkS")
        (effects (font (size 0.7 0.7) (thickness 0.127)) (justify mirror))
    )
    (fp_text value "C_470n_0402" (at 0 -1.17) (layer "B.Fab")
        (effects (font (size 1 1) (thickness 0.15)) (justify mirror))
    )
    (fp_text user "Author: Antmicro" (at -0.939 -3.399 180) (layer "B.Fab") hide
        (effects (font (size 0.7 0.7) (thickness 0.15)) (justify left bottom mirror))
    )
    (fp_text user "License: Apache-2.0" (at -0.939 -5.799 180) (layer "B.Fab") hide
        (effects (font (size 0.7 0.7) (thickness 0.15)) (justify left bottom mirror))
    )
    (fp_text user "${REFERENCE}" (at 0 0) (layer "B.Fab")
        (effects (font (size 0.25 0.25) (thickness 0.04)) (justify mirror))
    )
    (fp_rect (start -0.925 0.47) (end 0.925 -0.47)
      (stroke (width 0.05) (type default)) (fill none) (layer "B.CrtYd"))
    (fp_line (start -0.494 -0.248) (end -0.494 0.25)
      (stroke (width 0.15) (type solid)) (layer "B.Fab"))
    (fp_line (start -0.494 0.25) (end 0.504 0.25)
      (stroke (width 0.15) (type solid)) (layer "B.Fab"))
    (fp_line (start 0.504 -0.248) (end -0.494 -0.248)
      (stroke (width 0.15) (type solid)) (layer "B.Fab"))
    (fp_line (start 0.504 0.25) (end 0.504 -0.248)
      (stroke (width 0.15) (type solid)) (layer "B.Fab"))
    (pad "1" smd roundrect (at -0.48 0) (size 0.59 0.64) (layers "B.Cu" "B.Paste" "B.Mask") (roundrect_rratio 0.25)
      (net 211 "VCC1V2") (pintype "passive"))
    (pad "2" smd roundrect (at 0.48 0) (size 0.59 0.64) (layers "B.Cu" "B.Paste" "B.Mask") (roundrect_rratio 0.25)
      (net 1 "GND") (pintype "passive"))
  )

  (footprint "antmicro-footprints:C_0402_1005Metric" (layer "B.Cu")
    (at 101.95 117.05 -90)
    (descr "Capacitor SMD 0402")
    (tags "capacitor SMD 0402")
    (property "Author" "Antmicro")
    (property "Dielectric" "")
    (property "License" "Apache-2.0")
    (property "MPN" "C1005X5R1E474M050BB")
    (property "Manufacturer" "TDK")
    (property "Public" "False")
    (property "Sheetfile" "fpga-power-supply.kicad_sch")
    (property "Sheetname" "FPGA power supply")
    (property "Val" "470n")
    (property "Voltage" "")
    (property "ki_description" "SMD Multilayer Ceramic Capacitor, 0.47 µF, 25 V, 0402 [1005 Metric], ± 20%, X5R, C")
    (property "ki_keywords" "0402, SMT, CAPACITOR, PASSIVE, CERAMIC, MLCC")
    (attr smd)
    (fp_text reference "C191" (at 22.65 0.05 90) (layer "B.SilkS")
        (effects (font (size 0.7 0.7) (thickness 0.127)) (justify mirror))
    )
    (fp_text value "C_470n_0402" (at 0 -1.17 90) (layer "B.Fab")
        (effects (font (size 1 1) (thickness 0.15)) (justify mirror))
    )
    (fp_text user "Author: Antmicro" (at -0.939 -3.399 90) (layer "B.Fab") hide
        (effects (font (size 0.7 0.7) (thickness 0.15)) (justify left bottom mirror))
    )
    (fp_text user "${REFERENCE}" (at 0 0 90) (layer "B.Fab")
        (effects (font (size 0.25 0.25) (thickness 0.04)) (justify mirror))
    )
    (fp_text user "License: Apache-2.0" (at -0.939 -5.799 90) (layer "B.Fab") hide
        (effects (font (size 0.7 0.7) (thickness 0.15)) (justify left bottom mirror))
    )
    (fp_rect (start -0.925 0.47) (end 0.925 -0.47)
      (stroke (width 0.05) (type default)) (fill none) (layer "B.CrtYd"))
    (fp_line (start -0.494 -0.248) (end -0.494 0.25)
      (stroke (width 0.15) (type solid)) (layer "B.Fab"))
    (fp_line (start -0.494 0.25) (end 0.504 0.25)
      (stroke (width 0.15) (type solid)) (layer "B.Fab"))
    (fp_line (start 0.504 -0.248) (end -0.494 -0.248)
      (stroke (width 0.15) (type solid)) (layer "B.Fab"))
    (fp_line (start 0.504 0.25) (end 0.504 -0.248)
      (stroke (width 0.15) (type solid)) (layer "B.Fab"))
    (pad "1" smd roundrect (at -0.48 0 270) (size 0.59 0.64) (layers "B.Cu" "B.Paste" "B.Mask") (roundrect_rratio 0.25)
      (net 211 "VCC1V2") (pintype "passive"))
    (pad "2" smd roundrect (at 0.48 0 270) (size 0.59 0.64) (layers "B.Cu" "B.Paste" "B.Mask") (roundrect_rratio 0.25)
      (net 1 "GND") (pintype "passive"))
  )

  (footprint "antmicro-footprints:C_0402_1005Metric" (layer "B.Cu")
    (at 103.55 117.05 -90)
    (descr "Capacitor SMD 0402")
    (tags "capacitor SMD 0402")
    (property "Author" "Antmicro")
    (property "Dielectric" "")
    (property "License" "Apache-2.0")
    (property "MPN" "C1005X5R1E474M050BB")
    (property "Manufacturer" "TDK")
    (property "Public" "False")
    (property "Sheetfile" "fpga-power-supply.kicad_sch")
    (property "Sheetname" "FPGA power supply")
    (property "Val" "470n")
    (property "Voltage" "")
    (property "ki_description" "SMD Multilayer Ceramic Capacitor, 0.47 µF, 25 V, 0402 [1005 Metric], ± 20%, X5R, C")
    (property "ki_keywords" "0402, SMT, CAPACITOR, PASSIVE, CERAMIC, MLCC")
    (attr smd)
    (fp_text reference "C192" (at 22.65 0.05 90) (layer "B.SilkS")
        (effects (font (size 0.7 0.7) (thickness 0.127)) (justify mirror))
    )
    (fp_text value "C_470n_0402" (at 0 -1.17 90) (layer "B.Fab")
        (effects (font (size 1 1) (thickness 0.15)) (justify mirror))
    )
    (fp_text user "${REFERENCE}" (at 0 0 90) (layer "B.Fab")
        (effects (font (size 0.25 0.25) (thickness 0.04)) (justify mirror))
    )
    (fp_text user "License: Apache-2.0" (at -0.939 -5.799 90) (layer "B.Fab") hide
        (effects (font (size 0.7 0.7) (thickness 0.15)) (justify left bottom mirror))
    )
    (fp_text user "Author: Antmicro" (at -0.939 -3.399 90) (layer "B.Fab") hide
        (effects (font (size 0.7 0.7) (thickness 0.15)) (justify left bottom mirror))
    )
    (fp_rect (start -0.925 0.47) (end 0.925 -0.47)
      (stroke (width 0.05) (type default)) (fill none) (layer "B.CrtYd"))
    (fp_line (start -0.494 -0.248) (end -0.494 0.25)
      (stroke (width 0.15) (type solid)) (layer "B.Fab"))
    (fp_line (start -0.494 0.25) (end 0.504 0.25)
      (stroke (width 0.15) (type solid)) (layer "B.Fab"))
    (fp_line (start 0.504 -0.248) (end -0.494 -0.248)
      (stroke (width 0.15) (type solid)) (layer "B.Fab"))
    (fp_line (start 0.504 0.25) (end 0.504 -0.248)
      (stroke (width 0.15) (type solid)) (layer "B.Fab"))
    (pad "1" smd roundrect (at -0.48 0 270) (size 0.59 0.64) (layers "B.Cu" "B.Paste" "B.Mask") (roundrect_rratio 0.25)
      (net 211 "VCC1V2") (pintype "passive"))
    (pad "2" smd roundrect (at 0.48 0 270) (size 0.59 0.64) (layers "B.Cu" "B.Paste" "B.Mask") (roundrect_rratio 0.25)
      (net 1 "GND") (pintype "passive"))
  )

  (footprint "antmicro-footprints:C_0402_1005Metric" (layer "B.Cu")
    (at 100.5 117 90)
    (descr "Capacitor SMD 0402")
    (tags "capacitor SMD 0402")
    (property "Author" "Antmicro")
    (property "Dielectric" "")
    (property "License" "Apache-2.0")
    (property "MPN" "C1005X5R1E474M050BB")
    (property "Manufacturer" "TDK")
    (property "Public" "False")
    (property "Sheetfile" "fpga-power-supply.kicad_sch")
    (property "Sheetname" "FPGA power supply")
    (property "Val" "470n")
    (property "Voltage" "")
    (property "ki_description" "SMD Multilayer Ceramic Capacitor, 0.47 µF, 25 V, 0402 [1005 Metric], ± 20%, X5R, C")
    (property "ki_keywords" "0402, SMT, CAPACITOR, PASSIVE, CERAMIC, MLCC")
    (attr smd)
    (fp_text reference "C193" (at -22.7 -0.05 90) (layer "B.SilkS")
        (effects (font (size 0.7 0.7) (thickness 0.127)) (justify mirror))
    )
    (fp_text value "C_470n_0402" (at 0 -1.17 90) (layer "B.Fab")
        (effects (font (size 1 1) (thickness 0.15)) (justify mirror))
    )
    (fp_text user "Author: Antmicro" (at -0.939 -3.399 270) (layer "B.Fab") hide
        (effects (font (size 0.7 0.7) (thickness 0.15)) (justify left bottom mirror))
    )
    (fp_text user "${REFERENCE}" (at 0 0 90) (layer "B.Fab")
        (effects (font (size 0.25 0.25) (thickness 0.04)) (justify mirror))
    )
    (fp_text user "License: Apache-2.0" (at -0.939 -5.799 270) (layer "B.Fab") hide
        (effects (font (size 0.7 0.7) (thickness 0.15)) (justify left bottom mirror))
    )
    (fp_rect (start -0.925 0.47) (end 0.925 -0.47)
      (stroke (width 0.05) (type default)) (fill none) (layer "B.CrtYd"))
    (fp_line (start -0.494 -0.248) (end -0.494 0.25)
      (stroke (width 0.15) (type solid)) (layer "B.Fab"))
    (fp_line (start -0.494 0.25) (end 0.504 0.25)
      (stroke (width 0.15) (type solid)) (layer "B.Fab"))
    (fp_line (start 0.504 -0.248) (end -0.494 -0.248)
      (stroke (width 0.15) (type solid)) (layer "B.Fab"))
    (fp_line (start 0.504 0.25) (end 0.504 -0.248)
      (stroke (width 0.15) (type solid)) (layer "B.Fab"))
    (pad "1" smd roundrect (at -0.48 0 90) (size 0.59 0.64) (layers "B.Cu" "B.Paste" "B.Mask") (roundrect_rratio 0.25)
      (net 211 "VCC1V2") (pintype "passive"))
    (pad "2" smd roundrect (at 0.48 0 90) (size 0.59 0.64) (layers "B.Cu" "B.Paste" "B.Mask") (roundrect_rratio 0.25)
      (net 1 "GND") (pintype "passive"))
  )

  (footprint "antmicro-footprints:C_0402_1005Metric" (layer "B.Cu")
    (at 99.25 115.05 180)
    (descr "Capacitor SMD 0402")
    (tags "capacitor SMD 0402")
    (property "Author" "Antmicro")
    (property "Dielectric" "")
    (property "License" "Apache-2.0")
    (property "MPN" "GRM155R61A475MEAAD")
    (property "Manufacturer" "Murata")
    (property "Public" "False")
    (property "Sheetfile" "fpga-banks.kicad_sch")
    (property "Sheetname" "FPGA banks")
    (property "Val" "4u7")
    (property "Voltage" "")
    (property "ki_description" "SMD Multilayer Ceramic Capacitor, 4.7 µF, 10 V, 0402 [1005 Metric], ± 20%, X5R, GRM Series")
    (property "ki_keywords" "0402, SMT, CAPACITOR, PASSIVE")
    (attr smd)
    (fp_text reference "C203" (at 2.35 0.2) (layer "B.SilkS")
        (effects (font (size 0.7 0.7) (thickness 0.127)) (justify mirror))
    )
    (fp_text value "C_4u7_0402" (at 0 -1.17) (layer "B.Fab")
        (effects (font (size 1 1) (thickness 0.15)) (justify mirror))
    )
    (fp_text user "Author: Antmicro" (at -0.939 -3.399) (layer "B.Fab") hide
        (effects (font (size 0.7 0.7) (thickness 0.15)) (justify left bottom mirror))
    )
    (fp_text user "${REFERENCE}" (at 0 0) (layer "B.Fab")
        (effects (font (size 0.25 0.25) (thickness 0.04)) (justify mirror))
    )
    (fp_text user "License: Apache-2.0" (at -0.939 -5.799) (layer "B.Fab") hide
        (effects (font (size 0.7 0.7) (thickness 0.15)) (justify left bottom mirror))
    )
    (fp_rect (start -0.925 0.47) (end 0.925 -0.47)
      (stroke (width 0.05) (type default)) (fill none) (layer "B.CrtYd"))
    (fp_line (start -0.494 -0.248) (end -0.494 0.25)
      (stroke (width 0.15) (type solid)) (layer "B.Fab"))
    (fp_line (start -0.494 0.25) (end 0.504 0.25)
      (stroke (width 0.15) (type solid)) (layer "B.Fab"))
    (fp_line (start 0.504 -0.248) (end -0.494 -0.248)
      (stroke (width 0.15) (type solid)) (layer "B.Fab"))
    (fp_line (start 0.504 0.25) (end 0.504 -0.248)
      (stroke (width 0.15) (type solid)) (layer "B.Fab"))
    (pad "1" smd roundrect (at -0.48 0 180) (size 0.59 0.64) (layers "B.Cu" "B.Paste" "B.Mask") (roundrect_rratio 0.25)
      (net 2 "VCC3V3") (pintype "passive"))
    (pad "2" smd roundrect (at 0.48 0 180) (size 0.59 0.64) (layers "B.Cu" "B.Paste" "B.Mask") (roundrect_rratio 0.25)
      (net 1 "GND") (pintype "passive"))
  )

  (footprint "antmicro-footprints:C_0402_1005Metric" (layer "B.Cu")
    (at 104.4 115.15 -90)
    (descr "Capacitor SMD 0402")
    (tags "capacitor SMD 0402")
    (property "Author" "Antmicro")
    (property "Dielectric" "")
    (property "License" "Apache-2.0")
    (property "MPN" "C1005X5R1E474M050BB")
    (property "Manufacturer" "TDK")
    (property "Public" "False")
    (property "Sheetfile" "fpga-banks.kicad_sch")
    (property "Sheetname" "FPGA banks")
    (property "Val" "470n")
    (property "Voltage" "")
    (property "ki_description" "SMD Multilayer Ceramic Capacitor, 0.47 µF, 25 V, 0402 [1005 Metric], ± 20%, X5R, C")
    (property "ki_keywords" "0402, SMT, CAPACITOR, PASSIVE, CERAMIC, MLCC")
    (attr smd)
    (fp_text reference "C204" (at -4.35 -0.05 90) (layer "B.SilkS")
        (effects (font (size 0.7 0.7) (thickness 0.127)) (justify mirror))
    )
    (fp_text value "C_470n_0402" (at 0 -1.17 90) (layer "B.Fab")
        (effects (font (size 1 1) (thickness 0.15)) (justify mirror))
    )
    (fp_text user "${REFERENCE}" (at 0 0 90) (layer "B.Fab")
        (effects (font (size 0.25 0.25) (thickness 0.04)) (justify mirror))
    )
    (fp_text user "Author: Antmicro" (at -0.939 -3.399 90) (layer "B.Fab") hide
        (effects (font (size 0.7 0.7) (thickness 0.15)) (justify left bottom mirror))
    )
    (fp_text user "License: Apache-2.0" (at -0.939 -5.799 90) (layer "B.Fab") hide
        (effects (font (size 0.7 0.7) (thickness 0.15)) (justify left bottom mirror))
    )
    (fp_rect (start -0.925 0.47) (end 0.925 -0.47)
      (stroke (width 0.05) (type default)) (fill none) (layer "B.CrtYd"))
    (fp_line (start -0.494 -0.248) (end -0.494 0.25)
      (stroke (width 0.15) (type solid)) (layer "B.Fab"))
    (fp_line (start -0.494 0.25) (end 0.504 0.25)
      (stroke (width 0.15) (type solid)) (layer "B.Fab"))
    (fp_line (start 0.504 -0.248) (end -0.494 -0.248)
      (stroke (width 0.15) (type solid)) (layer "B.Fab"))
    (fp_line (start 0.504 0.25) (end 0.504 -0.248)
      (stroke (width 0.15) (type solid)) (layer "B.Fab"))
    (pad "1" smd roundrect (at -0.48 0 270) (size 0.59 0.64) (layers "B.Cu" "B.Paste" "B.Mask") (roundrect_rratio 0.25)
      (net 2 "VCC3V3") (pintype "passive"))
    (pad "2" smd roundrect (at 0.48 0 270) (size 0.59 0.64) (layers "B.Cu" "B.Paste" "B.Mask") (roundrect_rratio 0.25)
      (net 1 "GND") (pintype "passive"))
  )

  (footprint "antmicro-footprints:C_0402_1005Metric" (layer "B.Cu")
    (at 102.75 113.8 90)
    (descr "Capacitor SMD 0402")
    (tags "capacitor SMD 0402")
    (property "Author" "Antmicro")
    (property "Dielectric" "")
    (property "License" "Apache-2.0")
    (property "MPN" "C1005X5R1E474M050BB")
    (property "Manufacturer" "TDK")
    (property "Public" "False")
    (property "Sheetfile" "fpga-banks.kicad_sch")
    (property "Sheetname" "FPGA banks")
    (property "Val" "470n")
    (property "Voltage" "")
    (property "ki_description" "SMD Multilayer Ceramic Capacitor, 0.47 µF, 25 V, 0402 [1005 Metric], ± 20%, X5R, C")
    (property "ki_keywords" "0402, SMT, CAPACITOR, PASSIVE, CERAMIC, MLCC")
    (attr smd)
    (fp_text reference "C206" (at 2.45 -0.05 90) (layer "B.SilkS")
        (effects (font (size 0.7 0.7) (thickness 0.127)) (justify mirror))
    )
    (fp_text value "C_470n_0402" (at 0 -1.17 90) (layer "B.Fab")
        (effects (font (size 1 1) (thickness 0.15)) (justify mirror))
    )
    (fp_text user "Author: Antmicro" (at -0.939 -3.399 270) (layer "B.Fab") hide
        (effects (font (size 0.7 0.7) (thickness 0.15)) (justify left bottom mirror))
    )
    (fp_text user "License: Apache-2.0" (at -0.939 -5.799 270) (layer "B.Fab") hide
        (effects (font (size 0.7 0.7) (thickness 0.15)) (justify left bottom mirror))
    )
    (fp_text user "${REFERENCE}" (at 0 0 90) (layer "B.Fab")
        (effects (font (size 0.25 0.25) (thickness 0.04)) (justify mirror))
    )
    (fp_rect (start -0.925 0.47) (end 0.925 -0.47)
      (stroke (width 0.05) (type default)) (fill none) (layer "B.CrtYd"))
    (fp_line (start -0.494 -0.248) (end -0.494 0.25)
      (stroke (width 0.15) (type solid)) (layer "B.Fab"))
    (fp_line (start -0.494 0.25) (end 0.504 0.25)
      (stroke (width 0.15) (type solid)) (layer "B.Fab"))
    (fp_line (start 0.504 -0.248) (end -0.494 -0.248)
      (stroke (width 0.15) (type solid)) (layer "B.Fab"))
    (fp_line (start 0.504 0.25) (end 0.504 -0.248)
      (stroke (width 0.15) (type solid)) (layer "B.Fab"))
    (pad "1" smd roundrect (at -0.48 0 90) (size 0.59 0.64) (layers "B.Cu" "B.Paste" "B.Mask") (roundrect_rratio 0.25)
      (net 2 "VCC3V3") (pintype "passive"))
    (pad "2" smd roundrect (at 0.48 0 90) (size 0.59 0.64) (layers "B.Cu" "B.Paste" "B.Mask") (roundrect_rratio 0.25)
      (net 1 "GND") (pintype "passive"))
  )

  (footprint "antmicro-footprints:C_0402_1005Metric" (layer "B.Cu")
    (at 99.25 114.05 180)
    (descr "Capacitor SMD 0402")
    (tags "capacitor SMD 0402")
    (property "Author" "Antmicro")
    (property "Dielectric" "")
    (property "License" "Apache-2.0")
    (property "MPN" "C1005X5R1E474M050BB")
    (property "Manufacturer" "TDK")
    (property "Public" "False")
    (property "Sheetfile" "fpga-banks.kicad_sch")
    (property "Sheetname" "FPGA banks")
    (property "Val" "470n")
    (property "Voltage" "")
    (property "ki_description" "SMD Multilayer Ceramic Capacitor, 0.47 µF, 25 V, 0402 [1005 Metric], ± 20%, X5R, C")
    (property "ki_keywords" "0402, SMT, CAPACITOR, PASSIVE, CERAMIC, MLCC")
    (attr smd)
    (fp_text reference "C207" (at 2.4 0.25) (layer "B.SilkS")
        (effects (font (size 0.7 0.7) (thickness 0.127)) (justify mirror))
    )
    (fp_text value "C_470n_0402" (at 0 -1.17) (layer "B.Fab")
        (effects (font (size 1 1) (thickness 0.15)) (justify mirror))
    )
    (fp_text user "Author: Antmicro" (at -0.939 -3.399) (layer "B.Fab") hide
        (effects (font (size 0.7 0.7) (thickness 0.15)) (justify left bottom mirror))
    )
    (fp_text user "License: Apache-2.0" (at -0.939 -5.799) (layer "B.Fab") hide
        (effects (font (size 0.7 0.7) (thickness 0.15)) (justify left bottom mirror))
    )
    (fp_text user "${REFERENCE}" (at 0 0) (layer "B.Fab")
        (effects (font (size 0.25 0.25) (thickness 0.04)) (justify mirror))
    )
    (fp_rect (start -0.925 0.47) (end 0.925 -0.47)
      (stroke (width 0.05) (type default)) (fill none) (layer "B.CrtYd"))
    (fp_line (start -0.494 -0.248) (end -0.494 0.25)
      (stroke (width 0.15) (type solid)) (layer "B.Fab"))
    (fp_line (start -0.494 0.25) (end 0.504 0.25)
      (stroke (width 0.15) (type solid)) (layer "B.Fab"))
    (fp_line (start 0.504 -0.248) (end -0.494 -0.248)
      (stroke (width 0.15) (type solid)) (layer "B.Fab"))
    (fp_line (start 0.504 0.25) (end 0.504 -0.248)
      (stroke (width 0.15) (type solid)) (layer "B.Fab"))
    (pad "1" smd roundrect (at -0.48 0 180) (size 0.59 0.64) (layers "B.Cu" "B.Paste" "B.Mask") (roundrect_rratio 0.25)
      (net 2 "VCC3V3") (pintype "passive"))
    (pad "2" smd roundrect (at 0.48 0 180) (size 0.59 0.64) (layers "B.Cu" "B.Paste" "B.Mask") (roundrect_rratio 0.25)
      (net 1 "GND") (pintype "passive"))
  )

  (footprint "antmicro-footprints:C_0402_1005Metric" (layer "B.Cu")
    (at 109.55 114.95)
    (descr "Capacitor SMD 0402")
    (tags "capacitor SMD 0402")
    (property "Author" "Antmicro")
    (property "Dielectric" "")
    (property "License" "Apache-2.0")
    (property "MPN" "GRM155R61A475MEAAD")
    (property "Manufacturer" "Murata")
    (property "Public" "False")
    (property "Sheetfile" "fpga-banks.kicad_sch")
    (property "Sheetname" "FPGA banks")
    (property "Val" "4u7")
    (property "Voltage" "")
    (property "ki_description" "SMD Multilayer Ceramic Capacitor, 4.7 µF, 10 V, 0402 [1005 Metric], ± 20%, X5R, GRM Series")
    (property "ki_keywords" "0402, SMT, CAPACITOR, PASSIVE")
    (attr smd)
    (fp_text reference "C209" (at 2.8 -0.05) (layer "B.SilkS")
        (effects (font (size 0.7 0.7) (thickness 0.127)) (justify mirror))
    )
    (fp_text value "C_4u7_0402" (at 0 -1.17) (layer "B.Fab")
        (effects (font (size 1 1) (thickness 0.15)) (justify mirror))
    )
    (fp_text user "${REFERENCE}" (at 0 0) (layer "B.Fab")
        (effects (font (size 0.25 0.25) (thickness 0.04)) (justify mirror))
    )
    (fp_text user "License: Apache-2.0" (at -0.939 -5.799 180) (layer "B.Fab") hide
        (effects (font (size 0.7 0.7) (thickness 0.15)) (justify left bottom mirror))
    )
    (fp_text user "Author: Antmicro" (at -0.939 -3.399 180) (layer "B.Fab") hide
        (effects (font (size 0.7 0.7) (thickness 0.15)) (justify left bottom mirror))
    )
    (fp_rect (start -0.925 0.47) (end 0.925 -0.47)
      (stroke (width 0.05) (type default)) (fill none) (layer "B.CrtYd"))
    (fp_line (start -0.494 -0.248) (end -0.494 0.25)
      (stroke (width 0.15) (type solid)) (layer "B.Fab"))
    (fp_line (start -0.494 0.25) (end 0.504 0.25)
      (stroke (width 0.15) (type solid)) (layer "B.Fab"))
    (fp_line (start 0.504 -0.248) (end -0.494 -0.248)
      (stroke (width 0.15) (type solid)) (layer "B.Fab"))
    (fp_line (start 0.504 0.25) (end 0.504 -0.248)
      (stroke (width 0.15) (type solid)) (layer "B.Fab"))
    (pad "1" smd roundrect (at -0.48 0) (size 0.59 0.64) (layers "B.Cu" "B.Paste" "B.Mask") (roundrect_rratio 0.25)
      (net 2 "VCC3V3") (pintype "passive"))
    (pad "2" smd roundrect (at 0.48 0) (size 0.59 0.64) (layers "B.Cu" "B.Paste" "B.Mask") (roundrect_rratio 0.25)
      (net 1 "GND") (pintype "passive"))
  )

  (footprint "antmicro-footprints:C_0402_1005Metric" (layer "B.Cu")
    (at 111.25 124.775)
    (descr "Capacitor SMD 0402")
    (tags "capacitor SMD 0402")
    (property "Author" "Antmicro")
    (property "Dielectric" "")
    (property "License" "Apache-2.0")
    (property "MPN" "C1005X5R1E474M050BB")
    (property "Manufacturer" "TDK")
    (property "Public" "False")
    (property "Sheetfile" "fpga-banks.kicad_sch")
    (property "Sheetname" "FPGA banks")
    (property "Val" "470n")
    (property "Voltage" "")
    (property "ki_description" "SMD Multilayer Ceramic Capacitor, 0.47 µF, 25 V, 0402 [1005 Metric], ± 20%, X5R, C")
    (property "ki_keywords" "0402, SMT, CAPACITOR, PASSIVE, CERAMIC, MLCC")
    (attr smd)
    (fp_text reference "C210" (at 2.55 -0.025) (layer "B.SilkS")
        (effects (font (size 0.7 0.7) (thickness 0.127)) (justify mirror))
    )
    (fp_text value "C_470n_0402" (at 0 -1.17) (layer "B.Fab")
        (effects (font (size 1 1) (thickness 0.15)) (justify mirror))
    )
    (fp_text user "Author: Antmicro" (at -0.939 -3.399 180) (layer "B.Fab") hide
        (effects (font (size 0.7 0.7) (thickness 0.15)) (justify left bottom mirror))
    )
    (fp_text user "License: Apache-2.0" (at -0.939 -5.799 180) (layer "B.Fab") hide
        (effects (font (size 0.7 0.7) (thickness 0.15)) (justify left bottom mirror))
    )
    (fp_text user "${REFERENCE}" (at 0 0) (layer "B.Fab")
        (effects (font (size 0.25 0.25) (thickness 0.04)) (justify mirror))
    )
    (fp_rect (start -0.925 0.47) (end 0.925 -0.47)
      (stroke (width 0.05) (type default)) (fill none) (layer "B.CrtYd"))
    (fp_line (start -0.494 -0.248) (end -0.494 0.25)
      (stroke (width 0.15) (type solid)) (layer "B.Fab"))
    (fp_line (start -0.494 0.25) (end 0.504 0.25)
      (stroke (width 0.15) (type solid)) (layer "B.Fab"))
    (fp_line (start 0.504 -0.248) (end -0.494 -0.248)
      (stroke (width 0.15) (type solid)) (layer "B.Fab"))
    (fp_line (start 0.504 0.25) (end 0.504 -0.248)
      (stroke (width 0.15) (type solid)) (layer "B.Fab"))
    (pad "1" smd roundrect (at -0.48 0) (size 0.59 0.64) (layers "B.Cu" "B.Paste" "B.Mask") (roundrect_rratio 0.25)
      (net 2 "VCC3V3") (pintype "passive"))
    (pad "2" smd roundrect (at 0.48 0) (size 0.59 0.64) (layers "B.Cu" "B.Paste" "B.Mask") (roundrect_rratio 0.25)
      (net 1 "GND") (pintype "passive"))
  )

  (footprint "antmicro-footprints:C_0402_1005Metric" (layer "B.Cu")
    (at 105.95 115.15 -90)
    (descr "Capacitor SMD 0402")
    (tags "capacitor SMD 0402")
    (property "Author" "Antmicro")
    (property "Dielectric" "")
    (property "License" "Apache-2.0")
    (property "MPN" "C1005X5R1E474M050BB")
    (property "Manufacturer" "TDK")
    (property "Public" "False")
    (property "Sheetfile" "fpga-banks.kicad_sch")
    (property "Sheetname" "FPGA banks")
    (property "Val" "470n")
    (property "Voltage" "")
    (property "ki_description" "SMD Multilayer Ceramic Capacitor, 0.47 µF, 25 V, 0402 [1005 Metric], ± 20%, X5R, C")
    (property "ki_keywords" "0402, SMT, CAPACITOR, PASSIVE, CERAMIC, MLCC")
    (attr smd)
    (fp_text reference "C211" (at -4.3 0 90) (layer "B.SilkS")
        (effects (font (size 0.7 0.7) (thickness 0.127)) (justify mirror))
    )
    (fp_text value "C_470n_0402" (at 0 -1.17 90) (layer "B.Fab")
        (effects (font (size 1 1) (thickness 0.15)) (justify mirror))
    )
    (fp_text user "Author: Antmicro" (at -0.939 -3.399 90) (layer "B.Fab") hide
        (effects (font (size 0.7 0.7) (thickness 0.15)) (justify left bottom mirror))
    )
    (fp_text user "License: Apache-2.0" (at -0.939 -5.799 90) (layer "B.Fab") hide
        (effects (font (size 0.7 0.7) (thickness 0.15)) (justify left bottom mirror))
    )
    (fp_text user "${REFERENCE}" (at 0 0 90) (layer "B.Fab")
        (effects (font (size 0.25 0.25) (thickness 0.04)) (justify mirror))
    )
    (fp_rect (start -0.925 0.47) (end 0.925 -0.47)
      (stroke (width 0.05) (type default)) (fill none) (layer "B.CrtYd"))
    (fp_line (start -0.494 -0.248) (end -0.494 0.25)
      (stroke (width 0.15) (type solid)) (layer "B.Fab"))
    (fp_line (start -0.494 0.25) (end 0.504 0.25)
      (stroke (width 0.15) (type solid)) (layer "B.Fab"))
    (fp_line (start 0.504 -0.248) (end -0.494 -0.248)
      (stroke (width 0.15) (type solid)) (layer "B.Fab"))
    (fp_line (start 0.504 0.25) (end 0.504 -0.248)
      (stroke (width 0.15) (type solid)) (layer "B.Fab"))
    (pad "1" smd roundrect (at -0.48 0 270) (size 0.59 0.64) (layers "B.Cu" "B.Paste" "B.Mask") (roundrect_rratio 0.25)
      (net 2 "VCC3V3") (pintype "passive"))
    (pad "2" smd roundrect (at 0.48 0 270) (size 0.59 0.64) (layers "B.Cu" "B.Paste" "B.Mask") (roundrect_rratio 0.25)
      (net 1 "GND") (pintype "passive"))
  )

  (footprint "antmicro-footprints:C_0402_1005Metric" (layer "B.Cu")
    (at 111.25 125.8)
    (descr "Capacitor SMD 0402")
    (tags "capacitor SMD 0402")
    (property "Author" "Antmicro")
    (property "Dielectric" "")
    (property "License" "Apache-2.0")
    (property "MPN" "C1005X5R1E474M050BB")
    (property "Manufacturer" "TDK")
    (property "Public" "False")
    (property "Sheetfile" "fpga-banks.kicad_sch")
    (property "Sheetname" "FPGA banks")
    (property "Val" "470n")
    (property "Voltage" "")
    (property "ki_description" "SMD Multilayer Ceramic Capacitor, 0.47 µF, 25 V, 0402 [1005 Metric], ± 20%, X5R, C")
    (property "ki_keywords" "0402, SMT, CAPACITOR, PASSIVE, CERAMIC, MLCC")
    (attr smd)
    (fp_text reference "C212" (at 3.4 -0.05) (layer "B.SilkS")
        (effects (font (size 0.7 0.7) (thickness 0.127)) (justify mirror))
    )
    (fp_text value "C_470n_0402" (at 0 -1.17) (layer "B.Fab")
        (effects (font (size 1 1) (thickness 0.15)) (justify mirror))
    )
    (fp_text user "Author: Antmicro" (at -0.939 -3.399 180) (layer "B.Fab") hide
        (effects (font (size 0.7 0.7) (thickness 0.15)) (justify left bottom mirror))
    )
    (fp_text user "License: Apache-2.0" (at -0.939 -5.799 180) (layer "B.Fab") hide
        (effects (font (size 0.7 0.7) (thickness 0.15)) (justify left bottom mirror))
    )
    (fp_text user "${REFERENCE}" (at 0 0) (layer "B.Fab")
        (effects (font (size 0.25 0.25) (thickness 0.04)) (justify mirror))
    )
    (fp_rect (start -0.925 0.47) (end 0.925 -0.47)
      (stroke (width 0.05) (type default)) (fill none) (layer "B.CrtYd"))
    (fp_line (start -0.494 -0.248) (end -0.494 0.25)
      (stroke (width 0.15) (type solid)) (layer "B.Fab"))
    (fp_line (start -0.494 0.25) (end 0.504 0.25)
      (stroke (width 0.15) (type solid)) (layer "B.Fab"))
    (fp_line (start 0.504 -0.248) (end -0.494 -0.248)
      (stroke (width 0.15) (type solid)) (layer "B.Fab"))
    (fp_line (start 0.504 0.25) (end 0.504 -0.248)
      (stroke (width 0.15) (type solid)) (layer "B.Fab"))
    (pad "1" smd roundrect (at -0.48 0) (size 0.59 0.64) (layers "B.Cu" "B.Paste" "B.Mask") (roundrect_rratio 0.25)
      (net 2 "VCC3V3") (pintype "passive"))
    (pad "2" smd roundrect (at 0.48 0) (size 0.59 0.64) (layers "B.Cu" "B.Paste" "B.Mask") (roundrect_rratio 0.25)
      (net 1 "GND") (pintype "passive"))
  )

  (footprint "antmicro-footprints:C_0402_1005Metric" (layer "B.Cu")
    (at 105.95 113.2 90)
    (descr "Capacitor SMD 0402")
    (tags "capacitor SMD 0402")
    (property "Author" "Antmicro")
    (property "Dielectric" "")
    (property "License" "Apache-2.0")
    (property "MPN" "C1005X5R1E474M050BB")
    (property "Manufacturer" "TDK")
    (property "Public" "False")
    (property "Sheetfile" "fpga-banks.kicad_sch")
    (property "Sheetname" "FPGA banks")
    (property "Val" "470n")
    (property "Voltage" "")
    (property "ki_description" "SMD Multilayer Ceramic Capacitor, 0.47 µF, 25 V, 0402 [1005 Metric], ± 20%, X5R, C")
    (property "ki_keywords" "0402, SMT, CAPACITOR, PASSIVE, CERAMIC, MLCC")
    (attr smd)
    (fp_text reference "C213" (at 5.2 0 90) (layer "B.SilkS")
        (effects (font (size 0.7 0.7) (thickness 0.127)) (justify mirror))
    )
    (fp_text value "C_470n_0402" (at 0 -1.17 90) (layer "B.Fab")
        (effects (font (size 1 1) (thickness 0.15)) (justify mirror))
    )
    (fp_text user "${REFERENCE}" (at 0 0 90) (layer "B.Fab")
        (effects (font (size 0.25 0.25) (thickness 0.04)) (justify mirror))
    )
    (fp_text user "License: Apache-2.0" (at -0.939 -5.799 270) (layer "B.Fab") hide
        (effects (font (size 0.7 0.7) (thickness 0.15)) (justify left bottom mirror))
    )
    (fp_text user "Author: Antmicro" (at -0.939 -3.399 270) (layer "B.Fab") hide
        (effects (font (size 0.7 0.7) (thickness 0.15)) (justify left bottom mirror))
    )
    (fp_rect (start -0.925 0.47) (end 0.925 -0.47)
      (stroke (width 0.05) (type default)) (fill none) (layer "B.CrtYd"))
    (fp_line (start -0.494 -0.248) (end -0.494 0.25)
      (stroke (width 0.15) (type solid)) (layer "B.Fab"))
    (fp_line (start -0.494 0.25) (end 0.504 0.25)
      (stroke (width 0.15) (type solid)) (layer "B.Fab"))
    (fp_line (start 0.504 -0.248) (end -0.494 -0.248)
      (stroke (width 0.15) (type solid)) (layer "B.Fab"))
    (fp_line (start 0.504 0.25) (end 0.504 -0.248)
      (stroke (width 0.15) (type solid)) (layer "B.Fab"))
    (pad "1" smd roundrect (at -0.48 0 90) (size 0.59 0.64) (layers "B.Cu" "B.Paste" "B.Mask") (roundrect_rratio 0.25)
      (net 2 "VCC3V3") (pintype "passive"))
    (pad "2" smd roundrect (at 0.48 0 90) (size 0.59 0.64) (layers "B.Cu" "B.Paste" "B.Mask") (roundrect_rratio 0.25)
      (net 1 "GND") (pintype "passive"))
  )

  (footprint "antmicro-footprints:C_0402_1005Metric" (layer "B.Cu")
    (at 109.55 113.9)
    (descr "Capacitor SMD 0402")
    (tags "capacitor SMD 0402")
    (property "Author" "Antmicro")
    (property "Dielectric" "")
    (property "License" "Apache-2.0")
    (property "MPN" "C1005X5R1E474M050BB")
    (property "Manufacturer" "TDK")
    (property "Public" "False")
    (property "Sheetfile" "fpga-banks.kicad_sch")
    (property "Sheetname" "FPGA banks")
    (property "Val" "470n")
    (property "Voltage" "")
    (property "ki_description" "SMD Multilayer Ceramic Capacitor, 0.47 µF, 25 V, 0402 [1005 Metric], ± 20%, X5R, C")
    (property "ki_keywords" "0402, SMT, CAPACITOR, PASSIVE, CERAMIC, MLCC")
    (attr smd)
    (fp_text reference "C214" (at 2.8 0.05) (layer "B.SilkS")
        (effects (font (size 0.7 0.7) (thickness 0.127)) (justify mirror))
    )
    (fp_text value "C_470n_0402" (at 0 -1.17) (layer "B.Fab")
        (effects (font (size 1 1) (thickness 0.15)) (justify mirror))
    )
    (fp_text user "${REFERENCE}" (at 0 0) (layer "B.Fab")
        (effects (font (size 0.25 0.25) (thickness 0.04)) (justify mirror))
    )
    (fp_text user "License: Apache-2.0" (at -0.939 -5.799 180) (layer "B.Fab") hide
        (effects (font (size 0.7 0.7) (thickness 0.15)) (justify left bottom mirror))
    )
    (fp_text user "Author: Antmicro" (at -0.939 -3.399 180) (layer "B.Fab") hide
        (effects (font (size 0.7 0.7) (thickness 0.15)) (justify left bottom mirror))
    )
    (fp_rect (start -0.925 0.47) (end 0.925 -0.47)
      (stroke (width 0.05) (type default)) (fill none) (layer "B.CrtYd"))
    (fp_line (start -0.494 -0.248) (end -0.494 0.25)
      (stroke (width 0.15) (type solid)) (layer "B.Fab"))
    (fp_line (start -0.494 0.25) (end 0.504 0.25)
      (stroke (width 0.15) (type solid)) (layer "B.Fab"))
    (fp_line (start 0.504 -0.248) (end -0.494 -0.248)
      (stroke (width 0.15) (type solid)) (layer "B.Fab"))
    (fp_line (start 0.504 0.25) (end 0.504 -0.248)
      (stroke (width 0.15) (type solid)) (layer "B.Fab"))
    (pad "1" smd roundrect (at -0.48 0) (size 0.59 0.64) (layers "B.Cu" "B.Paste" "B.Mask") (roundrect_rratio 0.25)
      (net 2 "VCC3V3") (pintype "passive"))
    (pad "2" smd roundrect (at 0.48 0) (size 0.59 0.64) (layers "B.Cu" "B.Paste" "B.Mask") (roundrect_rratio 0.25)
      (net 1 "GND") (pintype "passive"))
  )

  (footprint "antmicro-footprints:C_0402_1005Metric" (layer "B.Cu")
    (at 106.95 113.75 90)
    (descr "Capacitor SMD 0402")
    (tags "capacitor SMD 0402")
    (property "Author" "Antmicro")
    (property "Dielectric" "")
    (property "License" "Apache-2.0")
    (property "MPN" "C1005X5R1E474M050BB")
    (property "Manufacturer" "TDK")
    (property "Public" "False")
    (property "Sheetfile" "fpga-banks.kicad_sch")
    (property "Sheetname" "FPGA banks")
    (property "Val" "470n")
    (property "Voltage" "")
    (property "ki_description" "SMD Multilayer Ceramic Capacitor, 0.47 µF, 25 V, 0402 [1005 Metric], ± 20%, X5R, C")
    (property "ki_keywords" "0402, SMT, CAPACITOR, PASSIVE, CERAMIC, MLCC")
    (attr smd)
    (fp_text reference "C215" (at 2.4 0.1 90) (layer "B.SilkS")
        (effects (font (size 0.7 0.7) (thickness 0.127)) (justify mirror))
    )
    (fp_text value "C_470n_0402" (at 0 -1.17 90) (layer "B.Fab")
        (effects (font (size 1 1) (thickness 0.15)) (justify mirror))
    )
    (fp_text user "License: Apache-2.0" (at -0.939 -5.799 270) (layer "B.Fab") hide
        (effects (font (size 0.7 0.7) (thickness 0.15)) (justify left bottom mirror))
    )
    (fp_text user "Author: Antmicro" (at -0.939 -3.399 270) (layer "B.Fab") hide
        (effects (font (size 0.7 0.7) (thickness 0.15)) (justify left bottom mirror))
    )
    (fp_text user "${REFERENCE}" (at 0 0 90) (layer "B.Fab")
        (effects (font (size 0.25 0.25) (thickness 0.04)) (justify mirror))
    )
    (fp_rect (start -0.925 0.47) (end 0.925 -0.47)
      (stroke (width 0.05) (type default)) (fill none) (layer "B.CrtYd"))
    (fp_line (start -0.494 -0.248) (end -0.494 0.25)
      (stroke (width 0.15) (type solid)) (layer "B.Fab"))
    (fp_line (start -0.494 0.25) (end 0.504 0.25)
      (stroke (width 0.15) (type solid)) (layer "B.Fab"))
    (fp_line (start 0.504 -0.248) (end -0.494 -0.248)
      (stroke (width 0.15) (type solid)) (layer "B.Fab"))
    (fp_line (start 0.504 0.25) (end 0.504 -0.248)
      (stroke (width 0.15) (type solid)) (layer "B.Fab"))
    (pad "1" smd roundrect (at -0.48 0 90) (size 0.59 0.64) (layers "B.Cu" "B.Paste" "B.Mask") (roundrect_rratio 0.25)
      (net 2 "VCC3V3") (pintype "passive"))
    (pad "2" smd roundrect (at 0.48 0 90) (size 0.59 0.64) (layers "B.Cu" "B.Paste" "B.Mask") (roundrect_rratio 0.25)
      (net 1 "GND") (pintype "passive"))
  )

  (footprint "antmicro-footprints:C_0402_1005Metric" (layer "B.Cu")
    (at 97.6 125.65 180)
    (descr "Capacitor SMD 0402")
    (tags "capacitor SMD 0402")
    (property "Author" "Antmicro")
    (property "Dielectric" "")
    (property "License" "Apache-2.0")
    (property "MPN" "C1005X5R1E474M050BB")
    (property "Manufacturer" "TDK")
    (property "Public" "False")
    (property "Sheetfile" "fpga-banks.kicad_sch")
    (property "Sheetname" "FPGA banks")
    (property "Val" "470n")
    (property "Voltage" "")
    (property "ki_description" "SMD Multilayer Ceramic Capacitor, 0.47 µF, 25 V, 0402 [1005 Metric], ± 20%, X5R, C")
    (property "ki_keywords" "0402, SMT, CAPACITOR, PASSIVE, CERAMIC, MLCC")
    (attr smd)
    (fp_text reference "C218" (at 2.3 -0.2) (layer "B.SilkS")
        (effects (font (size 0.7 0.7) (thickness 0.127)) (justify mirror))
    )
    (fp_text value "C_470n_0402" (at 0 -1.17) (layer "B.Fab")
        (effects (font (size 1 1) (thickness 0.15)) (justify mirror))
    )
    (fp_text user "${REFERENCE}" (at 0 0) (layer "B.Fab")
        (effects (font (size 0.25 0.25) (thickness 0.04)) (justify mirror))
    )
    (fp_text user "Author: Antmicro" (at -0.939 -3.399) (layer "B.Fab") hide
        (effects (font (size 0.7 0.7) (thickness 0.15)) (justify left bottom mirror))
    )
    (fp_text user "License: Apache-2.0" (at -0.939 -5.799) (layer "B.Fab") hide
        (effects (font (size 0.7 0.7) (thickness 0.15)) (justify left bottom mirror))
    )
    (fp_rect (start -0.925 0.47) (end 0.925 -0.47)
      (stroke (width 0.05) (type default)) (fill none) (layer "B.CrtYd"))
    (fp_line (start -0.494 -0.248) (end -0.494 0.25)
      (stroke (width 0.15) (type solid)) (layer "B.Fab"))
    (fp_line (start -0.494 0.25) (end 0.504 0.25)
      (stroke (width 0.15) (type solid)) (layer "B.Fab"))
    (fp_line (start 0.504 -0.248) (end -0.494 -0.248)
      (stroke (width 0.15) (type solid)) (layer "B.Fab"))
    (fp_line (start 0.504 0.25) (end 0.504 -0.248)
      (stroke (width 0.15) (type solid)) (layer "B.Fab"))
    (pad "1" smd roundrect (at -0.48 0 180) (size 0.59 0.64) (layers "B.Cu" "B.Paste" "B.Mask") (roundrect_rratio 0.25)
      (net 2 "VCC3V3") (pintype "passive"))
    (pad "2" smd roundrect (at 0.48 0 180) (size 0.59 0.64) (layers "B.Cu" "B.Paste" "B.Mask") (roundrect_rratio 0.25)
      (net 1 "GND") (pintype "passive"))
  )

  (footprint "antmicro-footprints:C_0402_1005Metric" (layer "B.Cu")
    (at 111.2 118.15)
    (descr "Capacitor SMD 0402")
    (tags "capacitor SMD 0402")
    (property "Author" "Antmicro")
    (property "Dielectric" "")
    (property "License" "Apache-2.0")
    (property "MPN" "GRM155R61A475MEAAD")
    (property "Manufacturer" "Murata")
    (property "Public" "False")
    (property "Sheetfile" "fpga-banks.kicad_sch")
    (property "Sheetname" "FPGA banks")
    (property "Val" "4u7")
    (property "Voltage" "")
    (property "ki_description" "SMD Multilayer Ceramic Capacitor, 4.7 µF, 10 V, 0402 [1005 Metric], ± 20%, X5R, GRM Series")
    (property "ki_keywords" "0402, SMT, CAPACITOR, PASSIVE")
    (attr smd)
    (fp_text reference "C219" (at 2.4 0) (layer "B.SilkS")
        (effects (font (size 0.7 0.7) (thickness 0.127)) (justify mirror))
    )
    (fp_text value "C_4u7_0402" (at 0 -1.17) (layer "B.Fab")
        (effects (font (size 1 1) (thickness 0.15)) (justify mirror))
    )
    (fp_text user "${REFERENCE}" (at 0 0) (layer "B.Fab")
        (effects (font (size 0.25 0.25) (thickness 0.04)) (justify mirror))
    )
    (fp_text user "Author: Antmicro" (at -0.939 -3.399 180) (layer "B.Fab") hide
        (effects (font (size 0.7 0.7) (thickness 0.15)) (justify left bottom mirror))
    )
    (fp_text user "License: Apache-2.0" (at -0.939 -5.799 180) (layer "B.Fab") hide
        (effects (font (size 0.7 0.7) (thickness 0.15)) (justify left bottom mirror))
    )
    (fp_rect (start -0.925 0.47) (end 0.925 -0.47)
      (stroke (width 0.05) (type default)) (fill none) (layer "B.CrtYd"))
    (fp_line (start -0.494 -0.248) (end -0.494 0.25)
      (stroke (width 0.15) (type solid)) (layer "B.Fab"))
    (fp_line (start -0.494 0.25) (end 0.504 0.25)
      (stroke (width 0.15) (type solid)) (layer "B.Fab"))
    (fp_line (start 0.504 -0.248) (end -0.494 -0.248)
      (stroke (width 0.15) (type solid)) (layer "B.Fab"))
    (fp_line (start 0.504 0.25) (end 0.504 -0.248)
      (stroke (width 0.15) (type solid)) (layer "B.Fab"))
    (pad "1" smd roundrect (at -0.48 0) (size 0.59 0.64) (layers "B.Cu" "B.Paste" "B.Mask") (roundrect_rratio 0.25)
      (net 218 "VCC1V8") (pintype "passive"))
    (pad "2" smd roundrect (at 0.48 0) (size 0.59 0.64) (layers "B.Cu" "B.Paste" "B.Mask") (roundrect_rratio 0.25)
      (net 1 "GND") (pintype "passive"))
  )

  (footprint "antmicro-footprints:C_0402_1005Metric" (layer "B.Cu")
    (at 97.6 126.65 180)
    (descr "Capacitor SMD 0402")
    (tags "capacitor SMD 0402")
    (property "Author" "Antmicro")
    (property "Dielectric" "")
    (property "License" "Apache-2.0")
    (property "MPN" "C1005X5R1E474M050BB")
    (property "Manufacturer" "TDK")
    (property "Public" "False")
    (property "Sheetfile" "fpga-banks.kicad_sch")
    (property "Sheetname" "FPGA banks")
    (property "Val" "470n")
    (property "Voltage" "")
    (property "ki_description" "SMD Multilayer Ceramic Capacitor, 0.47 µF, 25 V, 0402 [1005 Metric], ± 20%, X5R, C")
    (property "ki_keywords" "0402, SMT, CAPACITOR, PASSIVE, CERAMIC, MLCC")
    (attr smd)
    (fp_text reference "C220" (at 2.3 -0.2) (layer "B.SilkS")
        (effects (font (size 0.7 0.7) (thickness 0.127)) (justify mirror))
    )
    (fp_text value "C_470n_0402" (at 0 -1.17) (layer "B.Fab")
        (effects (font (size 1 1) (thickness 0.15)) (justify mirror))
    )
    (fp_text user "${REFERENCE}" (at 0 0) (layer "B.Fab")
        (effects (font (size 0.25 0.25) (thickness 0.04)) (justify mirror))
    )
    (fp_text user "Author: Antmicro" (at -0.939 -3.399) (layer "B.Fab") hide
        (effects (font (size 0.7 0.7) (thickness 0.15)) (justify left bottom mirror))
    )
    (fp_text user "License: Apache-2.0" (at -0.939 -5.799) (layer "B.Fab") hide
        (effects (font (size 0.7 0.7) (thickness 0.15)) (justify left bottom mirror))
    )
    (fp_rect (start -0.925 0.47) (end 0.925 -0.47)
      (stroke (width 0.05) (type default)) (fill none) (layer "B.CrtYd"))
    (fp_line (start -0.494 -0.248) (end -0.494 0.25)
      (stroke (width 0.15) (type solid)) (layer "B.Fab"))
    (fp_line (start -0.494 0.25) (end 0.504 0.25)
      (stroke (width 0.15) (type solid)) (layer "B.Fab"))
    (fp_line (start 0.504 -0.248) (end -0.494 -0.248)
      (stroke (width 0.15) (type solid)) (layer "B.Fab"))
    (fp_line (start 0.504 0.25) (end 0.504 -0.248)
      (stroke (width 0.15) (type solid)) (layer "B.Fab"))
    (pad "1" smd roundrect (at -0.48 0 180) (size 0.59 0.64) (layers "B.Cu" "B.Paste" "B.Mask") (roundrect_rratio 0.25)
      (net 2 "VCC3V3") (pintype "passive"))
    (pad "2" smd roundrect (at 0.48 0 180) (size 0.59 0.64) (layers "B.Cu" "B.Paste" "B.Mask") (roundrect_rratio 0.25)
      (net 1 "GND") (pintype "passive"))
  )

  (footprint "antmicro-footprints:C_0402_1005Metric" (layer "B.Cu")
    (at 109.2 121.75 -90)
    (descr "Capacitor SMD 0402")
    (tags "capacitor SMD 0402")
    (property "Author" "Antmicro")
    (property "Dielectric" "")
    (property "License" "Apache-2.0")
    (property "MPN" "C1005X5R1E474M050BB")
    (property "Manufacturer" "TDK")
    (property "Public" "False")
    (property "Sheetfile" "fpga-banks.kicad_sch")
    (property "Sheetname" "FPGA banks")
    (property "Val" "470n")
    (property "Voltage" "")
    (property "ki_description" "SMD Multilayer Ceramic Capacitor, 0.47 µF, 25 V, 0402 [1005 Metric], ± 20%, X5R, C")
    (property "ki_keywords" "0402, SMT, CAPACITOR, PASSIVE, CERAMIC, MLCC")
    (attr smd)
    (fp_text reference "C221" (at 22.8 -0.25 90) (layer "B.SilkS")
        (effects (font (size 0.7 0.7) (thickness 0.127)) (justify mirror))
    )
    (fp_text value "C_470n_0402" (at 0 -1.17 90) (layer "B.Fab")
        (effects (font (size 1 1) (thickness 0.15)) (justify mirror))
    )
    (fp_text user "${REFERENCE}" (at 0 0 90) (layer "B.Fab")
        (effects (font (size 0.25 0.25) (thickness 0.04)) (justify mirror))
    )
    (fp_text user "Author: Antmicro" (at -0.939 -3.399 90) (layer "B.Fab") hide
        (effects (font (size 0.7 0.7) (thickness 0.15)) (justify left bottom mirror))
    )
    (fp_text user "License: Apache-2.0" (at -0.939 -5.799 90) (layer "B.Fab") hide
        (effects (font (size 0.7 0.7) (thickness 0.15)) (justify left bottom mirror))
    )
    (fp_rect (start -0.925 0.47) (end 0.925 -0.47)
      (stroke (width 0.05) (type default)) (fill none) (layer "B.CrtYd"))
    (fp_line (start -0.494 -0.248) (end -0.494 0.25)
      (stroke (width 0.15) (type solid)) (layer "B.Fab"))
    (fp_line (start -0.494 0.25) (end 0.504 0.25)
      (stroke (width 0.15) (type solid)) (layer "B.Fab"))
    (fp_line (start 0.504 -0.248) (end -0.494 -0.248)
      (stroke (width 0.15) (type solid)) (layer "B.Fab"))
    (fp_line (start 0.504 0.25) (end 0.504 -0.248)
      (stroke (width 0.15) (type solid)) (layer "B.Fab"))
    (pad "1" smd roundrect (at -0.48 0 270) (size 0.59 0.64) (layers "B.Cu" "B.Paste" "B.Mask") (roundrect_rratio 0.25)
      (net 218 "VCC1V8") (pintype "passive"))
    (pad "2" smd roundrect (at 0.48 0 270) (size 0.59 0.64) (layers "B.Cu" "B.Paste" "B.Mask") (roundrect_rratio 0.25)
      (net 1 "GND") (pintype "passive"))
  )

  (footprint "antmicro-footprints:C_0402_1005Metric" (layer "B.Cu")
    (at 109.15 119.65 180)
    (descr "Capacitor SMD 0402")
    (tags "capacitor SMD 0402")
    (property "Author" "Antmicro")
    (property "Dielectric" "")
    (property "License" "Apache-2.0")
    (property "MPN" "C1005X5R1E474M050BB")
    (property "Manufacturer" "TDK")
    (property "Public" "False")
    (property "Sheetfile" "fpga-banks.kicad_sch")
    (property "Sheetname" "FPGA banks")
    (property "Val" "470n")
    (property "Voltage" "")
    (property "ki_description" "SMD Multilayer Ceramic Capacitor, 0.47 µF, 25 V, 0402 [1005 Metric], ± 20%, X5R, C")
    (property "ki_keywords" "0402, SMT, CAPACITOR, PASSIVE, CERAMIC, MLCC")
    (attr smd)
    (fp_text reference "C222" (at 0.05 -22.85) (layer "B.SilkS")
        (effects (font (size 0.7 0.7) (thickness 0.127)) (justify mirror))
    )
    (fp_text value "C_470n_0402" (at 0 -1.17) (layer "B.Fab")
        (effects (font (size 1 1) (thickness 0.15)) (justify mirror))
    )
    (fp_text user "${REFERENCE}" (at 0 0) (layer "B.Fab")
        (effects (font (size 0.25 0.25) (thickness 0.04)) (justify mirror))
    )
    (fp_text user "License: Apache-2.0" (at -0.939 -5.799) (layer "B.Fab") hide
        (effects (font (size 0.7 0.7) (thickness 0.15)) (justify left bottom mirror))
    )
    (fp_text user "Author: Antmicro" (at -0.939 -3.399) (layer "B.Fab") hide
        (effects (font (size 0.7 0.7) (thickness 0.15)) (justify left bottom mirror))
    )
    (fp_rect (start -0.925 0.47) (end 0.925 -0.47)
      (stroke (width 0.05) (type default)) (fill none) (layer "B.CrtYd"))
    (fp_line (start -0.494 -0.248) (end -0.494 0.25)
      (stroke (width 0.15) (type solid)) (layer "B.Fab"))
    (fp_line (start -0.494 0.25) (end 0.504 0.25)
      (stroke (width 0.15) (type solid)) (layer "B.Fab"))
    (fp_line (start 0.504 -0.248) (end -0.494 -0.248)
      (stroke (width 0.15) (type solid)) (layer "B.Fab"))
    (fp_line (start 0.504 0.25) (end 0.504 -0.248)
      (stroke (width 0.15) (type solid)) (layer "B.Fab"))
    (pad "1" smd roundrect (at -0.48 0 180) (size 0.59 0.64) (layers "B.Cu" "B.Paste" "B.Mask") (roundrect_rratio 0.25)
      (net 218 "VCC1V8") (pintype "passive"))
    (pad "2" smd roundrect (at 0.48 0 180) (size 0.59 0.64) (layers "B.Cu" "B.Paste" "B.Mask") (roundrect_rratio 0.25)
      (net 1 "GND") (pintype "passive"))
  )

  (footprint "antmicro-footprints:C_0402_1005Metric" (layer "B.Cu")
    (at 109.1 118.15 180)
    (descr "Capacitor SMD 0402")
    (tags "capacitor SMD 0402")
    (property "Author" "Antmicro")
    (property "Dielectric" "")
    (property "License" "Apache-2.0")
    (property "MPN" "C1005X5R1E474M050BB")
    (property "Manufacturer" "TDK")
    (property "Public" "False")
    (property "Sheetfile" "fpga-banks.kicad_sch")
    (property "Sheetname" "FPGA banks")
    (property "Val" "470n")
    (property "Voltage" "")
    (property "ki_description" "SMD Multilayer Ceramic Capacitor, 0.47 µF, 25 V, 0402 [1005 Metric], ± 20%, X5R, C")
    (property "ki_keywords" "0402, SMT, CAPACITOR, PASSIVE, CERAMIC, MLCC")
    (attr smd)
    (fp_text reference "C223" (at 0.05 -22.9) (layer "B.SilkS")
        (effects (font (size 0.7 0.7) (thickness 0.127)) (justify mirror))
    )
    (fp_text value "C_470n_0402" (at 0 -1.17) (layer "B.Fab")
        (effects (font (size 1 1) (thickness 0.15)) (justify mirror))
    )
    (fp_text user "License: Apache-2.0" (at -0.939 -5.799) (layer "B.Fab") hide
        (effects (font (size 0.7 0.7) (thickness 0.15)) (justify left bottom mirror))
    )
    (fp_text user "${REFERENCE}" (at 0 0) (layer "B.Fab")
        (effects (font (size 0.25 0.25) (thickness 0.04)) (justify mirror))
    )
    (fp_text user "Author: Antmicro" (at -0.939 -3.399) (layer "B.Fab") hide
        (effects (font (size 0.7 0.7) (thickness 0.15)) (justify left bottom mirror))
    )
    (fp_rect (start -0.925 0.47) (end 0.925 -0.47)
      (stroke (width 0.05) (type default)) (fill none) (layer "B.CrtYd"))
    (fp_line (start -0.494 -0.248) (end -0.494 0.25)
      (stroke (width 0.15) (type solid)) (layer "B.Fab"))
    (fp_line (start -0.494 0.25) (end 0.504 0.25)
      (stroke (width 0.15) (type solid)) (layer "B.Fab"))
    (fp_line (start 0.504 -0.248) (end -0.494 -0.248)
      (stroke (width 0.15) (type solid)) (layer "B.Fab"))
    (fp_line (start 0.504 0.25) (end 0.504 -0.248)
      (stroke (width 0.15) (type solid)) (layer "B.Fab"))
    (pad "1" smd roundrect (at -0.48 0 180) (size 0.59 0.64) (layers "B.Cu" "B.Paste" "B.Mask") (roundrect_rratio 0.25)
      (net 218 "VCC1V8") (pintype "passive"))
    (pad "2" smd roundrect (at 0.48 0 180) (size 0.59 0.64) (layers "B.Cu" "B.Paste" "B.Mask") (roundrect_rratio 0.25)
      (net 1 "GND") (pintype "passive"))
  )

  (footprint "antmicro-footprints:C_0402_1005Metric" (layer "B.Cu")
    (at 110.5 116.05)
    (descr "Capacitor SMD 0402")
    (tags "capacitor SMD 0402")
    (property "Author" "Antmicro")
    (property "Dielectric" "")
    (property "License" "Apache-2.0")
    (property "MPN" "C1005X5R1E474M050BB")
    (property "Manufacturer" "TDK")
    (property "Public" "False")
    (property "Sheetfile" "fpga-banks.kicad_sch")
    (property "Sheetname" "FPGA banks")
    (property "Val" "470n")
    (property "Voltage" "")
    (property "ki_description" "SMD Multilayer Ceramic Capacitor, 0.47 µF, 25 V, 0402 [1005 Metric], ± 20%, X5R, C")
    (property "ki_keywords" "0402, SMT, CAPACITOR, PASSIVE, CERAMIC, MLCC")
    (attr smd)
    (fp_text reference "C224" (at 2.55 -0.05) (layer "B.SilkS")
        (effects (font (size 0.7 0.7) (thickness 0.127)) (justify mirror))
    )
    (fp_text value "C_470n_0402" (at 0 -1.17) (layer "B.Fab")
        (effects (font (size 1 1) (thickness 0.15)) (justify mirror))
    )
    (fp_text user "License: Apache-2.0" (at -0.939 -5.799 180) (layer "B.Fab") hide
        (effects (font (size 0.7 0.7) (thickness 0.15)) (justify left bottom mirror))
    )
    (fp_text user "${REFERENCE}" (at 0 0) (layer "B.Fab")
        (effects (font (size 0.25 0.25) (thickness 0.04)) (justify mirror))
    )
    (fp_text user "Author: Antmicro" (at -0.939 -3.399 180) (layer "B.Fab") hide
        (effects (font (size 0.7 0.7) (thickness 0.15)) (justify left bottom mirror))
    )
    (fp_rect (start -0.925 0.47) (end 0.925 -0.47)
      (stroke (width 0.05) (type default)) (fill none) (layer "B.CrtYd"))
    (fp_line (start -0.494 -0.248) (end -0.494 0.25)
      (stroke (width 0.15) (type solid)) (layer "B.Fab"))
    (fp_line (start -0.494 0.25) (end 0.504 0.25)
      (stroke (width 0.15) (type solid)) (layer "B.Fab"))
    (fp_line (start 0.504 -0.248) (end -0.494 -0.248)
      (stroke (width 0.15) (type solid)) (layer "B.Fab"))
    (fp_line (start 0.504 0.25) (end 0.504 -0.248)
      (stroke (width 0.15) (type solid)) (layer "B.Fab"))
    (pad "1" smd roundrect (at -0.48 0) (size 0.59 0.64) (layers "B.Cu" "B.Paste" "B.Mask") (roundrect_rratio 0.25)
      (net 218 "VCC1V8") (pintype "passive"))
    (pad "2" smd roundrect (at 0.48 0) (size 0.59 0.64) (layers "B.Cu" "B.Paste" "B.Mask") (roundrect_rratio 0.25)
      (net 1 "GND") (pintype "passive"))
  )

  (footprint "antmicro-footprints:C_0402_1005Metric" (layer "B.Cu")
    (at 111.25 119.65)
    (descr "Capacitor SMD 0402")
    (tags "capacitor SMD 0402")
    (property "Author" "Antmicro")
    (property "Dielectric" "")
    (property "License" "Apache-2.0")
    (property "MPN" "GRM155R61A475MEAAD")
    (property "Manufacturer" "Murata")
    (property "Public" "False")
    (property "Sheetfile" "fpga-banks.kicad_sch")
    (property "Sheetname" "FPGA banks")
    (property "Val" "4u7")
    (property "Voltage" "")
    (property "ki_description" "SMD Multilayer Ceramic Capacitor, 4.7 µF, 10 V, 0402 [1005 Metric], ± 20%, X5R, GRM Series")
    (property "ki_keywords" "0402, SMT, CAPACITOR, PASSIVE")
    (attr smd)
    (fp_text reference "C225" (at 2.4 -0.05) (layer "B.SilkS")
        (effects (font (size 0.7 0.7) (thickness 0.127)) (justify mirror))
    )
    (fp_text value "C_4u7_0402" (at 0 -1.17) (layer "B.Fab")
        (effects (font (size 1 1) (thickness 0.15)) (justify mirror))
    )
    (fp_text user "Author: Antmicro" (at -0.939 -3.399 180) (layer "B.Fab") hide
        (effects (font (size 0.7 0.7) (thickness 0.15)) (justify left bottom mirror))
    )
    (fp_text user "${REFERENCE}" (at 0 0) (layer "B.Fab")
        (effects (font (size 0.25 0.25) (thickness 0.04)) (justify mirror))
    )
    (fp_text user "License: Apache-2.0" (at -0.939 -5.799 180) (layer "B.Fab") hide
        (effects (font (size 0.7 0.7) (thickness 0.15)) (justify left bottom mirror))
    )
    (fp_rect (start -0.925 0.47) (end 0.925 -0.47)
      (stroke (width 0.05) (type default)) (fill none) (layer "B.CrtYd"))
    (fp_line (start -0.494 -0.248) (end -0.494 0.25)
      (stroke (width 0.15) (type solid)) (layer "B.Fab"))
    (fp_line (start -0.494 0.25) (end 0.504 0.25)
      (stroke (width 0.15) (type solid)) (layer "B.Fab"))
    (fp_line (start 0.504 -0.248) (end -0.494 -0.248)
      (stroke (width 0.15) (type solid)) (layer "B.Fab"))
    (fp_line (start 0.504 0.25) (end 0.504 -0.248)
      (stroke (width 0.15) (type solid)) (layer "B.Fab"))
    (pad "1" smd roundrect (at -0.48 0) (size 0.59 0.64) (layers "B.Cu" "B.Paste" "B.Mask") (roundrect_rratio 0.25)
      (net 2 "VCC3V3") (pintype "passive"))
    (pad "2" smd roundrect (at 0.48 0) (size 0.59 0.64) (layers "B.Cu" "B.Paste" "B.Mask") (roundrect_rratio 0.25)
      (net 1 "GND") (pintype "passive"))
  )

  (footprint "antmicro-footprints:C_0402_1005Metric" (layer "B.Cu")
    (at 111.25 123.75)
    (descr "Capacitor SMD 0402")
    (tags "capacitor SMD 0402")
    (property "Author" "Antmicro")
    (property "Dielectric" "")
    (property "License" "Apache-2.0")
    (property "MPN" "C1005X5R1E474M050BB")
    (property "Manufacturer" "TDK")
    (property "Public" "False")
    (property "Sheetfile" "fpga-banks.kicad_sch")
    (property "Sheetname" "FPGA banks")
    (property "Val" "470n")
    (property "Voltage" "")
    (property "ki_description" "SMD Multilayer Ceramic Capacitor, 0.47 µF, 25 V, 0402 [1005 Metric], ± 20%, X5R, C")
    (property "ki_keywords" "0402, SMT, CAPACITOR, PASSIVE, CERAMIC, MLCC")
    (attr smd)
    (fp_text reference "C226" (at 2.5 -0.05) (layer "B.SilkS")
        (effects (font (size 0.7 0.7) (thickness 0.127)) (justify mirror))
    )
    (fp_text value "C_470n_0402" (at 0 -1.17) (layer "B.Fab")
        (effects (font (size 1 1) (thickness 0.15)) (justify mirror))
    )
    (fp_text user "Author: Antmicro" (at -0.939 -3.399 180) (layer "B.Fab") hide
        (effects (font (size 0.7 0.7) (thickness 0.15)) (justify left bottom mirror))
    )
    (fp_text user "License: Apache-2.0" (at -0.939 -5.799 180) (layer "B.Fab") hide
        (effects (font (size 0.7 0.7) (thickness 0.15)) (justify left bottom mirror))
    )
    (fp_text user "${REFERENCE}" (at 0 0) (layer "B.Fab")
        (effects (font (size 0.25 0.25) (thickness 0.04)) (justify mirror))
    )
    (fp_rect (start -0.925 0.47) (end 0.925 -0.47)
      (stroke (width 0.05) (type default)) (fill none) (layer "B.CrtYd"))
    (fp_line (start -0.494 -0.248) (end -0.494 0.25)
      (stroke (width 0.15) (type solid)) (layer "B.Fab"))
    (fp_line (start -0.494 0.25) (end 0.504 0.25)
      (stroke (width 0.15) (type solid)) (layer "B.Fab"))
    (fp_line (start 0.504 -0.248) (end -0.494 -0.248)
      (stroke (width 0.15) (type solid)) (layer "B.Fab"))
    (fp_line (start 0.504 0.25) (end 0.504 -0.248)
      (stroke (width 0.15) (type solid)) (layer "B.Fab"))
    (pad "1" smd roundrect (at -0.48 0) (size 0.59 0.64) (layers "B.Cu" "B.Paste" "B.Mask") (roundrect_rratio 0.25)
      (net 2 "VCC3V3") (pintype "passive"))
    (pad "2" smd roundrect (at 0.48 0) (size 0.59 0.64) (layers "B.Cu" "B.Paste" "B.Mask") (roundrect_rratio 0.25)
      (net 1 "GND") (pintype "passive"))
  )

  (footprint "antmicro-footprints:C_0402_1005Metric" (layer "B.Cu")
    (at 111.25 121.7)
    (descr "Capacitor SMD 0402")
    (tags "capacitor SMD 0402")
    (property "Author" "Antmicro")
    (property "Dielectric" "")
    (property "License" "Apache-2.0")
    (property "MPN" "C1005X5R1E474M050BB")
    (property "Manufacturer" "TDK")
    (property "Public" "False")
    (property "Sheetfile" "fpga-banks.kicad_sch")
    (property "Sheetname" "FPGA banks")
    (property "Val" "470n")
    (property "Voltage" "")
    (property "ki_description" "SMD Multilayer Ceramic Capacitor, 0.47 µF, 25 V, 0402 [1005 Metric], ± 20%, X5R, C")
    (property "ki_keywords" "0402, SMT, CAPACITOR, PASSIVE, CERAMIC, MLCC")
    (attr smd)
    (fp_text reference "C228" (at 2.45 -0.05) (layer "B.SilkS")
        (effects (font (size 0.7 0.7) (thickness 0.127)) (justify mirror))
    )
    (fp_text value "C_470n_0402" (at 0 -1.17) (layer "B.Fab")
        (effects (font (size 1 1) (thickness 0.15)) (justify mirror))
    )
    (fp_text user "License: Apache-2.0" (at -0.939 -5.799 180) (layer "B.Fab") hide
        (effects (font (size 0.7 0.7) (thickness 0.15)) (justify left bottom mirror))
    )
    (fp_text user "${REFERENCE}" (at 0 0) (layer "B.Fab")
        (effects (font (size 0.25 0.25) (thickness 0.04)) (justify mirror))
    )
    (fp_text user "Author: Antmicro" (at -0.939 -3.399 180) (layer "B.Fab") hide
        (effects (font (size 0.7 0.7) (thickness 0.15)) (justify left bottom mirror))
    )
    (fp_rect (start -0.925 0.47) (end 0.925 -0.47)
      (stroke (width 0.05) (type default)) (fill none) (layer "B.CrtYd"))
    (fp_line (start -0.494 -0.248) (end -0.494 0.25)
      (stroke (width 0.15) (type solid)) (layer "B.Fab"))
    (fp_line (start -0.494 0.25) (end 0.504 0.25)
      (stroke (width 0.15) (type solid)) (layer "B.Fab"))
    (fp_line (start 0.504 -0.248) (end -0.494 -0.248)
      (stroke (width 0.15) (type solid)) (layer "B.Fab"))
    (fp_line (start 0.504 0.25) (end 0.504 -0.248)
      (stroke (width 0.15) (type solid)) (layer "B.Fab"))
    (pad "1" smd roundrect (at -0.48 0) (size 0.59 0.64) (layers "B.Cu" "B.Paste" "B.Mask") (roundrect_rratio 0.25)
      (net 2 "VCC3V3") (pintype "passive"))
    (pad "2" smd roundrect (at 0.48 0) (size 0.59 0.64) (layers "B.Cu" "B.Paste" "B.Mask") (roundrect_rratio 0.25)
      (net 1 "GND") (pintype "passive"))
  )

  (footprint "antmicro-footprints:C_0402_1005Metric" (layer "B.Cu")
    (at 111.25 120.675)
    (descr "Capacitor SMD 0402")
    (tags "capacitor SMD 0402")
    (property "Author" "Antmicro")
    (property "Dielectric" "")
    (property "License" "Apache-2.0")
    (property "MPN" "C1005X5R1E474M050BB")
    (property "Manufacturer" "TDK")
    (property "Public" "False")
    (property "Sheetfile" "fpga-banks.kicad_sch")
    (property "Sheetname" "FPGA banks")
    (property "Val" "470n")
    (property "Voltage" "")
    (property "ki_description" "SMD Multilayer Ceramic Capacitor, 0.47 µF, 25 V, 0402 [1005 Metric], ± 20%, X5R, C")
    (property "ki_keywords" "0402, SMT, CAPACITOR, PASSIVE, CERAMIC, MLCC")
    (attr smd)
    (fp_text reference "C229" (at 2.4 -0.075) (layer "B.SilkS")
        (effects (font (size 0.7 0.7) (thickness 0.127)) (justify mirror))
    )
    (fp_text value "C_470n_0402" (at 0 -1.17) (layer "B.Fab")
        (effects (font (size 1 1) (thickness 0.15)) (justify mirror))
    )
    (fp_text user "Author: Antmicro" (at -0.939 -3.399 180) (layer "B.Fab") hide
        (effects (font (size 0.7 0.7) (thickness 0.15)) (justify left bottom mirror))
    )
    (fp_text user "${REFERENCE}" (at 0 0) (layer "B.Fab")
        (effects (font (size 0.25 0.25) (thickness 0.04)) (justify mirror))
    )
    (fp_text user "License: Apache-2.0" (at -0.939 -5.799 180) (layer "B.Fab") hide
        (effects (font (size 0.7 0.7) (thickness 0.15)) (justify left bottom mirror))
    )
    (fp_rect (start -0.925 0.47) (end 0.925 -0.47)
      (stroke (width 0.05) (type default)) (fill none) (layer "B.CrtYd"))
    (fp_line (start -0.494 -0.248) (end -0.494 0.25)
      (stroke (width 0.15) (type solid)) (layer "B.Fab"))
    (fp_line (start -0.494 0.25) (end 0.504 0.25)
      (stroke (width 0.15) (type solid)) (layer "B.Fab"))
    (fp_line (start 0.504 -0.248) (end -0.494 -0.248)
      (stroke (width 0.15) (type solid)) (layer "B.Fab"))
    (fp_line (start 0.504 0.25) (end 0.504 -0.248)
      (stroke (width 0.15) (type solid)) (layer "B.Fab"))
    (pad "1" smd roundrect (at -0.48 0) (size 0.59 0.64) (layers "B.Cu" "B.Paste" "B.Mask") (roundrect_rratio 0.25)
      (net 2 "VCC3V3") (pintype "passive"))
    (pad "2" smd roundrect (at 0.48 0) (size 0.59 0.64) (layers "B.Cu" "B.Paste" "B.Mask") (roundrect_rratio 0.25)
      (net 1 "GND") (pintype "passive"))
  )

  (footprint "antmicro-footprints:C_0402_1005Metric" (layer "B.Cu")
    (at 97.6 121.27857 180)
    (descr "Capacitor SMD 0402")
    (tags "capacitor SMD 0402")
    (property "Author" "Antmicro")
    (property "Dielectric" "")
    (property "License" "Apache-2.0")
    (property "MPN" "GRM155R61A475MEAAD")
    (property "Manufacturer" "Murata")
    (property "Public" "False")
    (property "Sheetfile" "fpga-banks.kicad_sch")
    (property "Sheetname" "FPGA banks")
    (property "Val" "4u7")
    (property "Voltage" "")
    (property "ki_description" "SMD Multilayer Ceramic Capacitor, 4.7 µF, 10 V, 0402 [1005 Metric], ± 20%, X5R, GRM Series")
    (property "ki_keywords" "0402, SMT, CAPACITOR, PASSIVE")
    (attr smd)
    (fp_text reference "C230" (at 2.4 0.22857) (layer "B.SilkS")
        (effects (font (size 0.7 0.7) (thickness 0.127)) (justify mirror))
    )
    (fp_text value "C_4u7_0402" (at 0 -1.17) (layer "B.Fab")
        (effects (font (size 1 1) (thickness 0.15)) (justify mirror))
    )
    (fp_text user "License: Apache-2.0" (at -0.939 -5.799) (layer "B.Fab") hide
        (effects (font (size 0.7 0.7) (thickness 0.15)) (justify left bottom mirror))
    )
    (fp_text user "${REFERENCE}" (at 0 0) (layer "B.Fab")
        (effects (font (size 0.25 0.25) (thickness 0.04)) (justify mirror))
    )
    (fp_text user "Author: Antmicro" (at -0.939 -3.399) (layer "B.Fab") hide
        (effects (font (size 0.7 0.7) (thickness 0.15)) (justify left bottom mirror))
    )
    (fp_rect (start -0.925 0.47) (end 0.925 -0.47)
      (stroke (width 0.05) (type default)) (fill none) (layer "B.CrtYd"))
    (fp_line (start -0.494 -0.248) (end -0.494 0.25)
      (stroke (width 0.15) (type solid)) (layer "B.Fab"))
    (fp_line (start -0.494 0.25) (end 0.504 0.25)
      (stroke (width 0.15) (type solid)) (layer "B.Fab"))
    (fp_line (start 0.504 -0.248) (end -0.494 -0.248)
      (stroke (width 0.15) (type solid)) (layer "B.Fab"))
    (fp_line (start 0.504 0.25) (end 0.504 -0.248)
      (stroke (width 0.15) (type solid)) (layer "B.Fab"))
    (pad "1" smd roundrect (at -0.48 0 180) (size 0.59 0.64) (layers "B.Cu" "B.Paste" "B.Mask") (roundrect_rratio 0.25)
      (net 3 "VCC1V35") (pintype "passive"))
    (pad "2" smd roundrect (at 0.48 0 180) (size 0.59 0.64) (layers "B.Cu" "B.Paste" "B.Mask") (roundrect_rratio 0.25)
      (net 1 "GND") (pintype "passive"))
  )

  (footprint "antmicro-footprints:C_0402_1005Metric" (layer "B.Cu")
    (at 97.6 122.314284)
    (descr "Capacitor SMD 0402")
    (tags "capacitor SMD 0402")
    (property "Author" "Antmicro")
    (property "Dielectric" "")
    (property "License" "Apache-2.0")
    (property "MPN" "C1005X5R1E474M050BB")
    (property "Manufacturer" "TDK")
    (property "Public" "False")
    (property "Sheetfile" "fpga-banks.kicad_sch")
    (property "Sheetname" "FPGA banks")
    (property "Val" "470n")
    (property "Voltage" "")
    (property "ki_description" "SMD Multilayer Ceramic Capacitor, 0.47 µF, 25 V, 0402 [1005 Metric], ± 20%, X5R, C")
    (property "ki_keywords" "0402, SMT, CAPACITOR, PASSIVE, CERAMIC, MLCC")
    (attr smd)
    (fp_text reference "C231" (at -2.16 -0.209284) (layer "B.SilkS")
        (effects (font (size 0.7 0.7) (thickness 0.127)) (justify mirror))
    )
    (fp_text value "C_470n_0402" (at 0 -1.17) (layer "B.Fab")
        (effects (font (size 1 1) (thickness 0.15)) (justify mirror))
    )
    (fp_text user "${REFERENCE}" (at 0 0) (layer "B.Fab")
        (effects (font (size 0.25 0.25) (thickness 0.04)) (justify mirror))
    )
    (fp_text user "License: Apache-2.0" (at -0.939 -5.799 180) (layer "B.Fab") hide
        (effects (font (size 0.7 0.7) (thickness 0.15)) (justify left bottom mirror))
    )
    (fp_text user "Author: Antmicro" (at -0.939 -3.399 180) (layer "B.Fab") hide
        (effects (font (size 0.7 0.7) (thickness 0.15)) (justify left bottom mirror))
    )
    (fp_rect (start -0.925 0.47) (end 0.925 -0.47)
      (stroke (width 0.05) (type default)) (fill none) (layer "B.CrtYd"))
    (fp_line (start -0.494 -0.248) (end -0.494 0.25)
      (stroke (width 0.15) (type solid)) (layer "B.Fab"))
    (fp_line (start -0.494 0.25) (end 0.504 0.25)
      (stroke (width 0.15) (type solid)) (layer "B.Fab"))
    (fp_line (start 0.504 -0.248) (end -0.494 -0.248)
      (stroke (width 0.15) (type solid)) (layer "B.Fab"))
    (fp_line (start 0.504 0.25) (end 0.504 -0.248)
      (stroke (width 0.15) (type solid)) (layer "B.Fab"))
    (pad "1" smd roundrect (at -0.48 0) (size 0.59 0.64) (layers "B.Cu" "B.Paste" "B.Mask") (roundrect_rratio 0.25)
      (net 1 "GND") (pintype "passive"))
    (pad "2" smd roundrect (at 0.48 0) (size 0.59 0.64) (layers "B.Cu" "B.Paste" "B.Mask") (roundrect_rratio 0.25)
      (net 3 "VCC1V35") (pintype "passive"))
  )

  (footprint "antmicro-footprints:C_0402_1005Metric" (layer "B.Cu")
    (at 99.5 122.6 -90)
    (descr "Capacitor SMD 0402")
    (tags "capacitor SMD 0402")
    (property "Author" "Antmicro")
    (property "Dielectric" "")
    (property "License" "Apache-2.0")
    (property "MPN" "C1005X5R1E474M050BB")
    (property "Manufacturer" "TDK")
    (property "Public" "False")
    (property "Sheetfile" "fpga-banks.kicad_sch")
    (property "Sheetname" "FPGA banks")
    (property "Val" "470n")
    (property "Voltage" "")
    (property "ki_description" "SMD Multilayer Ceramic Capacitor, 0.47 µF, 25 V, 0402 [1005 Metric], ± 20%, X5R, C")
    (property "ki_keywords" "0402, SMT, CAPACITOR, PASSIVE, CERAMIC, MLCC")
    (attr smd)
    (fp_text reference "C232" (at 22.5 -0.05 90) (layer "B.SilkS")
        (effects (font (size 0.7 0.7) (thickness 0.127)) (justify mirror))
    )
    (fp_text value "C_470n_0402" (at 0 -1.17 90) (layer "B.Fab")
        (effects (font (size 1 1) (thickness 0.15)) (justify mirror))
    )
    (fp_text user "${REFERENCE}" (at 0 0 90) (layer "B.Fab")
        (effects (font (size 0.25 0.25) (thickness 0.04)) (justify mirror))
    )
    (fp_text user "Author: Antmicro" (at -0.939 -3.399 90) (layer "B.Fab") hide
        (effects (font (size 0.7 0.7) (thickness 0.15)) (justify left bottom mirror))
    )
    (fp_text user "License: Apache-2.0" (at -0.939 -5.799 90) (layer "B.Fab") hide
        (effects (font (size 0.7 0.7) (thickness 0.15)) (justify left bottom mirror))
    )
    (fp_rect (start -0.925 0.47) (end 0.925 -0.47)
      (stroke (width 0.05) (type default)) (fill none) (layer "B.CrtYd"))
    (fp_line (start -0.494 -0.248) (end -0.494 0.25)
      (stroke (width 0.15) (type solid)) (layer "B.Fab"))
    (fp_line (start -0.494 0.25) (end 0.504 0.25)
      (stroke (width 0.15) (type solid)) (layer "B.Fab"))
    (fp_line (start 0.504 -0.248) (end -0.494 -0.248)
      (stroke (width 0.15) (type solid)) (layer "B.Fab"))
    (fp_line (start 0.504 0.25) (end 0.504 -0.248)
      (stroke (width 0.15) (type solid)) (layer "B.Fab"))
    (pad "1" smd roundrect (at -0.48 0 270) (size 0.59 0.64) (layers "B.Cu" "B.Paste" "B.Mask") (roundrect_rratio 0.25)
      (net 3 "VCC1V35") (pintype "passive"))
    (pad "2" smd roundrect (at 0.48 0 270) (size 0.59 0.64) (layers "B.Cu" "B.Paste" "B.Mask") (roundrect_rratio 0.25)
      (net 1 "GND") (pintype "passive"))
  )

  (footprint "antmicro-footprints:C_0402_1005Metric" (layer "B.Cu")
    (at 79.45 116.95 180)
    (descr "Capacitor SMD 0402")
    (tags "capacitor SMD 0402")
    (property "Author" "Antmicro")
    (property "Dielectric" "")
    (property "License" "Apache-2.0")
    (property "MPN" "C1005X5R1E474M050BB")
    (property "Manufacturer" "TDK")
    (property "Public" "False")
    (property "Sheetfile" "fpga-banks.kicad_sch")
    (property "Sheetname" "FPGA banks")
    (property "Val" "470n")
    (property "Voltage" "")
    (property "ki_description" "SMD Multilayer Ceramic Capacitor, 0.47 µF, 25 V, 0402 [1005 Metric], ± 20%, X5R, C")
    (property "ki_keywords" "0402, SMT, CAPACITOR, PASSIVE, CERAMIC, MLCC")
    (attr smd)
    (fp_text reference "C233" (at -0.08 0.995) (layer "B.SilkS")
        (effects (font (size 0.7 0.7) (thickness 0.127)) (justify mirror))
    )
    (fp_text value "C_470n_0402" (at 0 -1.17) (layer "B.Fab")
        (effects (font (size 1 1) (thickness 0.15)) (justify mirror))
    )
    (fp_text user "License: Apache-2.0" (at -0.939 -5.799) (layer "B.Fab") hide
        (effects (font (size 0.7 0.7) (thickness 0.15)) (justify left bottom mirror))
    )
    (fp_text user "${REFERENCE}" (at 0 0) (layer "B.Fab")
        (effects (font (size 0.25 0.25) (thickness 0.04)) (justify mirror))
    )
    (fp_text user "Author: Antmicro" (at -0.939 -3.399) (layer "B.Fab") hide
        (effects (font (size 0.7 0.7) (thickness 0.15)) (justify left bottom mirror))
    )
    (fp_rect (start -0.925 0.47) (end 0.925 -0.47)
      (stroke (width 0.05) (type default)) (fill none) (layer "B.CrtYd"))
    (fp_line (start -0.494 -0.248) (end -0.494 0.25)
      (stroke (width 0.15) (type solid)) (layer "B.Fab"))
    (fp_line (start -0.494 0.25) (end 0.504 0.25)
      (stroke (width 0.15) (type solid)) (layer "B.Fab"))
    (fp_line (start 0.504 -0.248) (end -0.494 -0.248)
      (stroke (width 0.15) (type solid)) (layer "B.Fab"))
    (fp_line (start 0.504 0.25) (end 0.504 -0.248)
      (stroke (width 0.15) (type solid)) (layer "B.Fab"))
    (pad "1" smd roundrect (at -0.48 0 180) (size 0.59 0.64) (layers "B.Cu" "B.Paste" "B.Mask") (roundrect_rratio 0.25)
      (net 3 "VCC1V35") (pintype "passive"))
    (pad "2" smd roundrect (at 0.48 0 180) (size 0.59 0.64) (layers "B.Cu" "B.Paste" "B.Mask") (roundrect_rratio 0.25)
      (net 1 "GND") (pintype "passive"))
  )

  (footprint "antmicro-footprints:C_0402_1005Metric" (layer "B.Cu")
    (at 97.6 124.65 180)
    (descr "Capacitor SMD 0402")
    (tags "capacitor SMD 0402")
    (property "Author" "Antmicro")
    (property "Dielectric" "")
    (property "License" "Apache-2.0")
    (property "MPN" "C1005X5R1E474M050BB")
    (property "Manufacturer" "TDK")
    (property "Public" "False")
    (property "Sheetfile" "fpga-banks.kicad_sch")
    (property "Sheetname" "FPGA banks")
    (property "Val" "470n")
    (property "Voltage" "")
    (property "ki_description" "SMD Multilayer Ceramic Capacitor, 0.47 µF, 25 V, 0402 [1005 Metric], ± 20%, X5R, C")
    (property "ki_keywords" "0402, SMT, CAPACITOR, PASSIVE, CERAMIC, MLCC")
    (attr smd)
    (fp_text reference "C234" (at 2.3 -0.2) (layer "B.SilkS")
        (effects (font (size 0.7 0.7) (thickness 0.127)) (justify mirror))
    )
    (fp_text value "C_470n_0402" (at 0 -1.17) (layer "B.Fab")
        (effects (font (size 1 1) (thickness 0.15)) (justify mirror))
    )
    (fp_text user "License: Apache-2.0" (at -0.939 -5.799) (layer "B.Fab") hide
        (effects (font (size 0.7 0.7) (thickness 0.15)) (justify left bottom mirror))
    )
    (fp_text user "Author: Antmicro" (at -0.939 -3.399) (layer "B.Fab") hide
        (effects (font (size 0.7 0.7) (thickness 0.15)) (justify left bottom mirror))
    )
    (fp_text user "${REFERENCE}" (at 0 0) (layer "B.Fab")
        (effects (font (size 0.25 0.25) (thickness 0.04)) (justify mirror))
    )
    (fp_rect (start -0.925 0.47) (end 0.925 -0.47)
      (stroke (width 0.05) (type default)) (fill none) (layer "B.CrtYd"))
    (fp_line (start -0.494 -0.248) (end -0.494 0.25)
      (stroke (width 0.15) (type solid)) (layer "B.Fab"))
    (fp_line (start -0.494 0.25) (end 0.504 0.25)
      (stroke (width 0.15) (type solid)) (layer "B.Fab"))
    (fp_line (start 0.504 -0.248) (end -0.494 -0.248)
      (stroke (width 0.15) (type solid)) (layer "B.Fab"))
    (fp_line (start 0.504 0.25) (end 0.504 -0.248)
      (stroke (width 0.15) (type solid)) (layer "B.Fab"))
    (pad "1" smd roundrect (at -0.48 0 180) (size 0.59 0.64) (layers "B.Cu" "B.Paste" "B.Mask") (roundrect_rratio 0.25)
      (net 3 "VCC1V35") (pintype "passive"))
    (pad "2" smd roundrect (at 0.48 0 180) (size 0.59 0.64) (layers "B.Cu" "B.Paste" "B.Mask") (roundrect_rratio 0.25)
      (net 1 "GND") (pintype "passive"))
  )

  (footprint "antmicro-footprints:C_0402_1005Metric" (layer "B.Cu")
    (at 104.4 113.2 90)
    (descr "Capacitor SMD 0402")
    (tags "capacitor SMD 0402")
    (property "Author" "Antmicro")
    (property "Dielectric" "")
    (property "License" "Apache-2.0")
    (property "MPN" "GRM155R61A475MEAAD")
    (property "Manufacturer" "Murata")
    (property "Public" "False")
    (property "Sheetfile" "fpga-banks.kicad_sch")
    (property "Sheetname" "FPGA banks")
    (property "Val" "4u7")
    (property "Voltage" "")
    (property "ki_description" "SMD Multilayer Ceramic Capacitor, 4.7 µF, 10 V, 0402 [1005 Metric], ± 20%, X5R, GRM Series")
    (property "ki_keywords" "0402, SMT, CAPACITOR, PASSIVE")
    (attr smd)
    (fp_text reference "C235" (at 5.25 0.05 90) (layer "B.SilkS")
        (effects (font (size 0.7 0.7) (thickness 0.127)) (justify mirror))
    )
    (fp_text value "C_4u7_0402" (at 0 -1.17 90) (layer "B.Fab")
        (effects (font (size 1 1) (thickness 0.15)) (justify mirror))
    )
    (fp_text user "License: Apache-2.0" (at -0.939 -5.799 270) (layer "B.Fab") hide
        (effects (font (size 0.7 0.7) (thickness 0.15)) (justify left bottom mirror))
    )
    (fp_text user "Author: Antmicro" (at -0.939 -3.399 270) (layer "B.Fab") hide
        (effects (font (size 0.7 0.7) (thickness 0.15)) (justify left bottom mirror))
    )
    (fp_text user "${REFERENCE}" (at 0 0 90) (layer "B.Fab")
        (effects (font (size 0.25 0.25) (thickness 0.04)) (justify mirror))
    )
    (fp_rect (start -0.925 0.47) (end 0.925 -0.47)
      (stroke (width 0.05) (type default)) (fill none) (layer "B.CrtYd"))
    (fp_line (start -0.494 -0.248) (end -0.494 0.25)
      (stroke (width 0.15) (type solid)) (layer "B.Fab"))
    (fp_line (start -0.494 0.25) (end 0.504 0.25)
      (stroke (width 0.15) (type solid)) (layer "B.Fab"))
    (fp_line (start 0.504 -0.248) (end -0.494 -0.248)
      (stroke (width 0.15) (type solid)) (layer "B.Fab"))
    (fp_line (start 0.504 0.25) (end 0.504 -0.248)
      (stroke (width 0.15) (type solid)) (layer "B.Fab"))
    (pad "1" smd roundrect (at -0.48 0 90) (size 0.59 0.64) (layers "B.Cu" "B.Paste" "B.Mask") (roundrect_rratio 0.25)
      (net 2 "VCC3V3") (pintype "passive"))
    (pad "2" smd roundrect (at 0.48 0 90) (size 0.59 0.64) (layers "B.Cu" "B.Paste" "B.Mask") (roundrect_rratio 0.25)
      (net 1 "GND") (pintype "passive"))
  )

  (footprint "antmicro-footprints:C_0402_1005Metric" (layer "B.Cu")
    (at 97.6 116.1 180)
    (descr "Capacitor SMD 0402")
    (tags "capacitor SMD 0402")
    (property "Author" "Antmicro")
    (property "Dielectric" "")
    (property "License" "Apache-2.0")
    (property "MPN" "C1005X5R1E474M050BB")
    (property "Manufacturer" "TDK")
    (property "Public" "False")
    (property "Sheetfile" "fpga-banks.kicad_sch")
    (property "Sheetname" "FPGA banks")
    (property "Val" "470n")
    (property "Voltage" "")
    (property "ki_description" "SMD Multilayer Ceramic Capacitor, 0.47 µF, 25 V, 0402 [1005 Metric], ± 20%, X5R, C")
    (property "ki_keywords" "0402, SMT, CAPACITOR, PASSIVE, CERAMIC, MLCC")
    (attr smd)
    (fp_text reference "C236" (at 2.4 0.2) (layer "B.SilkS")
        (effects (font (size 0.7 0.7) (thickness 0.127)) (justify mirror))
    )
    (fp_text value "C_470n_0402" (at 0 -1.17) (layer "B.Fab")
        (effects (font (size 1 1) (thickness 0.15)) (justify mirror))
    )
    (fp_text user "Author: Antmicro" (at -0.939 -3.399) (layer "B.Fab") hide
        (effects (font (size 0.7 0.7) (thickness 0.15)) (justify left bottom mirror))
    )
    (fp_text user "${REFERENCE}" (at 0 0) (layer "B.Fab")
        (effects (font (size 0.25 0.25) (thickness 0.04)) (justify mirror))
    )
    (fp_text user "License: Apache-2.0" (at -0.939 -5.799) (layer "B.Fab") hide
        (effects (font (size 0.7 0.7) (thickness 0.15)) (justify left bottom mirror))
    )
    (fp_rect (start -0.925 0.47) (end 0.925 -0.47)
      (stroke (width 0.05) (type default)) (fill none) (layer "B.CrtYd"))
    (fp_line (start -0.494 -0.248) (end -0.494 0.25)
      (stroke (width 0.15) (type solid)) (layer "B.Fab"))
    (fp_line (start -0.494 0.25) (end 0.504 0.25)
      (stroke (width 0.15) (type solid)) (layer "B.Fab"))
    (fp_line (start 0.504 -0.248) (end -0.494 -0.248)
      (stroke (width 0.15) (type solid)) (layer "B.Fab"))
    (fp_line (start 0.504 0.25) (end 0.504 -0.248)
      (stroke (width 0.15) (type solid)) (layer "B.Fab"))
    (pad "1" smd roundrect (at -0.48 0 180) (size 0.59 0.64) (layers "B.Cu" "B.Paste" "B.Mask") (roundrect_rratio 0.25)
      (net 2 "VCC3V3") (pintype "passive"))
    (pad "2" smd roundrect (at 0.48 0 180) (size 0.59 0.64) (layers "B.Cu" "B.Paste" "B.Mask") (roundrect_rratio 0.25)
      (net 1 "GND") (pintype "passive"))
  )

  (footprint "antmicro-footprints:C_0402_1005Metric" (layer "B.Cu")
    (at 97.6 119.207142 180)
    (descr "Capacitor SMD 0402")
    (tags "capacitor SMD 0402")
    (property "Author" "Antmicro")
    (property "Dielectric" "")
    (property "License" "Apache-2.0")
    (property "MPN" "C1005X5R1E474M050BB")
    (property "Manufacturer" "TDK")
    (property "Public" "False")
    (property "Sheetfile" "fpga-banks.kicad_sch")
    (property "Sheetname" "FPGA banks")
    (property "Val" "470n")
    (property "Voltage" "")
    (property "ki_description" "SMD Multilayer Ceramic Capacitor, 0.47 µF, 25 V, 0402 [1005 Metric], ± 20%, X5R, C")
    (property "ki_keywords" "0402, SMT, CAPACITOR, PASSIVE, CERAMIC, MLCC")
    (attr smd)
    (fp_text reference "C237" (at 2.4 0.207142) (layer "B.SilkS")
        (effects (font (size 0.7 0.7) (thickness 0.127)) (justify mirror))
    )
    (fp_text value "C_470n_0402" (at 0 -1.17) (layer "B.Fab")
        (effects (font (size 1 1) (thickness 0.15)) (justify mirror))
    )
    (fp_text user "${REFERENCE}" (at 0 0) (layer "B.Fab")
        (effects (font (size 0.25 0.25) (thickness 0.04)) (justify mirror))
    )
    (fp_text user "Author: Antmicro" (at -0.939 -3.399) (layer "B.Fab") hide
        (effects (font (size 0.7 0.7) (thickness 0.15)) (justify left bottom mirror))
    )
    (fp_text user "License: Apache-2.0" (at -0.939 -5.799) (layer "B.Fab") hide
        (effects (font (size 0.7 0.7) (thickness 0.15)) (justify left bottom mirror))
    )
    (fp_rect (start -0.925 0.47) (end 0.925 -0.47)
      (stroke (width 0.05) (type default)) (fill none) (layer "B.CrtYd"))
    (fp_line (start -0.494 -0.248) (end -0.494 0.25)
      (stroke (width 0.15) (type solid)) (layer "B.Fab"))
    (fp_line (start -0.494 0.25) (end 0.504 0.25)
      (stroke (width 0.15) (type solid)) (layer "B.Fab"))
    (fp_line (start 0.504 -0.248) (end -0.494 -0.248)
      (stroke (width 0.15) (type solid)) (layer "B.Fab"))
    (fp_line (start 0.504 0.25) (end 0.504 -0.248)
      (stroke (width 0.15) (type solid)) (layer "B.Fab"))
    (pad "1" smd roundrect (at -0.48 0 180) (size 0.59 0.64) (layers "B.Cu" "B.Paste" "B.Mask") (roundrect_rratio 0.25)
      (net 2 "VCC3V3") (pintype "passive"))
    (pad "2" smd roundrect (at 0.48 0 180) (size 0.59 0.64) (layers "B.Cu" "B.Paste" "B.Mask") (roundrect_rratio 0.25)
      (net 1 "GND") (pintype "passive"))
  )

  (footprint "antmicro-footprints:C_0402_1005Metric" (layer "B.Cu")
    (at 97.6 118.171428 180)
    (descr "Capacitor SMD 0402")
    (tags "capacitor SMD 0402")
    (property "Author" "Antmicro")
    (property "Dielectric" "")
    (property "License" "Apache-2.0")
    (property "MPN" "C1005X5R1E474M050BB")
    (property "Manufacturer" "TDK")
    (property "Public" "False")
    (property "Sheetfile" "fpga-banks.kicad_sch")
    (property "Sheetname" "FPGA banks")
    (property "Val" "470n")
    (property "Voltage" "")
    (property "ki_description" "SMD Multilayer Ceramic Capacitor, 0.47 µF, 25 V, 0402 [1005 Metric], ± 20%, X5R, C")
    (property "ki_keywords" "0402, SMT, CAPACITOR, PASSIVE, CERAMIC, MLCC")
    (attr smd)
    (fp_text reference "C238" (at 2.4 0.221428) (layer "B.SilkS")
        (effects (font (size 0.7 0.7) (thickness 0.127)) (justify mirror))
    )
    (fp_text value "C_470n_0402" (at 0 -1.17) (layer "B.Fab")
        (effects (font (size 1 1) (thickness 0.15)) (justify mirror))
    )
    (fp_text user "License: Apache-2.0" (at -0.939 -5.799) (layer "B.Fab") hide
        (effects (font (size 0.7 0.7) (thickness 0.15)) (justify left bottom mirror))
    )
    (fp_text user "${REFERENCE}" (at 0 0) (layer "B.Fab")
        (effects (font (size 0.25 0.25) (thickness 0.04)) (justify mirror))
    )
    (fp_text user "Author: Antmicro" (at -0.939 -3.399) (layer "B.Fab") hide
        (effects (font (size 0.7 0.7) (thickness 0.15)) (justify left bottom mirror))
    )
    (fp_rect (start -0.925 0.47) (end 0.925 -0.47)
      (stroke (width 0.05) (type default)) (fill none) (layer "B.CrtYd"))
    (fp_line (start -0.494 -0.248) (end -0.494 0.25)
      (stroke (width 0.15) (type solid)) (layer "B.Fab"))
    (fp_line (start -0.494 0.25) (end 0.504 0.25)
      (stroke (width 0.15) (type solid)) (layer "B.Fab"))
    (fp_line (start 0.504 -0.248) (end -0.494 -0.248)
      (stroke (width 0.15) (type solid)) (layer "B.Fab"))
    (fp_line (start 0.504 0.25) (end 0.504 -0.248)
      (stroke (width 0.15) (type solid)) (layer "B.Fab"))
    (pad "1" smd roundrect (at -0.48 0 180) (size 0.59 0.64) (layers "B.Cu" "B.Paste" "B.Mask") (roundrect_rratio 0.25)
      (net 2 "VCC3V3") (pintype "passive"))
    (pad "2" smd roundrect (at 0.48 0 180) (size 0.59 0.64) (layers "B.Cu" "B.Paste" "B.Mask") (roundrect_rratio 0.25)
      (net 1 "GND") (pintype "passive"))
  )

  (footprint "antmicro-footprints:C_0402_1005Metric" (layer "B.Cu")
    (at 97.6 120.242856 180)
    (descr "Capacitor SMD 0402")
    (tags "capacitor SMD 0402")
    (property "Author" "Antmicro")
    (property "Dielectric" "")
    (property "License" "Apache-2.0")
    (property "MPN" "C1005X5R1E474M050BB")
    (property "Manufacturer" "TDK")
    (property "Public" "False")
    (property "Sheetfile" "fpga-banks.kicad_sch")
    (property "Sheetname" "FPGA banks")
    (property "Val" "470n")
    (property "Voltage" "")
    (property "ki_description" "SMD Multilayer Ceramic Capacitor, 0.47 µF, 25 V, 0402 [1005 Metric], ± 20%, X5R, C")
    (property "ki_keywords" "0402, SMT, CAPACITOR, PASSIVE, CERAMIC, MLCC")
    (attr smd)
    (fp_text reference "C239" (at 2.4 0.192856) (layer "B.SilkS")
        (effects (font (size 0.7 0.7) (thickness 0.127)) (justify mirror))
    )
    (fp_text value "C_470n_0402" (at 0 -1.17) (layer "B.Fab")
        (effects (font (size 1 1) (thickness 0.15)) (justify mirror))
    )
    (fp_text user "License: Apache-2.0" (at -0.939 -5.799) (layer "B.Fab") hide
        (effects (font (size 0.7 0.7) (thickness 0.15)) (justify left bottom mirror))
    )
    (fp_text user "${REFERENCE}" (at 0 0) (layer "B.Fab")
        (effects (font (size 0.25 0.25) (thickness 0.04)) (justify mirror))
    )
    (fp_text user "Author: Antmicro" (at -0.939 -3.399) (layer "B.Fab") hide
        (effects (font (size 0.7 0.7) (thickness 0.15)) (justify left bottom mirror))
    )
    (fp_rect (start -0.925 0.47) (end 0.925 -0.47)
      (stroke (width 0.05) (type default)) (fill none) (layer "B.CrtYd"))
    (fp_line (start -0.494 -0.248) (end -0.494 0.25)
      (stroke (width 0.15) (type solid)) (layer "B.Fab"))
    (fp_line (start -0.494 0.25) (end 0.504 0.25)
      (stroke (width 0.15) (type solid)) (layer "B.Fab"))
    (fp_line (start 0.504 -0.248) (end -0.494 -0.248)
      (stroke (width 0.15) (type solid)) (layer "B.Fab"))
    (fp_line (start 0.504 0.25) (end 0.504 -0.248)
      (stroke (width 0.15) (type solid)) (layer "B.Fab"))
    (pad "1" smd roundrect (at -0.48 0 180) (size 0.59 0.64) (layers "B.Cu" "B.Paste" "B.Mask") (roundrect_rratio 0.25)
      (net 2 "VCC3V3") (pintype "passive"))
    (pad "2" smd roundrect (at 0.48 0 180) (size 0.59 0.64) (layers "B.Cu" "B.Paste" "B.Mask") (roundrect_rratio 0.25)
      (net 1 "GND") (pintype "passive"))
  )

  (footprint "antmicro-footprints:FB_0603_1608Metric" (layer "B.Cu")
    (at 98.76 128.995 -90)
    (property "Author" "Antmicro")
    (property "Current" "")
    (property "License" "Apache-2.0")
    (property "MPN" "BLM18PG121SN1D")
    (property "Manufacturer" "Murata")
    (property "Public" "False")
    (property "Sheetfile" "fpga-power-supply.kicad_sch")
    (property "Sheetname" "FPGA power supply")
    (property "Val" "120Z/2A")
    (property "ki_description" "Ferrite Bead, 0603 [1608 Metric], 120 ohm, 2 A, BLM18P, 0.05 ohm, ± 25%, DC power line")
    (property "ki_keywords" "0603, SMT, FERRITE BEAD, PASSIVE")
    (attr smd)
    (fp_text reference "FB4" (at 21.52 -1.02 90) (layer "B.SilkS")
        (effects (font (size 0.7 0.7) (thickness 0.127)) (justify mirror))
    )
    (fp_text value "FB_120Z_2A_Murata-BLM18PG_0603" (at 0 -1.9 90) (layer "B.Fab")
        (effects (font (size 1 1) (thickness 0.15)) (justify mirror))
    )
    (fp_text user "${REFERENCE}" (at -1.653 -4.6 90) (layer "B.Fab") hide
        (effects (font (size 0.7 0.7) (thickness 0.15)) (justify left bottom mirror))
    )
    (fp_text user "License: Apache-2.0" (at -1.653 -5.9 90) (layer "B.Fab") hide
        (effects (font (size 0.7 0.7) (thickness 0.15)) (justify left bottom mirror))
    )
    (fp_text user "Author: Antmicro" (at -1.653 -3.162 90) (layer "B.Fab") hide
        (effects (font (size 0.7 0.7) (thickness 0.15)) (justify left bottom mirror))
    )
    (fp_line (start -0.15 -0.4) (end 0.15 -0.4)
      (stroke (width 0.15) (type solid)) (layer "B.SilkS"))
    (fp_line (start -0.15 0.4) (end 0.15 0.4)
      (stroke (width 0.15) (type solid)) (layer "B.SilkS"))
    (fp_rect (start -1.25 0.65) (end 1.25 -0.65)
      (stroke (width 0.05) (type solid)) (fill none) (layer "B.CrtYd"))
    (fp_line (start -0.803 -0.406) (end -0.803 0.408)
      (stroke (width 0.15) (type solid)) (layer "B.Fab"))
    (fp_line (start 0.8 -0.406) (end -0.803 -0.406)
      (stroke (width 0.15) (type solid)) (layer "B.Fab"))
    (fp_line (start 0.8 0.408) (end -0.803 0.408)
      (stroke (width 0.15) (type solid)) (layer "B.Fab"))
    (fp_line (start 0.8 0.408) (end 0.8 -0.406)
      (stroke (width 0.15) (type solid)) (layer "B.Fab"))
    (pad "1" smd roundrect (at -0.7 0 270) (size 0.8 1) (layers "B.Cu" "B.Paste" "B.Mask") (roundrect_rratio 0.2)
      (net 211 "VCC1V2") (pintype "passive"))
    (pad "2" smd roundrect (at 0.7 0 270) (size 0.8 1) (layers "B.Cu" "B.Paste" "B.Mask") (roundrect_rratio 0.2)
      (net 302 "/FPGA power supply/VCCA0") (pintype "passive"))
  )

  (footprint "antmicro-footprints:FB_0603_1608Metric" (layer "B.Cu")
    (at 99.8 127.075)
    (property "Author" "Antmicro")
    (property "Current" "")
    (property "License" "Apache-2.0")
    (property "MPN" "BLM18PG121SN1D")
    (property "Manufacturer" "Murata")
    (property "Public" "False")
    (property "Sheetfile" "fpga-power-supply.kicad_sch")
    (property "Sheetname" "FPGA power supply")
    (property "Val" "120Z/2A")
    (property "ki_description" "Ferrite Bead, 0603 [1608 Metric], 120 ohm, 2 A, BLM18P, 0.05 ohm, ± 25%, DC power line")
    (property "ki_keywords" "0603, SMT, FERRITE BEAD, PASSIVE")
    (attr smd)
    (fp_text reference "FB5" (at 0.15 21.71) (layer "B.SilkS")
        (effects (font (size 0.7 0.7) (thickness 0.127)) (justify mirror))
    )
    (fp_text value "FB_120Z_2A_Murata-BLM18PG_0603" (at 0 -1.9) (layer "B.Fab")
        (effects (font (size 1 1) (thickness 0.15)) (justify mirror))
    )
    (fp_text user "${REFERENCE}" (at -1.653 -4.6 180) (layer "B.Fab") hide
        (effects (font (size 0.7 0.7) (thickness 0.15)) (justify left bottom mirror))
    )
    (fp_text user "Author: Antmicro" (at -1.653 -3.162 180) (layer "B.Fab") hide
        (effects (font (size 0.7 0.7) (thickness 0.15)) (justify left bottom mirror))
    )
    (fp_text user "License: Apache-2.0" (at -1.653 -5.9 180) (layer "B.Fab") hide
        (effects (font (size 0.7 0.7) (thickness 0.15)) (justify left bottom mirror))
    )
    (fp_line (start -0.15 -0.4) (end 0.15 -0.4)
      (stroke (width 0.15) (type solid)) (layer "B.SilkS"))
    (fp_line (start -0.15 0.4) (end 0.15 0.4)
      (stroke (width 0.15) (type solid)) (layer "B.SilkS"))
    (fp_rect (start -1.25 0.65) (end 1.25 -0.65)
      (stroke (width 0.05) (type solid)) (fill none) (layer "B.CrtYd"))
    (fp_line (start -0.803 -0.406) (end -0.803 0.408)
      (stroke (width 0.15) (type solid)) (layer "B.Fab"))
    (fp_line (start 0.8 -0.406) (end -0.803 -0.406)
      (stroke (width 0.15) (type solid)) (layer "B.Fab"))
    (fp_line (start 0.8 0.408) (end -0.803 0.408)
      (stroke (width 0.15) (type solid)) (layer "B.Fab"))
    (fp_line (start 0.8 0.408) (end 0.8 -0.406)
      (stroke (width 0.15) (type solid)) (layer "B.Fab"))
    (pad "1" smd roundrect (at -0.7 0) (size 0.8 1) (layers "B.Cu" "B.Paste" "B.Mask") (roundrect_rratio 0.2)
      (net 211 "VCC1V2") (pintype "passive"))
    (pad "2" smd roundrect (at 0.7 0) (size 0.8 1) (layers "B.Cu" "B.Paste" "B.Mask") (roundrect_rratio 0.2)
      (net 5 "/FPGA power supply/VCCHTX0") (pintype "passive"))
  )

  (footprint "antmicro-footprints:FB_0603_1608Metric" (layer "B.Cu")
    (at 110.7 127.1 180)
    (property "Author" "Antmicro")
    (property "Current" "")
    (property "License" "Apache-2.0")
    (property "MPN" "BLM18PG121SN1D")
    (property "Manufacturer" "Murata")
    (property "Public" "False")
    (property "Sheetfile" "fpga-power-supply.kicad_sch")
    (property "Sheetname" "FPGA power supply")
    (property "Val" "120Z/2A")
    (property "ki_description" "Ferrite Bead, 0603 [1608 Metric], 120 ohm, 2 A, BLM18P, 0.05 ohm, ± 25%, DC power line")
    (property "ki_keywords" "0603, SMT, FERRITE BEAD, PASSIVE")
    (attr smd)
    (fp_text reference "FB6" (at -3.95 -0.2) (layer "B.SilkS")
        (effects (font (size 0.7 0.7) (thickness 0.127)) (justify mirror))
    )
    (fp_text value "FB_120Z_2A_Murata-BLM18PG_0603" (at 0 -1.9) (layer "B.Fab")
        (effects (font (size 1 1) (thickness 0.15)) (justify mirror))
    )
    (fp_text user "License: Apache-2.0" (at -1.653 -5.9) (layer "B.Fab") hide
        (effects (font (size 0.7 0.7) (thickness 0.15)) (justify left bottom mirror))
    )
    (fp_text user "${REFERENCE}" (at -1.653 -4.6) (layer "B.Fab") hide
        (effects (font (size 0.7 0.7) (thickness 0.15)) (justify left bottom mirror))
    )
    (fp_text user "Author: Antmicro" (at -1.653 -3.162) (layer "B.Fab") hide
        (effects (font (size 0.7 0.7) (thickness 0.15)) (justify left bottom mirror))
    )
    (fp_line (start -0.15 -0.4) (end 0.15 -0.4)
      (stroke (width 0.15) (type solid)) (layer "B.SilkS"))
    (fp_line (start -0.15 0.4) (end 0.15 0.4)
      (stroke (width 0.15) (type solid)) (layer "B.SilkS"))
    (fp_rect (start -1.25 0.65) (end 1.25 -0.65)
      (stroke (width 0.05) (type solid)) (fill none) (layer "B.CrtYd"))
    (fp_line (start -0.803 -0.406) (end -0.803 0.408)
      (stroke (width 0.15) (type solid)) (layer "B.Fab"))
    (fp_line (start 0.8 -0.406) (end -0.803 -0.406)
      (stroke (width 0.15) (type solid)) (layer "B.Fab"))
    (fp_line (start 0.8 0.408) (end -0.803 0.408)
      (stroke (width 0.15) (type solid)) (layer "B.Fab"))
    (fp_line (start 0.8 0.408) (end 0.8 -0.406)
      (stroke (width 0.15) (type solid)) (layer "B.Fab"))
    (pad "1" smd roundrect (at -0.7 0 180) (size 0.8 1) (layers "B.Cu" "B.Paste" "B.Mask") (roundrect_rratio 0.2)
      (net 211 "VCC1V2") (pintype "passive"))
    (pad "2" smd roundrect (at 0.7 0 180) (size 0.8 1) (layers "B.Cu" "B.Paste" "B.Mask") (roundrect_rratio 0.2)
      (net 6 "/FPGA power supply/VCCHTX1") (pintype "passive"))
  )

  (footprint "antmicro-footprints:FB_0603_1608Metric" (layer "B.Cu")
    (at 111.2 129.15 90)
    (property "Author" "Antmicro")
    (property "Current" "")
    (property "License" "Apache-2.0")
    (property "MPN" "BLM18PG121SN1D")
    (property "Manufacturer" "Murata")
    (property "Public" "False")
    (property "Sheetfile" "fpga-power-supply.kicad_sch")
    (property "Sheetname" "FPGA power supply")
    (property "Val" "120Z/2A")
    (property "ki_description" "Ferrite Bead, 0603 [1608 Metric], 120 ohm, 2 A, BLM18P, 0.05 ohm, ± 25%, DC power line")
    (property "ki_keywords" "0603, SMT, FERRITE BEAD, PASSIVE")
    (attr smd)
    (fp_text reference "FB7" (at 1.015 1.92 270) (layer "B.SilkS")
        (effects (font (size 0.7 0.7) (thickness 0.127)) (justify mirror))
    )
    (fp_text value "FB_120Z_2A_Murata-BLM18PG_0603" (at 0 -1.9 90) (layer "B.Fab")
        (effects (font (size 1 1) (thickness 0.15)) (justify mirror))
    )
    (fp_text user "License: Apache-2.0" (at -1.653 -5.9 270) (layer "B.Fab") hide
        (effects (font (size 0.7 0.7) (thickness 0.15)) (justify left bottom mirror))
    )
    (fp_text user "Author: Antmicro" (at -1.653 -3.162 270) (layer "B.Fab") hide
        (effects (font (size 0.7 0.7) (thickness 0.15)) (justify left bottom mirror))
    )
    (fp_text user "${REFERENCE}" (at -1.653 -4.6 270) (layer "B.Fab") hide
        (effects (font (size 0.7 0.7) (thickness 0.15)) (justify left bottom mirror))
    )
    (fp_line (start -0.15 -0.4) (end 0.15 -0.4)
      (stroke (width 0.15) (type solid)) (layer "B.SilkS"))
    (fp_line (start -0.15 0.4) (end 0.15 0.4)
      (stroke (width 0.15) (type solid)) (layer "B.SilkS"))
    (fp_rect (start -1.25 0.65) (end 1.25 -0.65)
      (stroke (width 0.05) (type solid)) (fill none) (layer "B.CrtYd"))
    (fp_line (start -0.803 -0.406) (end -0.803 0.408)
      (stroke (width 0.15) (type solid)) (layer "B.Fab"))
    (fp_line (start 0.8 -0.406) (end -0.803 -0.406)
      (stroke (width 0.15) (type solid)) (layer "B.Fab"))
    (fp_line (start 0.8 0.408) (end -0.803 0.408)
      (stroke (width 0.15) (type solid)) (layer "B.Fab"))
    (fp_line (start 0.8 0.408) (end 0.8 -0.406)
      (stroke (width 0.15) (type solid)) (layer "B.Fab"))
    (pad "1" smd roundrect (at -0.7 0 90) (size 0.8 1) (layers "B.Cu" "B.Paste" "B.Mask") (roundrect_rratio 0.2)
      (net 303 "/FPGA power supply/VCCA1") (pintype "passive"))
    (pad "2" smd roundrect (at 0.7 0 90) (size 0.8 1) (layers "B.Cu" "B.Paste" "B.Mask") (roundrect_rratio 0.2)
      (net 211 "VCC1V2") (pintype "passive"))
  )

  (footprint "antmicro-footprints:FB_0603_1608Metric" (layer "B.Cu")
    (at 113.8 132.55 -90)
    (property "Author" "Antmicro")
    (property "Current" "")
    (property "License" "Apache-2.0")
    (property "MPN" "BLM18PG121SN1D")
    (property "Manufacturer" "Murata")
    (property "Public" "False")
    (property "Sheetfile" "fpga-power-supply.kicad_sch")
    (property "Sheetname" "FPGA power supply")
    (property "Val" "120Z/2A")
    (property "ki_description" "Ferrite Bead, 0603 [1608 Metric], 120 ohm, 2 A, BLM18P, 0.05 ohm, ± 25%, DC power line")
    (property "ki_keywords" "0603, SMT, FERRITE BEAD, PASSIVE")
    (attr smd)
    (fp_text reference "FB8" (at 1.365 -1.34 90) (layer "B.SilkS")
        (effects (font (size 0.7 0.7) (thickness 0.127)) (justify mirror))
    )
    (fp_text value "FB_120Z_2A_Murata-BLM18PG_0603" (at 0 -1.9 90) (layer "B.Fab")
        (effects (font (size 1 1) (thickness 0.15)) (justify mirror))
    )
    (fp_text user "Author: Antmicro" (at -1.653 -3.162 90) (layer "B.Fab") hide
        (effects (font (size 0.7 0.7) (thickness 0.15)) (justify left bottom mirror))
    )
    (fp_text user "${REFERENCE}" (at -1.653 -4.6 90) (layer "B.Fab") hide
        (effects (font (size 0.7 0.7) (thickness 0.15)) (justify left bottom mirror))
    )
    (fp_text user "License: Apache-2.0" (at -1.653 -5.9 90) (layer "B.Fab") hide
        (effects (font (size 0.7 0.7) (thickness 0.15)) (justify left bottom mirror))
    )
    (fp_line (start -0.15 -0.4) (end 0.15 -0.4)
      (stroke (width 0.15) (type solid)) (layer "B.SilkS"))
    (fp_line (start -0.15 0.4) (end 0.15 0.4)
      (stroke (width 0.15) (type solid)) (layer "B.SilkS"))
    (fp_rect (start -1.25 0.65) (end 1.25 -0.65)
      (stroke (width 0.05) (type solid)) (fill none) (layer "B.CrtYd"))
    (fp_line (start -0.803 -0.406) (end -0.803 0.408)
      (stroke (width 0.15) (type solid)) (layer "B.Fab"))
    (fp_line (start 0.8 -0.406) (end -0.803 -0.406)
      (stroke (width 0.15) (type solid)) (layer "B.Fab"))
    (fp_line (start 0.8 0.408) (end -0.803 0.408)
      (stroke (width 0.15) (type solid)) (layer "B.Fab"))
    (fp_line (start 0.8 0.408) (end 0.8 -0.406)
      (stroke (width 0.15) (type solid)) (layer "B.Fab"))
    (pad "1" smd roundrect (at -0.7 0 270) (size 0.8 1) (layers "B.Cu" "B.Paste" "B.Mask") (roundrect_rratio 0.2)
      (net 304 "/FPGA power supply/VCCAUX") (pintype "passive"))
    (pad "2" smd roundrect (at 0.7 0 270) (size 0.8 1) (layers "B.Cu" "B.Paste" "B.Mask") (roundrect_rratio 0.2)
      (net 225 "VCC2V5") (pintype "passive"))
  )

  (footprint "antmicro-footprints:C_0402_1005Metric" (layer "B.Cu")
    (at 105.55 127.4 90)
    (descr "Capacitor SMD 0402")
    (tags "capacitor SMD 0402")
    (property "Author" "Antmicro")
    (property "Dielectric" "X5R")
    (property "License" "Apache-2.0")
    (property "MPN" "GRM155R61H104KE14D")
    (property "Manufacturer" "Murata")
    (property "Public" "False")
    (property "Sheetfile" "fpga-power-supply.kicad_sch")
    (property "Sheetname" "FPGA power supply")
    (property "Val" "100n")
    (property "Voltage" "50V")
    (property "ki_description" "SMD Multilayer Ceramic Capacitor, 0.1 µF, 50 V, 0402 [1005 Metric], ± 10%, X5R, GRM Series")
    (property "ki_keywords" "0402, SMT, CAPACITOR, PASSIVE, CERAMIC, MLCC")
    (attr smd)
    (fp_text reference "C139" (at 22.8 0.05 90) (layer "B.SilkS")
        (effects (font (size 0.7 0.7) (thickness 0.127)) (justify mirror))
    )
    (fp_text value "C_100n_0402" (at 0 -1.17 90) (layer "B.Fab")
        (effects (font (size 1 1) (thickness 0.15)) (justify mirror))
    )
    (fp_text user "${REFERENCE}" (at 0 0 90) (layer "B.Fab")
        (effects (font (size 0.25 0.25) (thickness 0.04)) (justify mirror))
    )
    (fp_text user "Author: Antmicro" (at -0.939 -3.399 270) (layer "B.Fab") hide
        (effects (font (size 0.7 0.7) (thickness 0.15)) (justify left bottom mirror))
    )
    (fp_text user "License: Apache-2.0" (at -0.939 -5.799 270) (layer "B.Fab") hide
        (effects (font (size 0.7 0.7) (thickness 0.15)) (justify left bottom mirror))
    )
    (fp_rect (start -0.925 0.47) (end 0.925 -0.47)
      (stroke (width 0.05) (type default)) (fill none) (layer "B.CrtYd"))
    (fp_line (start -0.494 -0.248) (end -0.494 0.25)
      (stroke (width 0.15) (type solid)) (layer "B.Fab"))
    (fp_line (start -0.494 0.25) (end 0.504 0.25)
      (stroke (width 0.15) (type solid)) (layer "B.Fab"))
    (fp_line (start 0.504 -0.248) (end -0.494 -0.248)
      (stroke (width 0.15) (type solid)) (layer "B.Fab"))
    (fp_line (start 0.504 0.25) (end 0.504 -0.248)
      (stroke (width 0.15) (type solid)) (layer "B.Fab"))
    (pad "1" smd roundrect (at -0.48 0 90) (size 0.59 0.64) (layers "B.Cu" "B.Paste" "B.Mask") (roundrect_rratio 0.25)
      (net 1 "GND") (pintype "passive"))
    (pad "2" smd roundrect (at 0.48 0 90) (size 0.59 0.64) (layers "B.Cu" "B.Paste" "B.Mask") (roundrect_rratio 0.25)
      (net 5 "/FPGA power supply/VCCHTX0") (pintype "passive"))
  )

  (footprint "antmicro-footprints:C_0402_1005Metric" (layer "B.Cu")
    (at 102.55 127.4 90)
    (descr "Capacitor SMD 0402")
    (tags "capacitor SMD 0402")
    (property "Author" "Antmicro")
    (property "Dielectric" "X5R")
    (property "License" "Apache-2.0")
    (property "MPN" "GRM155R61H104KE14D")
    (property "Manufacturer" "Murata")
    (property "Public" "False")
    (property "Sheetfile" "fpga-power-supply.kicad_sch")
    (property "Sheetname" "FPGA power supply")
    (property "Val" "100n")
    (property "Voltage" "50V")
    (property "ki_description" "SMD Multilayer Ceramic Capacitor, 0.1 µF, 50 V, 0402 [1005 Metric], ± 10%, X5R, GRM Series")
    (property "ki_keywords" "0402, SMT, CAPACITOR, PASSIVE, CERAMIC, MLCC")
    (attr smd)
    (fp_text reference "C140" (at 22.8 0.05 90) (layer "B.SilkS")
        (effects (font (size 0.7 0.7) (thickness 0.127)) (justify mirror))
    )
    (fp_text value "C_100n_0402" (at 0 -1.17 90) (layer "B.Fab")
        (effects (font (size 1 1) (thickness 0.15)) (justify mirror))
    )
    (fp_text user "Author: Antmicro" (at -0.939 -3.399 270) (layer "B.Fab") hide
        (effects (font (size 0.7 0.7) (thickness 0.15)) (justify left bottom mirror))
    )
    (fp_text user "${REFERENCE}" (at 0 0 90) (layer "B.Fab")
        (effects (font (size 0.25 0.25) (thickness 0.04)) (justify mirror))
    )
    (fp_text user "License: Apache-2.0" (at -0.939 -5.799 270) (layer "B.Fab") hide
        (effects (font (size 0.7 0.7) (thickness 0.15)) (justify left bottom mirror))
    )
    (fp_rect (start -0.925 0.47) (end 0.925 -0.47)
      (stroke (width 0.05) (type default)) (fill none) (layer "B.CrtYd"))
    (fp_line (start -0.494 -0.248) (end -0.494 0.25)
      (stroke (width 0.15) (type solid)) (layer "B.Fab"))
    (fp_line (start -0.494 0.25) (end 0.504 0.25)
      (stroke (width 0.15) (type solid)) (layer "B.Fab"))
    (fp_line (start 0.504 -0.248) (end -0.494 -0.248)
      (stroke (width 0.15) (type solid)) (layer "B.Fab"))
    (fp_line (start 0.504 0.25) (end 0.504 -0.248)
      (stroke (width 0.15) (type solid)) (layer "B.Fab"))
    (pad "1" smd roundrect (at -0.48 0 90) (size 0.59 0.64) (layers "B.Cu" "B.Paste" "B.Mask") (roundrect_rratio 0.25)
      (net 1 "GND") (pintype "passive"))
    (pad "2" smd roundrect (at 0.48 0 90) (size 0.59 0.64) (layers "B.Cu" "B.Paste" "B.Mask") (roundrect_rratio 0.25)
      (net 302 "/FPGA power supply/VCCA0") (pintype "passive"))
  )

  (footprint "antmicro-footprints:C_0402_1005Metric" (layer "B.Cu")
    (at 108.55 127.4 90)
    (descr "Capacitor SMD 0402")
    (tags "capacitor SMD 0402")
    (property "Author" "Antmicro")
    (property "Dielectric" "X5R")
    (property "License" "Apache-2.0")
    (property "MPN" "GRM155R61H104KE14D")
    (property "Manufacturer" "Murata")
    (property "Public" "False")
    (property "Sheetfile" "fpga-power-supply.kicad_sch")
    (property "Sheetname" "FPGA power supply")
    (property "Val" "100n")
    (property "Voltage" "50V")
    (property "ki_description" "SMD Multilayer Ceramic Capacitor, 0.1 µF, 50 V, 0402 [1005 Metric], ± 10%, X5R, GRM Series")
    (property "ki_keywords" "0402, SMT, CAPACITOR, PASSIVE, CERAMIC, MLCC")
    (attr smd)
    (fp_text reference "C141" (at 22.8 -0.05 90) (layer "B.SilkS")
        (effects (font (size 0.7 0.7) (thickness 0.127)) (justify mirror))
    )
    (fp_text value "C_100n_0402" (at 0 -1.17 90) (layer "B.Fab")
        (effects (font (size 1 1) (thickness 0.15)) (justify mirror))
    )
    (fp_text user "Author: Antmicro" (at -0.939 -3.399 270) (layer "B.Fab") hide
        (effects (font (size 0.7 0.7) (thickness 0.15)) (justify left bottom mirror))
    )
    (fp_text user "${REFERENCE}" (at 0 0 90) (layer "B.Fab")
        (effects (font (size 0.25 0.25) (thickness 0.04)) (justify mirror))
    )
    (fp_text user "License: Apache-2.0" (at -0.939 -5.799 270) (layer "B.Fab") hide
        (effects (font (size 0.7 0.7) (thickness 0.15)) (justify left bottom mirror))
    )
    (fp_rect (start -0.925 0.47) (end 0.925 -0.47)
      (stroke (width 0.05) (type default)) (fill none) (layer "B.CrtYd"))
    (fp_line (start -0.494 -0.248) (end -0.494 0.25)
      (stroke (width 0.15) (type solid)) (layer "B.Fab"))
    (fp_line (start -0.494 0.25) (end 0.504 0.25)
      (stroke (width 0.15) (type solid)) (layer "B.Fab"))
    (fp_line (start 0.504 -0.248) (end -0.494 -0.248)
      (stroke (width 0.15) (type solid)) (layer "B.Fab"))
    (fp_line (start 0.504 0.25) (end 0.504 -0.248)
      (stroke (width 0.15) (type solid)) (layer "B.Fab"))
    (pad "1" smd roundrect (at -0.48 0 90) (size 0.59 0.64) (layers "B.Cu" "B.Paste" "B.Mask") (roundrect_rratio 0.25)
      (net 1 "GND") (pintype "passive"))
    (pad "2" smd roundrect (at 0.48 0 90) (size 0.59 0.64) (layers "B.Cu" "B.Paste" "B.Mask") (roundrect_rratio 0.25)
      (net 6 "/FPGA power supply/VCCHTX1") (pintype "passive"))
  )

  (footprint "antmicro-footprints:C_0402_1005Metric" (layer "B.Cu")
    (at 107.95 130.2)
    (descr "Capacitor SMD 0402")
    (tags "capacitor SMD 0402")
    (property "Author" "Antmicro")
    (property "Dielectric" "X5R")
    (property "License" "Apache-2.0")
    (property "MPN" "GRM155R61H104KE14D")
    (property "Manufacturer" "Murata")
    (property "Public" "False")
    (property "Sheetfile" "fpga-power-supply.kicad_sch")
    (property "Sheetname" "FPGA power supply")
    (property "Val" "100n")
    (property "Voltage" "50V")
    (property "ki_description" "SMD Multilayer Ceramic Capacitor, 0.1 µF, 50 V, 0402 [1005 Metric], ± 10%, X5R, GRM Series")
    (property "ki_keywords" "0402, SMT, CAPACITOR, PASSIVE, CERAMIC, MLCC")
    (attr smd)
    (fp_text reference "C142" (at 0.66 20.875) (layer "B.SilkS")
        (effects (font (size 0.7 0.7) (thickness 0.127)) (justify mirror))
    )
    (fp_text value "C_100n_0402" (at 0 -1.17) (layer "B.Fab")
        (effects (font (size 1 1) (thickness 0.15)) (justify mirror))
    )
    (fp_text user "${REFERENCE}" (at 0 0) (layer "B.Fab")
        (effects (font (size 0.25 0.25) (thickness 0.04)) (justify mirror))
    )
    (fp_text user "License: Apache-2.0" (at -0.939 -5.799 180) (layer "B.Fab") hide
        (effects (font (size 0.7 0.7) (thickness 0.15)) (justify left bottom mirror))
    )
    (fp_text user "Author: Antmicro" (at -0.939 -3.399 180) (layer "B.Fab") hide
        (effects (font (size 0.7 0.7) (thickness 0.15)) (justify left bottom mirror))
    )
    (fp_rect (start -0.925 0.47) (end 0.925 -0.47)
      (stroke (width 0.05) (type default)) (fill none) (layer "B.CrtYd"))
    (fp_line (start -0.494 -0.248) (end -0.494 0.25)
      (stroke (width 0.15) (type solid)) (layer "B.Fab"))
    (fp_line (start -0.494 0.25) (end 0.504 0.25)
      (stroke (width 0.15) (type solid)) (layer "B.Fab"))
    (fp_line (start 0.504 -0.248) (end -0.494 -0.248)
      (stroke (width 0.15) (type solid)) (layer "B.Fab"))
    (fp_line (start 0.504 0.25) (end 0.504 -0.248)
      (stroke (width 0.15) (type solid)) (layer "B.Fab"))
    (pad "1" smd roundrect (at -0.48 0) (size 0.59 0.64) (layers "B.Cu" "B.Paste" "B.Mask") (roundrect_rratio 0.25)
      (net 1 "GND") (pintype "passive"))
    (pad "2" smd roundrect (at 0.48 0) (size 0.59 0.64) (layers "B.Cu" "B.Paste" "B.Mask") (roundrect_rratio 0.25)
      (net 303 "/FPGA power supply/VCCA1") (pintype "passive"))
  )

  (footprint "antmicro-footprints:C_0402_1005Metric" (layer "B.Cu")
    (at 101.55 127.4 90)
    (descr "Capacitor SMD 0402")
    (tags "capacitor SMD 0402")
    (property "Author" "Antmicro")
    (property "Dielectric" "X7R")
    (property "License" "Apache-2.0")
    (property "MPN" "GRM155R71H103KA88D")
    (property "Manufacturer" "Murata")
    (property "Public" "False")
    (property "Sheetfile" "fpga-power-supply.kicad_sch")
    (property "Sheetname" "FPGA power supply")
    (property "Val" "10n")
    (property "Voltage" "50V")
    (property "ki_description" "SMD Multilayer Ceramic Capacitor, 10000 pF, 50 V, 0402 [1005 Metric], ± 10%, X7R, GRM Series")
    (property "ki_keywords" "0402, SMT, CAPACITOR, PASSIVE")
    (attr smd)
    (fp_text reference "C144" (at -20.475 2.06 90) (layer "B.SilkS")
        (effects (font (size 0.7 0.7) (thickness 0.127)) (justify mirror))
    )
    (fp_text value "C_10n_0402" (at 0 -1.17 90) (layer "B.Fab")
        (effects (font (size 1 1) (thickness 0.15)) (justify mirror))
    )
    (fp_text user "Author: Antmicro" (at -0.939 -3.399 270) (layer "B.Fab") hide
        (effects (font (size 0.7 0.7) (thickness 0.15)) (justify left bottom mirror))
    )
    (fp_text user "License: Apache-2.0" (at -0.939 -5.799 270) (layer "B.Fab") hide
        (effects (font (size 0.7 0.7) (thickness 0.15)) (justify left bottom mirror))
    )
    (fp_text user "${REFERENCE}" (at 0 0 90) (layer "B.Fab")
        (effects (font (size 0.25 0.25) (thickness 0.04)) (justify mirror))
    )
    (fp_rect (start -0.925 0.47) (end 0.925 -0.47)
      (stroke (width 0.05) (type default)) (fill none) (layer "B.CrtYd"))
    (fp_line (start -0.494 -0.248) (end -0.494 0.25)
      (stroke (width 0.15) (type solid)) (layer "B.Fab"))
    (fp_line (start -0.494 0.25) (end 0.504 0.25)
      (stroke (width 0.15) (type solid)) (layer "B.Fab"))
    (fp_line (start 0.504 -0.248) (end -0.494 -0.248)
      (stroke (width 0.15) (type solid)) (layer "B.Fab"))
    (fp_line (start 0.504 0.25) (end 0.504 -0.248)
      (stroke (width 0.15) (type solid)) (layer "B.Fab"))
    (pad "1" smd roundrect (at -0.48 0 90) (size 0.59 0.64) (layers "B.Cu" "B.Paste" "B.Mask") (roundrect_rratio 0.25)
      (net 1 "GND") (pintype "passive"))
    (pad "2" smd roundrect (at 0.48 0 90) (size 0.59 0.64) (layers "B.Cu" "B.Paste" "B.Mask") (roundrect_rratio 0.25)
      (net 5 "/FPGA power supply/VCCHTX0") (pintype "passive"))
  )

  (footprint "antmicro-footprints:C_0402_1005Metric" (layer "B.Cu")
    (at 104.55 127.4 90)
    (descr "Capacitor SMD 0402")
    (tags "capacitor SMD 0402")
    (property "Author" "Antmicro")
    (property "Dielectric" "X7R")
    (property "License" "Apache-2.0")
    (property "MPN" "GRM155R71H103KA88D")
    (property "Manufacturer" "Murata")
    (property "Public" "False")
    (property "Sheetfile" "fpga-power-supply.kicad_sch")
    (property "Sheetname" "FPGA power supply")
    (property "Val" "10n")
    (property "Voltage" "50V")
    (property "ki_description" "SMD Multilayer Ceramic Capacitor, 10000 pF, 50 V, 0402 [1005 Metric], ± 10%, X7R, GRM Series")
    (property "ki_keywords" "0402, SMT, CAPACITOR, PASSIVE")
    (attr smd)
    (fp_text reference "C146" (at 22.8 0 90) (layer "B.SilkS")
        (effects (font (size 0.7 0.7) (thickness 0.127)) (justify mirror))
    )
    (fp_text value "C_10n_0402" (at 0 -1.17 90) (layer "B.Fab")
        (effects (font (size 1 1) (thickness 0.15)) (justify mirror))
    )
    (fp_text user "${REFERENCE}" (at 0 0 90) (layer "B.Fab")
        (effects (font (size 0.25 0.25) (thickness 0.04)) (justify mirror))
    )
    (fp_text user "License: Apache-2.0" (at -0.939 -5.799 270) (layer "B.Fab") hide
        (effects (font (size 0.7 0.7) (thickness 0.15)) (justify left bottom mirror))
    )
    (fp_text user "Author: Antmicro" (at -0.939 -3.399 270) (layer "B.Fab") hide
        (effects (font (size 0.7 0.7) (thickness 0.15)) (justify left bottom mirror))
    )
    (fp_rect (start -0.925 0.47) (end 0.925 -0.47)
      (stroke (width 0.05) (type default)) (fill none) (layer "B.CrtYd"))
    (fp_line (start -0.494 -0.248) (end -0.494 0.25)
      (stroke (width 0.15) (type solid)) (layer "B.Fab"))
    (fp_line (start -0.494 0.25) (end 0.504 0.25)
      (stroke (width 0.15) (type solid)) (layer "B.Fab"))
    (fp_line (start 0.504 -0.248) (end -0.494 -0.248)
      (stroke (width 0.15) (type solid)) (layer "B.Fab"))
    (fp_line (start 0.504 0.25) (end 0.504 -0.248)
      (stroke (width 0.15) (type solid)) (layer "B.Fab"))
    (pad "1" smd roundrect (at -0.48 0 90) (size 0.59 0.64) (layers "B.Cu" "B.Paste" "B.Mask") (roundrect_rratio 0.25)
      (net 1 "GND") (pintype "passive"))
    (pad "2" smd roundrect (at 0.48 0 90) (size 0.59 0.64) (layers "B.Cu" "B.Paste" "B.Mask") (roundrect_rratio 0.25)
      (net 6 "/FPGA power supply/VCCHTX1") (pintype "passive"))
  )

  (footprint "antmicro-footprints:C_0402_1005Metric" (layer "B.Cu")
    (at 100.45 128.8 90)
    (descr "Capacitor SMD 0402")
    (tags "capacitor SMD 0402")
    (property "Author" "Antmicro")
    (property "Dielectric" "C0G")
    (property "License" "Apache-2.0")
    (property "MPN" "GRM1555C1H102JA01D")
    (property "Manufacturer" "Murata")
    (property "Public" "False")
    (property "Sheetfile" "fpga-power-supply.kicad_sch")
    (property "Sheetname" "FPGA power supply")
    (property "Val" "1n")
    (property "Voltage" "50V")
    (property "ki_description" "SMD Multilayer Ceramic Capacitor, 1000 pF, 50 V, 0402 [1005 Metric], ± 5%, C0G / NP0, GRM Series")
    (property "ki_keywords" "0402, SMT, CAPACITOR, PASSIVE, CERAMIC, MLCC")
    (attr smd)
    (fp_text reference "C149" (at -19.095 2.25 90) (layer "B.SilkS")
        (effects (font (size 0.7 0.7) (thickness 0.127)) (justify mirror))
    )
    (fp_text value "C_1n_0402" (at 0 -1.17 90) (layer "B.Fab")
        (effects (font (size 1 1) (thickness 0.15)) (justify mirror))
    )
    (fp_text user "License: Apache-2.0" (at -0.939 -5.799 270) (layer "B.Fab") hide
        (effects (font (size 0.7 0.7) (thickness 0.15)) (justify left bottom mirror))
    )
    (fp_text user "Author: Antmicro" (at -0.939 -3.399 270) (layer "B.Fab") hide
        (effects (font (size 0.7 0.7) (thickness 0.15)) (justify left bottom mirror))
    )
    (fp_text user "${REFERENCE}" (at 0 0 90) (layer "B.Fab")
        (effects (font (size 0.25 0.25) (thickness 0.04)) (justify mirror))
    )
    (fp_rect (start -0.925 0.47) (end 0.925 -0.47)
      (stroke (width 0.05) (type default)) (fill none) (layer "B.CrtYd"))
    (fp_line (start -0.494 -0.248) (end -0.494 0.25)
      (stroke (width 0.15) (type solid)) (layer "B.Fab"))
    (fp_line (start -0.494 0.25) (end 0.504 0.25)
      (stroke (width 0.15) (type solid)) (layer "B.Fab"))
    (fp_line (start 0.504 -0.248) (end -0.494 -0.248)
      (stroke (width 0.15) (type solid)) (layer "B.Fab"))
    (fp_line (start 0.504 0.25) (end 0.504 -0.248)
      (stroke (width 0.15) (type solid)) (layer "B.Fab"))
    (pad "1" smd roundrect (at -0.48 0 90) (size 0.59 0.64) (layers "B.Cu" "B.Paste" "B.Mask") (roundrect_rratio 0.25)
      (net 1 "GND") (pintype "passive"))
    (pad "2" smd roundrect (at 0.48 0 90) (size 0.59 0.64) (layers "B.Cu" "B.Paste" "B.Mask") (roundrect_rratio 0.25)
      (net 5 "/FPGA power supply/VCCHTX0") (pintype "passive"))
  )

  (footprint "antmicro-footprints:C_0402_1005Metric" (layer "B.Cu")
    (at 109.95 128.8 90)
    (descr "Capacitor SMD 0402")
    (tags "capacitor SMD 0402")
    (property "Author" "Antmicro")
    (property "Dielectric" "C0G")
    (property "License" "Apache-2.0")
    (property "MPN" "GRM1555C1H102JA01D")
    (property "Manufacturer" "Murata")
    (property "Public" "False")
    (property "Sheetfile" "fpga-power-supply.kicad_sch")
    (property "Sheetname" "FPGA power supply")
    (property "Val" "1n")
    (property "Voltage" "50V")
    (property "ki_description" "SMD Multilayer Ceramic Capacitor, 1000 pF, 50 V, 0402 [1005 Metric], ± 5%, C0G / NP0, GRM Series")
    (property "ki_keywords" "0402, SMT, CAPACITOR, PASSIVE, CERAMIC, MLCC")
    (attr smd)
    (fp_text reference "C151" (at 23.5 0 90) (layer "B.SilkS")
        (effects (font (size 0.7 0.7) (thickness 0.127)) (justify mirror))
    )
    (fp_text value "C_1n_0402" (at 0 -1.17 90) (layer "B.Fab")
        (effects (font (size 1 1) (thickness 0.15)) (justify mirror))
    )
    (fp_text user "${REFERENCE}" (at 0 0 90) (layer "B.Fab")
        (effects (font (size 0.25 0.25) (thickness 0.04)) (justify mirror))
    )
    (fp_text user "Author: Antmicro" (at -0.939 -3.399 270) (layer "B.Fab") hide
        (effects (font (size 0.7 0.7) (thickness 0.15)) (justify left bottom mirror))
    )
    (fp_text user "License: Apache-2.0" (at -0.939 -5.799 270) (layer "B.Fab") hide
        (effects (font (size 0.7 0.7) (thickness 0.15)) (justify left bottom mirror))
    )
    (fp_rect (start -0.925 0.47) (end 0.925 -0.47)
      (stroke (width 0.05) (type default)) (fill none) (layer "B.CrtYd"))
    (fp_line (start -0.494 -0.248) (end -0.494 0.25)
      (stroke (width 0.15) (type solid)) (layer "B.Fab"))
    (fp_line (start -0.494 0.25) (end 0.504 0.25)
      (stroke (width 0.15) (type solid)) (layer "B.Fab"))
    (fp_line (start 0.504 -0.248) (end -0.494 -0.248)
      (stroke (width 0.15) (type solid)) (layer "B.Fab"))
    (fp_line (start 0.504 0.25) (end 0.504 -0.248)
      (stroke (width 0.15) (type solid)) (layer "B.Fab"))
    (pad "1" smd roundrect (at -0.48 0 90) (size 0.59 0.64) (layers "B.Cu" "B.Paste" "B.Mask") (roundrect_rratio 0.25)
      (net 1 "GND") (pintype "passive"))
    (pad "2" smd roundrect (at 0.48 0 90) (size 0.59 0.64) (layers "B.Cu" "B.Paste" "B.Mask") (roundrect_rratio 0.25)
      (net 6 "/FPGA power supply/VCCHTX1") (pintype "passive"))
  )

  (footprint "antmicro-footprints:C_0402_1005Metric" (layer "B.Cu")
    (at 106.75 117.05 -90)
    (descr "Capacitor SMD 0402")
    (tags "capacitor SMD 0402")
    (property "Author" "Antmicro")
    (property "Dielectric" "")
    (property "License" "Apache-2.0")
    (property "MPN" "C1005X5R1E474M050BB")
    (property "Manufacturer" "TDK")
    (property "Public" "False")
    (property "Sheetfile" "fpga-power-supply.kicad_sch")
    (property "Sheetname" "FPGA power supply")
    (property "Val" "470n")
    (property "Voltage" "")
    (property "ki_description" "SMD Multilayer Ceramic Capacitor, 0.47 µF, 25 V, 0402 [1005 Metric], ± 20%, X5R, C")
    (property "ki_keywords" "0402, SMT, CAPACITOR, PASSIVE, CERAMIC, MLCC")
    (attr smd)
    (fp_text reference "C194" (at 22.7 0 -90) (layer "B.SilkS")
        (effects (font (size 0.7 0.7) (thickness 0.127)) (justify mirror))
    )
    (fp_text value "C_470n_0402" (at 0 -1.17 -90) (layer "B.Fab")
        (effects (font (size 1 1) (thickness 0.15)) (justify mirror))
    )
    (fp_text user "Author: Antmicro" (at -0.939 -3.399 90) (layer "B.Fab") hide
        (effects (font (size 0.7 0.7) (thickness 0.15)) (justify left bottom mirror))
    )
    (fp_text user "License: Apache-2.0" (at -0.939 -5.799 90) (layer "B.Fab") hide
        (effects (font (size 0.7 0.7) (thickness 0.15)) (justify left bottom mirror))
    )
    (fp_text user "${REFERENCE}" (at 0 0 -90) (layer "B.Fab")
        (effects (font (size 0.25 0.25) (thickness 0.04)) (justify mirror))
    )
    (fp_rect (start -0.925 0.47) (end 0.925 -0.47)
      (stroke (width 0.05) (type default)) (fill none) (layer "B.CrtYd"))
    (fp_line (start -0.494 -0.248) (end -0.494 0.25)
      (stroke (width 0.15) (type solid)) (layer "B.Fab"))
    (fp_line (start -0.494 0.25) (end 0.504 0.25)
      (stroke (width 0.15) (type solid)) (layer "B.Fab"))
    (fp_line (start 0.504 -0.248) (end -0.494 -0.248)
      (stroke (width 0.15) (type solid)) (layer "B.Fab"))
    (fp_line (start 0.504 0.25) (end 0.504 -0.248)
      (stroke (width 0.15) (type solid)) (layer "B.Fab"))
    (pad "1" smd roundrect (at -0.48 0 270) (size 0.59 0.64) (layers "B.Cu" "B.Paste" "B.Mask") (roundrect_rratio 0.25)
      (net 211 "VCC1V2") (pintype "passive"))
    (pad "2" smd roundrect (at 0.48 0 270) (size 0.59 0.64) (layers "B.Cu" "B.Paste" "B.Mask") (roundrect_rratio 0.25)
      (net 1 "GND") (pintype "passive"))
  )

  (footprint "antmicro-footprints:C_0402_1005Metric" (layer "B.Cu")
    (at 104.85 129.2)
    (descr "Capacitor SMD 0402")
    (tags "capacitor SMD 0402")
    (property "Author" "Antmicro")
    (property "Dielectric" "C0G")
    (property "License" "Apache-2.0")
    (property "MPN" "GRM1555C1H102JA01D")
    (property "Manufacturer" "Murata")
    (property "Public" "False")
    (property "Sheetfile" "fpga-power-supply.kicad_sch")
    (property "Sheetname" "FPGA power supply")
    (property "Val" "1n")
    (property "Voltage" "50V")
    (property "ki_description" "SMD Multilayer Ceramic Capacitor, 1000 pF, 50 V, 0402 [1005 Metric], ± 5%, C0G / NP0, GRM Series")
    (property "ki_keywords" "0402, SMT, CAPACITOR, PASSIVE, CERAMIC, MLCC")
    (attr smd)
    (fp_text reference "C180" (at 0.29 20.695) (layer "B.SilkS")
        (effects (font (size 0.7 0.7) (thickness 0.127)) (justify mirror))
    )
    (fp_text value "C_1n_0402" (at 0 -1.17) (layer "B.Fab")
        (effects (font (size 1 1) (thickness 0.15)) (justify mirror))
    )
    (fp_text user "License: Apache-2.0" (at -0.939 -5.799 180) (layer "B.Fab") hide
        (effects (font (size 0.7 0.7) (thickness 0.15)) (justify left bottom mirror))
    )
    (fp_text user "${REFERENCE}" (at 0 0) (layer "B.Fab")
        (effects (font (size 0.25 0.25) (thickness 0.04)) (justify mirror))
    )
    (fp_text user "Author: Antmicro" (at -0.939 -3.399 180) (layer "B.Fab") hide
        (effects (font (size 0.7 0.7) (thickness 0.15)) (justify left bottom mirror))
    )
    (fp_rect (start -0.925 0.47) (end 0.925 -0.47)
      (stroke (width 0.05) (type default)) (fill none) (layer "B.CrtYd"))
    (fp_line (start -0.494 -0.248) (end -0.494 0.25)
      (stroke (width 0.15) (type solid)) (layer "B.Fab"))
    (fp_line (start -0.494 0.25) (end 0.504 0.25)
      (stroke (width 0.15) (type solid)) (layer "B.Fab"))
    (fp_line (start 0.504 -0.248) (end -0.494 -0.248)
      (stroke (width 0.15) (type solid)) (layer "B.Fab"))
    (fp_line (start 0.504 0.25) (end 0.504 -0.248)
      (stroke (width 0.15) (type solid)) (layer "B.Fab"))
    (pad "1" smd roundrect (at -0.48 0) (size 0.59 0.64) (layers "B.Cu" "B.Paste" "B.Mask") (roundrect_rratio 0.25)
      (net 1 "GND") (pintype "passive"))
    (pad "2" smd roundrect (at 0.48 0) (size 0.59 0.64) (layers "B.Cu" "B.Paste" "B.Mask") (roundrect_rratio 0.25)
      (net 303 "/FPGA power supply/VCCA1") (pintype "passive"))
  )

  (footprint "antmicro-footprints:C_0402_1005Metric" (layer "B.Cu")
    (at 96.865 128.8)
    (descr "Capacitor SMD 0402")
    (tags "capacitor SMD 0402")
    (property "Author" "Antmicro")
    (property "Dielectric" "C0G")
    (property "License" "Apache-2.0")
    (property "MPN" "GRM1555C1H102JA01D")
    (property "Manufacturer" "Murata")
    (property "Public" "False")
    (property "Sheetfile" "fpga-power-supply.kicad_sch")
    (property "Sheetname" "FPGA power supply")
    (property "Val" "1n")
    (property "Voltage" "50V")
    (property "ki_description" "SMD Multilayer Ceramic Capacitor, 1000 pF, 50 V, 0402 [1005 Metric], ± 5%, C0G / NP0, GRM Series")
    (property "ki_keywords" "0402, SMT, CAPACITOR, PASSIVE, CERAMIC, MLCC")
    (attr smd)
    (fp_text reference "C153" (at -2.895 -0.185) (layer "B.SilkS")
        (effects (font (size 0.7 0.7) (thickness 0.127)) (justify mirror))
    )
    (fp_text value "C_1n_0402" (at 0 -1.17) (layer "B.Fab")
        (effects (font (size 1 1) (thickness 0.15)) (justify mirror))
    )
    (fp_text user "Author: Antmicro" (at -0.939 -3.399 180) (layer "B.Fab") hide
        (effects (font (size 0.7 0.7) (thickness 0.15)) (justify left bottom mirror))
    )
    (fp_text user "License: Apache-2.0" (at -0.939 -5.799 180) (layer "B.Fab") hide
        (effects (font (size 0.7 0.7) (thickness 0.15)) (justify left bottom mirror))
    )
    (fp_text user "${REFERENCE}" (at 0 0) (layer "B.Fab")
        (effects (font (size 0.25 0.25) (thickness 0.04)) (justify mirror))
    )
    (fp_rect (start -0.925 0.47) (end 0.925 -0.47)
      (stroke (width 0.05) (type default)) (fill none) (layer "B.CrtYd"))
    (fp_line (start -0.494 -0.248) (end -0.494 0.25)
      (stroke (width 0.15) (type solid)) (layer "B.Fab"))
    (fp_line (start -0.494 0.25) (end 0.504 0.25)
      (stroke (width 0.15) (type solid)) (layer "B.Fab"))
    (fp_line (start 0.504 -0.248) (end -0.494 -0.248)
      (stroke (width 0.15) (type solid)) (layer "B.Fab"))
    (fp_line (start 0.504 0.25) (end 0.504 -0.248)
      (stroke (width 0.15) (type solid)) (layer "B.Fab"))
    (pad "1" smd roundrect (at -0.48 0) (size 0.59 0.64) (layers "B.Cu" "B.Paste" "B.Mask") (roundrect_rratio 0.25)
      (net 1 "GND") (pintype "passive"))
    (pad "2" smd roundrect (at 0.48 0) (size 0.59 0.64) (layers "B.Cu" "B.Paste" "B.Mask") (roundrect_rratio 0.25)
      (net 302 "/FPGA power supply/VCCA0") (pintype "passive"))
  )

  (footprint "antmicro-footprints:C_0402_1005Metric" (layer "B.Cu")
    (at 101.925 132.25 90)
    (descr "Capacitor SMD 0402")
    (tags "capacitor SMD 0402")
    (property "Author" "Antmicro")
    (property "Dielectric" "")
    (property "License" "Apache-2.0")
    (property "MPN" "C1005X5R1E474M050BB")
    (property "Manufacturer" "TDK")
    (property "Public" "False")
    (property "Sheetfile" "fpga-power-supply.kicad_sch")
    (property "Sheetname" "FPGA power supply")
    (property "Val" "470n")
    (property "Voltage" "")
    (property "ki_description" "SMD Multilayer Ceramic Capacitor, 0.47 µF, 25 V, 0402 [1005 Metric], ± 20%, X5R, C")
    (property "ki_keywords" "0402, SMT, CAPACITOR, PASSIVE, CERAMIC, MLCC")
    (attr smd)
    (fp_text reference "C135" (at -20.705 0.975 90) (layer "B.SilkS")
        (effects (font (size 0.7 0.7) (thickness 0.127)) (justify mirror))
    )
    (fp_text value "C_470n_0402" (at 0 -1.17 90) (layer "B.Fab")
        (effects (font (size 1 1) (thickness 0.15)) (justify mirror))
    )
    (fp_text user "${REFERENCE}" (at 0 0 90) (layer "B.Fab")
        (effects (font (size 0.25 0.25) (thickness 0.04)) (justify mirror))
    )
    (fp_text user "License: Apache-2.0" (at -0.939 -5.799 270) (layer "B.Fab") hide
        (effects (font (size 0.7 0.7) (thickness 0.15)) (justify left bottom mirror))
    )
    (fp_text user "Author: Antmicro" (at -0.939 -3.399 270) (layer "B.Fab") hide
        (effects (font (size 0.7 0.7) (thickness 0.15)) (justify left bottom mirror))
    )
    (fp_rect (start -0.925 0.47) (end 0.925 -0.47)
      (stroke (width 0.05) (type default)) (fill none) (layer "B.CrtYd"))
    (fp_line (start -0.494 -0.248) (end -0.494 0.25)
      (stroke (width 0.15) (type solid)) (layer "B.Fab"))
    (fp_line (start -0.494 0.25) (end 0.504 0.25)
      (stroke (width 0.15) (type solid)) (layer "B.Fab"))
    (fp_line (start 0.504 -0.248) (end -0.494 -0.248)
      (stroke (width 0.15) (type solid)) (layer "B.Fab"))
    (fp_line (start 0.504 0.25) (end 0.504 -0.248)
      (stroke (width 0.15) (type solid)) (layer "B.Fab"))
    (pad "1" smd roundrect (at -0.48 0 90) (size 0.59 0.64) (layers "B.Cu" "B.Paste" "B.Mask") (roundrect_rratio 0.25)
      (net 1 "GND") (pintype "passive"))
    (pad "2" smd roundrect (at 0.48 0 90) (size 0.59 0.64) (layers "B.Cu" "B.Paste" "B.Mask") (roundrect_rratio 0.25)
      (net 302 "/FPGA power supply/VCCA0") (pintype "passive"))
  )

  (footprint "antmicro-footprints:C_0402_1005Metric" (layer "B.Cu")
    (at 105.15 117.05 -90)
    (descr "Capacitor SMD 0402")
    (tags "capacitor SMD 0402")
    (property "Author" "Antmicro")
    (property "Dielectric" "")
    (property "License" "Apache-2.0")
    (property "MPN" "C1005X5R1E474M050BB")
    (property "Manufacturer" "TDK")
    (property "Public" "False")
    (property "Sheetfile" "fpga-power-supply.kicad_sch")
    (property "Sheetname" "FPGA power supply")
    (property "Val" "470n")
    (property "Voltage" "")
    (property "ki_description" "SMD Multilayer Ceramic Capacitor, 0.47 µF, 25 V, 0402 [1005 Metric], ± 20%, X5R, C")
    (property "ki_keywords" "0402, SMT, CAPACITOR, PASSIVE, CERAMIC, MLCC")
    (attr smd)
    (fp_text reference "C195" (at 22.65 0.05 -90) (layer "B.SilkS")
        (effects (font (size 0.7 0.7) (thickness 0.127)) (justify mirror))
    )
    (fp_text value "C_470n_0402" (at 0 -1.17 -90) (layer "B.Fab")
        (effects (font (size 1 1) (thickness 0.15)) (justify mirror))
    )
    (fp_text user "License: Apache-2.0" (at -0.939 -5.799 90) (layer "B.Fab") hide
        (effects (font (size 0.7 0.7) (thickness 0.15)) (justify left bottom mirror))
    )
    (fp_text user "${REFERENCE}" (at 0 0 -90) (layer "B.Fab")
        (effects (font (size 0.25 0.25) (thickness 0.04)) (justify mirror))
    )
    (fp_text user "Author: Antmicro" (at -0.939 -3.399 90) (layer "B.Fab") hide
        (effects (font (size 0.7 0.7) (thickness 0.15)) (justify left bottom mirror))
    )
    (fp_rect (start -0.925 0.47) (end 0.925 -0.47)
      (stroke (width 0.05) (type default)) (fill none) (layer "B.CrtYd"))
    (fp_line (start -0.494 -0.248) (end -0.494 0.25)
      (stroke (width 0.15) (type solid)) (layer "B.Fab"))
    (fp_line (start -0.494 0.25) (end 0.504 0.25)
      (stroke (width 0.15) (type solid)) (layer "B.Fab"))
    (fp_line (start 0.504 -0.248) (end -0.494 -0.248)
      (stroke (width 0.15) (type solid)) (layer "B.Fab"))
    (fp_line (start 0.504 0.25) (end 0.504 -0.248)
      (stroke (width 0.15) (type solid)) (layer "B.Fab"))
    (pad "1" smd roundrect (at -0.48 0 270) (size 0.59 0.64) (layers "B.Cu" "B.Paste" "B.Mask") (roundrect_rratio 0.25)
      (net 211 "VCC1V2") (pintype "passive"))
    (pad "2" smd roundrect (at 0.48 0 270) (size 0.59 0.64) (layers "B.Cu" "B.Paste" "B.Mask") (roundrect_rratio 0.25)
      (net 1 "GND") (pintype "passive"))
  )

  (footprint "antmicro-footprints:C_0402_1005Metric" (layer "B.Cu")
    (at 108.95 94.6 180)
    (descr "Capacitor SMD 0402")
    (tags "capacitor SMD 0402")
    (property "Author" "Antmicro")
    (property "Dielectric" "")
    (property "License" "Apache-2.0")
    (property "MPN" "GRM155R61A475MEAAD")
    (property "Manufacturer" "Murata")
    (property "Public" "False")
    (property "Sheetfile" "ethernet.kicad_sch")
    (property "Sheetname" "Ethernet")
    (property "Val" "4u7")
    (property "Voltage" "")
    (property "ki_description" "SMD Multilayer Ceramic Capacitor, 4.7 µF, 10 V, 0402 [1005 Metric], ± 20%, X5R, GRM Series")
    (property "ki_keywords" "0402, SMT, CAPACITOR, PASSIVE")
    (attr smd)
    (fp_text reference "C22" (at 0.1 5.17) (layer "B.SilkS")
        (effects (font (size 0.7 0.7) (thickness 0.127)) (justify mirror))
    )
    (fp_text value "C_4u7_0402" (at 0 -1.17) (layer "B.Fab")
        (effects (font (size 1 1) (thickness 0.15)) (justify mirror))
    )
    (fp_text user "License: Apache-2.0" (at -0.939 -5.799) (layer "B.Fab") hide
        (effects (font (size 0.7 0.7) (thickness 0.15)) (justify left bottom mirror))
    )
    (fp_text user "Author: Antmicro" (at -0.939 -3.399) (layer "B.Fab") hide
        (effects (font (size 0.7 0.7) (thickness 0.15)) (justify left bottom mirror))
    )
    (fp_text user "${REFERENCE}" (at 0 0) (layer "B.Fab")
        (effects (font (size 0.25 0.25) (thickness 0.04)) (justify mirror))
    )
    (fp_rect (start -0.925 0.47) (end 0.925 -0.47)
      (stroke (width 0.05) (type default)) (fill none) (layer "B.CrtYd"))
    (fp_line (start -0.494 -0.248) (end -0.494 0.25)
      (stroke (width 0.15) (type solid)) (layer "B.Fab"))
    (fp_line (start -0.494 0.25) (end 0.504 0.25)
      (stroke (width 0.15) (type solid)) (layer "B.Fab"))
    (fp_line (start 0.504 -0.248) (end -0.494 -0.248)
      (stroke (width 0.15) (type solid)) (layer "B.Fab"))
    (fp_line (start 0.504 0.25) (end 0.504 -0.248)
      (stroke (width 0.15) (type solid)) (layer "B.Fab"))
    (pad "1" smd roundrect (at -0.48 0 180) (size 0.59 0.64) (layers "B.Cu" "B.Paste" "B.Mask") (roundrect_rratio 0.25)
      (net 1 "GND") (pintype "passive"))
    (pad "2" smd roundrect (at 0.48 0 180) (size 0.59 0.64) (layers "B.Cu" "B.Paste" "B.Mask") (roundrect_rratio 0.25)
      (net 10 "/Ethernet/AVDDL_PLL") (pintype "passive"))
  )

  (footprint "antmicro-footprints:C_0402_1005Metric" (layer "B.Cu")
    (at 104.4 93.35 90)
    (descr "Capacitor SMD 0402")
    (tags "capacitor SMD 0402")
    (property "Author" "Antmicro")
    (property "Dielectric" "X7R")
    (property "License" "Apache-2.0")
    (property "MPN" "GRM155R71H103KA88D")
    (property "Manufacturer" "Murata")
    (property "Public" "False")
    (property "Sheetfile" "ethernet.kicad_sch")
    (property "Sheetname" "Ethernet")
    (property "Val" "10n")
    (property "Voltage" "50V")
    (property "ki_description" "SMD Multilayer Ceramic Capacitor, 10000 pF, 50 V, 0402 [1005 Metric], ± 10%, X7R, GRM Series")
    (property "ki_keywords" "0402, SMT, CAPACITOR, PASSIVE")
    (attr smd)
    (fp_text reference "C21" (at -0.075 -0.86 90) (layer "B.SilkS")
        (effects (font (size 0.7 0.7) (thickness 0.127)) (justify mirror))
    )
    (fp_text value "C_10n_0402" (at 0 -1.17 90) (layer "B.Fab")
        (effects (font (size 1 1) (thickness 0.15)) (justify mirror))
    )
    (fp_text user "${REFERENCE}" (at 0 0 90) (layer "B.Fab")
        (effects (font (size 0.25 0.25) (thickness 0.04)) (justify mirror))
    )
    (fp_text user "Author: Antmicro" (at -0.939 -3.399 270) (layer "B.Fab") hide
        (effects (font (size 0.7 0.7) (thickness 0.15)) (justify left bottom mirror))
    )
    (fp_text user "License: Apache-2.0" (at -0.939 -5.799 270) (layer "B.Fab") hide
        (effects (font (size 0.7 0.7) (thickness 0.15)) (justify left bottom mirror))
    )
    (fp_rect (start -0.925 0.47) (end 0.925 -0.47)
      (stroke (width 0.05) (type default)) (fill none) (layer "B.CrtYd"))
    (fp_line (start -0.494 -0.248) (end -0.494 0.25)
      (stroke (width 0.15) (type solid)) (layer "B.Fab"))
    (fp_line (start -0.494 0.25) (end 0.504 0.25)
      (stroke (width 0.15) (type solid)) (layer "B.Fab"))
    (fp_line (start 0.504 -0.248) (end -0.494 -0.248)
      (stroke (width 0.15) (type solid)) (layer "B.Fab"))
    (fp_line (start 0.504 0.25) (end 0.504 -0.248)
      (stroke (width 0.15) (type solid)) (layer "B.Fab"))
    (pad "1" smd roundrect (at -0.48 0 90) (size 0.59 0.64) (layers "B.Cu" "B.Paste" "B.Mask") (roundrect_rratio 0.25)
      (net 1 "GND") (pintype "passive"))
    (pad "2" smd roundrect (at 0.48 0 90) (size 0.59 0.64) (layers "B.Cu" "B.Paste" "B.Mask") (roundrect_rratio 0.25)
      (net 9 "/Ethernet/AVDDL") (pintype "passive"))
  )

  (footprint "antmicro-footprints:C_0402_1005Metric" (layer "B.Cu")
    (at 101.95 93.35 90)
    (descr "Capacitor SMD 0402")
    (tags "capacitor SMD 0402")
    (property "Author" "Antmicro")
    (property "Dielectric" "")
    (property "License" "Apache-2.0")
    (property "MPN" "C1005X5R1E474M050BB")
    (property "Manufacturer" "TDK")
    (property "Public" "False")
    (property "Sheetfile" "ethernet.kicad_sch")
    (property "Sheetname" "Ethernet")
    (property "Val" "470n")
    (property "Voltage" "")
    (property "ki_description" "SMD Multilayer Ceramic Capacitor, 0.47 µF, 25 V, 0402 [1005 Metric], ± 20%, X5R, C")
    (property "ki_keywords" "0402, SMT, CAPACITOR, PASSIVE, CERAMIC, MLCC")
    (attr smd)
    (fp_text reference "C19" (at -1.865 -0.02 90) (layer "B.SilkS")
        (effects (font (size 0.7 0.7) (thickness 0.127)) (justify mirror))
    )
    (fp_text value "C_470n_0402" (at 0 -1.17 90) (layer "B.Fab")
        (effects (font (size 1 1) (thickness 0.15)) (justify mirror))
    )
    (fp_text user "Author: Antmicro" (at -0.939 -3.399 270) (layer "B.Fab") hide
        (effects (font (size 0.7 0.7) (thickness 0.15)) (justify left bottom mirror))
    )
    (fp_text user "License: Apache-2.0" (at -0.939 -5.799 270) (layer "B.Fab") hide
        (effects (font (size 0.7 0.7) (thickness 0.15)) (justify left bottom mirror))
    )
    (fp_text user "${REFERENCE}" (at 0 0 90) (layer "B.Fab")
        (effects (font (size 0.25 0.25) (thickness 0.04)) (justify mirror))
    )
    (fp_rect (start -0.925 0.47) (end 0.925 -0.47)
      (stroke (width 0.05) (type default)) (fill none) (layer "B.CrtYd"))
    (fp_line (start -0.494 -0.248) (end -0.494 0.25)
      (stroke (width 0.15) (type solid)) (layer "B.Fab"))
    (fp_line (start -0.494 0.25) (end 0.504 0.25)
      (stroke (width 0.15) (type solid)) (layer "B.Fab"))
    (fp_line (start 0.504 -0.248) (end -0.494 -0.248)
      (stroke (width 0.15) (type solid)) (layer "B.Fab"))
    (fp_line (start 0.504 0.25) (end 0.504 -0.248)
      (stroke (width 0.15) (type solid)) (layer "B.Fab"))
    (pad "1" smd roundrect (at -0.48 0 90) (size 0.59 0.64) (layers "B.Cu" "B.Paste" "B.Mask") (roundrect_rratio 0.25)
      (net 1 "GND") (pintype "passive"))
    (pad "2" smd roundrect (at 0.48 0 90) (size 0.59 0.64) (layers "B.Cu" "B.Paste" "B.Mask") (roundrect_rratio 0.25)
      (net 9 "/Ethernet/AVDDL") (pintype "passive"))
  )

  (footprint "antmicro-footprints:C_0402_1005Metric" (layer "B.Cu")
    (at 101.95 90.55 -90)
    (descr "Capacitor SMD 0402")
    (tags "capacitor SMD 0402")
    (property "Author" "Antmicro")
    (property "Dielectric" "")
    (property "License" "Apache-2.0")
    (property "MPN" "GRM155R61A475MEAAD")
    (property "Manufacturer" "Murata")
    (property "Public" "False")
    (property "Sheetfile" "ethernet.kicad_sch")
    (property "Sheetname" "Ethernet")
    (property "Val" "4u7")
    (property "Voltage" "")
    (property "ki_description" "SMD Multilayer Ceramic Capacitor, 4.7 µF, 10 V, 0402 [1005 Metric], ± 20%, X5R, GRM Series")
    (property "ki_keywords" "0402, SMT, CAPACITOR, PASSIVE")
    (attr smd)
    (fp_text reference "C18" (at -1.845 0.42 90) (layer "B.SilkS")
        (effects (font (size 0.7 0.7) (thickness 0.127)) (justify mirror))
    )
    (fp_text value "C_4u7_0402" (at 0 -1.17 90) (layer "B.Fab")
        (effects (font (size 1 1) (thickness 0.15)) (justify mirror))
    )
    (fp_text user "Author: Antmicro" (at -0.939 -3.399 90) (layer "B.Fab") hide
        (effects (font (size 0.7 0.7) (thickness 0.15)) (justify left bottom mirror))
    )
    (fp_text user "${REFERENCE}" (at 0 0 90) (layer "B.Fab")
        (effects (font (size 0.25 0.25) (thickness 0.04)) (justify mirror))
    )
    (fp_text user "License: Apache-2.0" (at -0.939 -5.799 90) (layer "B.Fab") hide
        (effects (font (size 0.7 0.7) (thickness 0.15)) (justify left bottom mirror))
    )
    (fp_rect (start -0.925 0.47) (end 0.925 -0.47)
      (stroke (width 0.05) (type default)) (fill none) (layer "B.CrtYd"))
    (fp_line (start -0.494 -0.248) (end -0.494 0.25)
      (stroke (width 0.15) (type solid)) (layer "B.Fab"))
    (fp_line (start -0.494 0.25) (end 0.504 0.25)
      (stroke (width 0.15) (type solid)) (layer "B.Fab"))
    (fp_line (start 0.504 -0.248) (end -0.494 -0.248)
      (stroke (width 0.15) (type solid)) (layer "B.Fab"))
    (fp_line (start 0.504 0.25) (end 0.504 -0.248)
      (stroke (width 0.15) (type solid)) (layer "B.Fab"))
    (pad "1" smd roundrect (at -0.48 0 270) (size 0.59 0.64) (layers "B.Cu" "B.Paste" "B.Mask") (roundrect_rratio 0.25)
      (net 1 "GND") (pintype "passive"))
    (pad "2" smd roundrect (at 0.48 0 270) (size 0.59 0.64) (layers "B.Cu" "B.Paste" "B.Mask") (roundrect_rratio 0.25)
      (net 9 "/Ethernet/AVDDL") (pintype "passive"))
  )

  (footprint "antmicro-footprints:C_0402_1005Metric" (layer "B.Cu")
    (at 106.05 100.3 -90)
    (descr "Capacitor SMD 0402")
    (tags "capacitor SMD 0402")
    (property "Author" "Antmicro")
    (property "Dielectric" "X7R")
    (property "License" "Apache-2.0")
    (property "MPN" "GRM155R71H103KA88D")
    (property "Manufacturer" "Murata")
    (property "Public" "False")
    (property "Sheetfile" "ethernet.kicad_sch")
    (property "Sheetname" "Ethernet")
    (property "Val" "10n")
    (property "Voltage" "50V")
    (property "ki_description" "SMD Multilayer Ceramic Capacitor, 10000 pF, 50 V, 0402 [1005 Metric], ± 10%, X7R, GRM Series")
    (property "ki_keywords" "0402, SMT, CAPACITOR, PASSIVE")
    (attr smd)
    (fp_text reference "C17" (at 0.855 -0.85 90) (layer "B.SilkS")
        (effects (font (size 0.7 0.7) (thickness 0.127)) (justify mirror))
    )
    (fp_text value "C_10n_0402" (at 0 -1.17 90) (layer "B.Fab")
        (effects (font (size 1 1) (thickness 0.15)) (justify mirror))
    )
    (fp_text user "License: Apache-2.0" (at -0.939 -5.799 90) (layer "B.Fab") hide
        (effects (font (size 0.7 0.7) (thickness 0.15)) (justify left bottom mirror))
    )
    (fp_text user "${REFERENCE}" (at 0 0 90) (layer "B.Fab")
        (effects (font (size 0.25 0.25) (thickness 0.04)) (justify mirror))
    )
    (fp_text user "Author: Antmicro" (at -0.939 -3.399 90) (layer "B.Fab") hide
        (effects (font (size 0.7 0.7) (thickness 0.15)) (justify left bottom mirror))
    )
    (fp_rect (start -0.925 0.47) (end 0.925 -0.47)
      (stroke (width 0.05) (type default)) (fill none) (layer "B.CrtYd"))
    (fp_line (start -0.494 -0.248) (end -0.494 0.25)
      (stroke (width 0.15) (type solid)) (layer "B.Fab"))
    (fp_line (start -0.494 0.25) (end 0.504 0.25)
      (stroke (width 0.15) (type solid)) (layer "B.Fab"))
    (fp_line (start 0.504 -0.248) (end -0.494 -0.248)
      (stroke (width 0.15) (type solid)) (layer "B.Fab"))
    (fp_line (start 0.504 0.25) (end 0.504 -0.248)
      (stroke (width 0.15) (type solid)) (layer "B.Fab"))
    (pad "1" smd roundrect (at -0.48 0 270) (size 0.59 0.64) (layers "B.Cu" "B.Paste" "B.Mask") (roundrect_rratio 0.25)
      (net 1 "GND") (pintype "passive"))
    (pad "2" smd roundrect (at 0.48 0 270) (size 0.59 0.64) (layers "B.Cu" "B.Paste" "B.Mask") (roundrect_rratio 0.25)
      (net 2 "VCC3V3") (pintype "passive"))
  )

  (footprint "antmicro-footprints:C_0402_1005Metric" (layer "B.Cu")
    (at 105.95 93.35 90)
    (descr "Capacitor SMD 0402")
    (tags "capacitor SMD 0402")
    (property "Author" "Antmicro")
    (property "Dielectric" "X7R")
    (property "License" "Apache-2.0")
    (property "MPN" "GRM155R71H103KA88D")
    (property "Manufacturer" "Murata")
    (property "Public" "False")
    (property "Sheetfile" "ethernet.kicad_sch")
    (property "Sheetname" "Ethernet")
    (property "Val" "10n")
    (property "Voltage" "50V")
    (property "ki_description" "SMD Multilayer Ceramic Capacitor, 10000 pF, 50 V, 0402 [1005 Metric], ± 10%, X7R, GRM Series")
    (property "ki_keywords" "0402, SMT, CAPACITOR, PASSIVE")
    (attr smd)
    (fp_text reference "C16" (at 0.005 0.87 90) (layer "B.SilkS")
        (effects (font (size 0.7 0.7) (thickness 0.127)) (justify mirror))
    )
    (fp_text value "C_10n_0402" (at 0 -1.17 90) (layer "B.Fab")
        (effects (font (size 1 1) (thickness 0.15)) (justify mirror))
    )
    (fp_text user "License: Apache-2.0" (at -0.939 -5.799 270) (layer "B.Fab") hide
        (effects (font (size 0.7 0.7) (thickness 0.15)) (justify left bottom mirror))
    )
    (fp_text user "Author: Antmicro" (at -0.939 -3.399 270) (layer "B.Fab") hide
        (effects (font (size 0.7 0.7) (thickness 0.15)) (justify left bottom mirror))
    )
    (fp_text user "${REFERENCE}" (at 0 0 90) (layer "B.Fab")
        (effects (font (size 0.25 0.25) (thickness 0.04)) (justify mirror))
    )
    (fp_rect (start -0.925 0.47) (end 0.925 -0.47)
      (stroke (width 0.05) (type default)) (fill none) (layer "B.CrtYd"))
    (fp_line (start -0.494 -0.248) (end -0.494 0.25)
      (stroke (width 0.15) (type solid)) (layer "B.Fab"))
    (fp_line (start -0.494 0.25) (end 0.504 0.25)
      (stroke (width 0.15) (type solid)) (layer "B.Fab"))
    (fp_line (start 0.504 -0.248) (end -0.494 -0.248)
      (stroke (width 0.15) (type solid)) (layer "B.Fab"))
    (fp_line (start 0.504 0.25) (end 0.504 -0.248)
      (stroke (width 0.15) (type solid)) (layer "B.Fab"))
    (pad "1" smd roundrect (at -0.48 0 90) (size 0.59 0.64) (layers "B.Cu" "B.Paste" "B.Mask") (roundrect_rratio 0.25)
      (net 1 "GND") (pintype "passive"))
    (pad "2" smd roundrect (at 0.48 0 90) (size 0.59 0.64) (layers "B.Cu" "B.Paste" "B.Mask") (roundrect_rratio 0.25)
      (net 4 "/Ethernet/AVDDH") (pintype "passive"))
  )

  (footprint "antmicro-footprints:C_0402_1005Metric" (layer "B.Cu")
    (at 103.02 99.55 -90)
    (descr "Capacitor SMD 0402")
    (tags "capacitor SMD 0402")
    (property "Author" "Antmicro")
    (property "Dielectric" "X7R")
    (property "License" "Apache-2.0")
    (property "MPN" "GRM155R71H103KA88D")
    (property "Manufacturer" "Murata")
    (property "Public" "False")
    (property "Sheetfile" "ethernet.kicad_sch")
    (property "Sheetname" "Ethernet")
    (property "Val" "10n")
    (property "Voltage" "50V")
    (property "ki_description" "SMD Multilayer Ceramic Capacitor, 10000 pF, 50 V, 0402 [1005 Metric], ± 10%, X7R, GRM Series")
    (property "ki_keywords" "0402, SMT, CAPACITOR, PASSIVE")
    (attr smd)
    (fp_text reference "C15" (at -1.905 -0.01 90) (layer "B.SilkS")
        (effects (font (size 0.7 0.7) (thickness 0.127)) (justify mirror))
    )
    (fp_text value "C_10n_0402" (at 0 -1.17 90) (layer "B.Fab")
        (effects (font (size 1 1) (thickness 0.15)) (justify mirror))
    )
    (fp_text user "Author: Antmicro" (at -0.939 -3.399 90) (layer "B.Fab") hide
        (effects (font (size 0.7 0.7) (thickness 0.15)) (justify left bottom mirror))
    )
    (fp_text user "${REFERENCE}" (at 0 0 90) (layer "B.Fab")
        (effects (font (size 0.25 0.25) (thickness 0.04)) (justify mirror))
    )
    (fp_text user "License: Apache-2.0" (at -0.939 -5.799 90) (layer "B.Fab") hide
        (effects (font (size 0.7 0.7) (thickness 0.15)) (justify left bottom mirror))
    )
    (fp_rect (start -0.925 0.47) (end 0.925 -0.47)
      (stroke (width 0.05) (type default)) (fill none) (layer "B.CrtYd"))
    (fp_line (start -0.494 -0.248) (end -0.494 0.25)
      (stroke (width 0.15) (type solid)) (layer "B.Fab"))
    (fp_line (start -0.494 0.25) (end 0.504 0.25)
      (stroke (width 0.15) (type solid)) (layer "B.Fab"))
    (fp_line (start 0.504 -0.248) (end -0.494 -0.248)
      (stroke (width 0.15) (type solid)) (layer "B.Fab"))
    (fp_line (start 0.504 0.25) (end 0.504 -0.248)
      (stroke (width 0.15) (type solid)) (layer "B.Fab"))
    (pad "1" smd roundrect (at -0.48 0 270) (size 0.59 0.64) (layers "B.Cu" "B.Paste" "B.Mask") (roundrect_rratio 0.25)
      (net 1 "GND") (pintype "passive"))
    (pad "2" smd roundrect (at 0.48 0 270) (size 0.59 0.64) (layers "B.Cu" "B.Paste" "B.Mask") (roundrect_rratio 0.25)
      (net 211 "VCC1V2") (pintype "passive"))
  )

  (footprint "antmicro-footprints:C_0402_1005Metric" (layer "B.Cu")
    (at 108.95 97.75 180)
    (descr "Capacitor SMD 0402")
    (tags "capacitor SMD 0402")
    (property "Author" "Antmicro")
    (property "Dielectric" "X7R")
    (property "License" "Apache-2.0")
    (property "MPN" "GRM155R71H103KA88D")
    (property "Manufacturer" "Murata")
    (property "Public" "False")
    (property "Sheetfile" "ethernet.kicad_sch")
    (property "Sheetname" "Ethernet")
    (property "Val" "10n")
    (property "Voltage" "50V")
    (property "ki_description" "SMD Multilayer Ceramic Capacitor, 10000 pF, 50 V, 0402 [1005 Metric], ± 10%, X7R, GRM Series")
    (property "ki_keywords" "0402, SMT, CAPACITOR, PASSIVE")
    (attr smd)
    (fp_text reference "C14" (at -2.54 -0.005) (layer "B.SilkS")
        (effects (font (size 0.7 0.7) (thickness 0.127)) (justify mirror))
    )
    (fp_text value "C_10n_0402" (at 0 -1.17) (layer "B.Fab")
        (effects (font (size 1 1) (thickness 0.15)) (justify mirror))
    )
    (fp_text user "Author: Antmicro" (at -0.939 -3.399) (layer "B.Fab") hide
        (effects (font (size 0.7 0.7) (thickness 0.15)) (justify left bottom mirror))
    )
    (fp_text user "License: Apache-2.0" (at -0.939 -5.799) (layer "B.Fab") hide
        (effects (font (size 0.7 0.7) (thickness 0.15)) (justify left bottom mirror))
    )
    (fp_text user "${REFERENCE}" (at 0 0) (layer "B.Fab")
        (effects (font (size 0.25 0.25) (thickness 0.04)) (justify mirror))
    )
    (fp_rect (start -0.925 0.47) (end 0.925 -0.47)
      (stroke (width 0.05) (type default)) (fill none) (layer "B.CrtYd"))
    (fp_line (start -0.494 -0.248) (end -0.494 0.25)
      (stroke (width 0.15) (type solid)) (layer "B.Fab"))
    (fp_line (start -0.494 0.25) (end 0.504 0.25)
      (stroke (width 0.15) (type solid)) (layer "B.Fab"))
    (fp_line (start 0.504 -0.248) (end -0.494 -0.248)
      (stroke (width 0.15) (type solid)) (layer "B.Fab"))
    (fp_line (start 0.504 0.25) (end 0.504 -0.248)
      (stroke (width 0.15) (type solid)) (layer "B.Fab"))
    (pad "1" smd roundrect (at -0.48 0 180) (size 0.59 0.64) (layers "B.Cu" "B.Paste" "B.Mask") (roundrect_rratio 0.25)
      (net 1 "GND") (pintype "passive"))
    (pad "2" smd roundrect (at 0.48 0 180) (size 0.59 0.64) (layers "B.Cu" "B.Paste" "B.Mask") (roundrect_rratio 0.25)
      (net 2 "VCC3V3") (pintype "passive"))
  )

  (footprint "antmicro-footprints:C_0402_1005Metric" (layer "B.Cu")
    (at 105.95 90.55 -90)
    (descr "Capacitor SMD 0402")
    (tags "capacitor SMD 0402")
    (property "Author" "Antmicro")
    (property "Dielectric" "X7R")
    (property "License" "Apache-2.0")
    (property "MPN" "GRM155R71H103KA88D")
    (property "Manufacturer" "Murata")
    (property "Public" "False")
    (property "Sheetfile" "ethernet.kicad_sch")
    (property "Sheetname" "Ethernet")
    (property "Val" "10n")
    (property "Voltage" "50V")
    (property "ki_description" "SMD Multilayer Ceramic Capacitor, 10000 pF, 50 V, 0402 [1005 Metric], ± 10%, X7R, GRM Series")
    (property "ki_keywords" "0402, SMT, CAPACITOR, PASSIVE")
    (attr smd)
    (fp_text reference "C13" (at -0.005 -0.95 90) (layer "B.SilkS")
        (effects (font (size 0.7 0.7) (thickness 0.127)) (justify mirror))
    )
    (fp_text value "C_10n_0402" (at 0 -1.17 90) (layer "B.Fab")
        (effects (font (size 1 1) (thickness 0.15)) (justify mirror))
    )
    (fp_text user "Author: Antmicro" (at -0.939 -3.399 90) (layer "B.Fab") hide
        (effects (font (size 0.7 0.7) (thickness 0.15)) (justify left bottom mirror))
    )
    (fp_text user "License: Apache-2.0" (at -0.939 -5.799 90) (layer "B.Fab") hide
        (effects (font (size 0.7 0.7) (thickness 0.15)) (justify left bottom mirror))
    )
    (fp_text user "${REFERENCE}" (at 0 0 90) (layer "B.Fab")
        (effects (font (size 0.25 0.25) (thickness 0.04)) (justify mirror))
    )
    (fp_rect (start -0.925 0.47) (end 0.925 -0.47)
      (stroke (width 0.05) (type default)) (fill none) (layer "B.CrtYd"))
    (fp_line (start -0.494 -0.248) (end -0.494 0.25)
      (stroke (width 0.15) (type solid)) (layer "B.Fab"))
    (fp_line (start -0.494 0.25) (end 0.504 0.25)
      (stroke (width 0.15) (type solid)) (layer "B.Fab"))
    (fp_line (start 0.504 -0.248) (end -0.494 -0.248)
      (stroke (width 0.15) (type solid)) (layer "B.Fab"))
    (fp_line (start 0.504 0.25) (end 0.504 -0.248)
      (stroke (width 0.15) (type solid)) (layer "B.Fab"))
    (pad "1" smd roundrect (at -0.48 0 270) (size 0.59 0.64) (layers "B.Cu" "B.Paste" "B.Mask") (roundrect_rratio 0.25)
      (net 1 "GND") (pintype "passive"))
    (pad "2" smd roundrect (at 0.48 0 270) (size 0.59 0.64) (layers "B.Cu" "B.Paste" "B.Mask") (roundrect_rratio 0.25)
      (net 4 "/Ethernet/AVDDH") (pintype "passive"))
  )

  (footprint "antmicro-footprints:C_0402_1005Metric" (layer "B.Cu")
    (at 100.1 94.15 180)
    (descr "Capacitor SMD 0402")
    (tags "capacitor SMD 0402")
    (property "Author" "Antmicro")
    (property "Dielectric" "X7R")
    (property "License" "Apache-2.0")
    (property "MPN" "GRM155R71H103KA88D")
    (property "Manufacturer" "Murata")
    (property "Public" "False")
    (property "Sheetfile" "ethernet.kicad_sch")
    (property "Sheetname" "Ethernet")
    (property "Val" "10n")
    (property "Voltage" "50V")
    (property "ki_description" "SMD Multilayer Ceramic Capacitor, 10000 pF, 50 V, 0402 [1005 Metric], ± 10%, X7R, GRM Series")
    (property "ki_keywords" "0402, SMT, CAPACITOR, PASSIVE")
    (attr smd)
    (fp_text reference "C12" (at -0.04 0.945) (layer "B.SilkS")
        (effects (font (size 0.7 0.7) (thickness 0.127)) (justify mirror))
    )
    (fp_text value "C_10n_0402" (at 0 -1.17) (layer "B.Fab")
        (effects (font (size 1 1) (thickness 0.15)) (justify mirror))
    )
    (fp_text user "Author: Antmicro" (at -0.939 -3.399) (layer "B.Fab") hide
        (effects (font (size 0.7 0.7) (thickness 0.15)) (justify left bottom mirror))
    )
    (fp_text user "License: Apache-2.0" (at -0.939 -5.799) (layer "B.Fab") hide
        (effects (font (size 0.7 0.7) (thickness 0.15)) (justify left bottom mirror))
    )
    (fp_text user "${REFERENCE}" (at 0 0) (layer "B.Fab")
        (effects (font (size 0.25 0.25) (thickness 0.04)) (justify mirror))
    )
    (fp_rect (start -0.925 0.47) (end 0.925 -0.47)
      (stroke (width 0.05) (type default)) (fill none) (layer "B.CrtYd"))
    (fp_line (start -0.494 -0.248) (end -0.494 0.25)
      (stroke (width 0.15) (type solid)) (layer "B.Fab"))
    (fp_line (start -0.494 0.25) (end 0.504 0.25)
      (stroke (width 0.15) (type solid)) (layer "B.Fab"))
    (fp_line (start 0.504 -0.248) (end -0.494 -0.248)
      (stroke (width 0.15) (type solid)) (layer "B.Fab"))
    (fp_line (start 0.504 0.25) (end 0.504 -0.248)
      (stroke (width 0.15) (type solid)) (layer "B.Fab"))
    (pad "1" smd roundrect (at -0.48 0 180) (size 0.59 0.64) (layers "B.Cu" "B.Paste" "B.Mask") (roundrect_rratio 0.25)
      (net 1 "GND") (pintype "passive"))
    (pad "2" smd roundrect (at 0.48 0 180) (size 0.59 0.64) (layers "B.Cu" "B.Paste" "B.Mask") (roundrect_rratio 0.25)
      (net 211 "VCC1V2") (pintype "passive"))
  )

  (footprint "antmicro-footprints:C_0402_1005Metric" (layer "B.Cu")
    (at 100.45 90.55 -90)
    (descr "Capacitor SMD 0402")
    (tags "capacitor SMD 0402")
    (property "Author" "Antmicro")
    (property "Dielectric" "")
    (property "License" "Apache-2.0")
    (property "MPN" "GRM155R61A475MEAAD")
    (property "Manufacturer" "Murata")
    (property "Public" "False")
    (property "Sheetfile" "ethernet.kicad_sch")
    (property "Sheetname" "Ethernet")
    (property "Val" "4u7")
    (property "Voltage" "")
    (property "ki_description" "SMD Multilayer Ceramic Capacitor, 4.7 µF, 10 V, 0402 [1005 Metric], ± 20%, X5R, GRM Series")
    (property "ki_keywords" "0402, SMT, CAPACITOR, PASSIVE")
    (attr smd)
    (fp_text reference "C10" (at -0.045 0.94 90) (layer "B.SilkS")
        (effects (font (size 0.7 0.7) (thickness 0.127)) (justify mirror))
    )
    (fp_text value "C_4u7_0402" (at 0 -1.17 90) (layer "B.Fab")
        (effects (font (size 1 1) (thickness 0.15)) (justify mirror))
    )
    (fp_text user "Author: Antmicro" (at -0.939 -3.399 90) (layer "B.Fab") hide
        (effects (font (size 0.7 0.7) (thickness 0.15)) (justify left bottom mirror))
    )
    (fp_text user "${REFERENCE}" (at 0 0 90) (layer "B.Fab")
        (effects (font (size 0.25 0.25) (thickness 0.04)) (justify mirror))
    )
    (fp_text user "License: Apache-2.0" (at -0.939 -5.799 90) (layer "B.Fab") hide
        (effects (font (size 0.7 0.7) (thickness 0.15)) (justify left bottom mirror))
    )
    (fp_rect (start -0.925 0.47) (end 0.925 -0.47)
      (stroke (width 0.05) (type default)) (fill none) (layer "B.CrtYd"))
    (fp_line (start -0.494 -0.248) (end -0.494 0.25)
      (stroke (width 0.15) (type solid)) (layer "B.Fab"))
    (fp_line (start -0.494 0.25) (end 0.504 0.25)
      (stroke (width 0.15) (type solid)) (layer "B.Fab"))
    (fp_line (start 0.504 -0.248) (end -0.494 -0.248)
      (stroke (width 0.15) (type solid)) (layer "B.Fab"))
    (fp_line (start 0.504 0.25) (end 0.504 -0.248)
      (stroke (width 0.15) (type solid)) (layer "B.Fab"))
    (pad "1" smd roundrect (at -0.48 0 270) (size 0.59 0.64) (layers "B.Cu" "B.Paste" "B.Mask") (roundrect_rratio 0.25)
      (net 1 "GND") (pintype "passive"))
    (pad "2" smd roundrect (at 0.48 0 270) (size 0.59 0.64) (layers "B.Cu" "B.Paste" "B.Mask") (roundrect_rratio 0.25)
      (net 4 "/Ethernet/AVDDH") (pintype "passive"))
  )

  (footprint "antmicro-footprints:C_0402_1005Metric" (layer "B.Cu")
    (at 106.3 97.7)
    (descr "Capacitor SMD 0402")
    (tags "capacitor SMD 0402")
    (property "Author" "Antmicro")
    (property "Dielectric" "")
    (property "License" "Apache-2.0")
    (property "MPN" "C1005X5R1E474M050BB")
    (property "Manufacturer" "TDK")
    (property "Public" "False")
    (property "Sheetfile" "ethernet.kicad_sch")
    (property "Sheetname" "Ethernet")
    (property "Val" "470n")
    (property "Voltage" "")
    (property "ki_description" "SMD Multilayer Ceramic Capacitor, 0.47 µF, 25 V, 0402 [1005 Metric], ± 20%, X5R, C")
    (property "ki_keywords" "0402, SMT, CAPACITOR, PASSIVE, CERAMIC, MLCC")
    (attr smd)
    (fp_text reference "C8" (at 0.19 -0.835) (layer "B.SilkS")
        (effects (font (size 0.7 0.7) (thickness 0.127)) (justify mirror))
    )
    (fp_text value "C_470n_0402" (at 0 -1.17) (layer "B.Fab")
        (effects (font (size 1 1) (thickness 0.15)) (justify mirror))
    )
    (fp_text user "${REFERENCE}" (at 0 0) (layer "B.Fab")
        (effects (font (size 0.25 0.25) (thickness 0.04)) (justify mirror))
    )
    (fp_text user "Author: Antmicro" (at -0.939 -3.399 180) (layer "B.Fab") hide
        (effects (font (size 0.7 0.7) (thickness 0.15)) (justify left bottom mirror))
    )
    (fp_text user "License: Apache-2.0" (at -0.939 -5.799 180) (layer "B.Fab") hide
        (effects (font (size 0.7 0.7) (thickness 0.15)) (justify left bottom mirror))
    )
    (fp_rect (start -0.925 0.47) (end 0.925 -0.47)
      (stroke (width 0.05) (type default)) (fill none) (layer "B.CrtYd"))
    (fp_line (start -0.494 -0.248) (end -0.494 0.25)
      (stroke (width 0.15) (type solid)) (layer "B.Fab"))
    (fp_line (start -0.494 0.25) (end 0.504 0.25)
      (stroke (width 0.15) (type solid)) (layer "B.Fab"))
    (fp_line (start 0.504 -0.248) (end -0.494 -0.248)
      (stroke (width 0.15) (type solid)) (layer "B.Fab"))
    (fp_line (start 0.504 0.25) (end 0.504 -0.248)
      (stroke (width 0.15) (type solid)) (layer "B.Fab"))
    (pad "1" smd roundrect (at -0.48 0) (size 0.59 0.64) (layers "B.Cu" "B.Paste" "B.Mask") (roundrect_rratio 0.25)
      (net 1 "GND") (pintype "passive"))
    (pad "2" smd roundrect (at 0.48 0) (size 0.59 0.64) (layers "B.Cu" "B.Paste" "B.Mask") (roundrect_rratio 0.25)
      (net 2 "VCC3V3") (pintype "passive"))
  )

  (footprint "antmicro-footprints:C_0402_1005Metric" (layer "B.Cu")
    (at 101 99.55 -90)
    (descr "Capacitor SMD 0402")
    (tags "capacitor SMD 0402")
    (property "Author" "Antmicro")
    (property "Dielectric" "X7R")
    (property "License" "Apache-2.0")
    (property "MPN" "GRM155R71H103KA88D")
    (property "Manufacturer" "Murata")
    (property "Public" "False")
    (property "Sheetfile" "ethernet.kicad_sch")
    (property "Sheetname" "Ethernet")
    (property "Val" "10n")
    (property "Voltage" "50V")
    (property "ki_description" "SMD Multilayer Ceramic Capacitor, 10000 pF, 50 V, 0402 [1005 Metric], ± 10%, X7R, GRM Series")
    (property "ki_keywords" "0402, SMT, CAPACITOR, PASSIVE")
    (attr smd)
    (fp_text reference "C7" (at 0.345 0.82 90) (layer "B.SilkS")
        (effects (font (size 0.7 0.7) (thickness 0.127)) (justify mirror))
    )
    (fp_text value "C_10n_0402" (at 0 -1.17 90) (layer "B.Fab")
        (effects (font (size 1 1) (thickness 0.15)) (justify mirror))
    )
    (fp_text user "Author: Antmicro" (at -0.939 -3.399 90) (layer "B.Fab") hide
        (effects (font (size 0.7 0.7) (thickness 0.15)) (justify left bottom mirror))
    )
    (fp_text user "License: Apache-2.0" (at -0.939 -5.799 90) (layer "B.Fab") hide
        (effects (font (size 0.7 0.7) (thickness 0.15)) (justify left bottom mirror))
    )
    (fp_text user "${REFERENCE}" (at 0 0) (layer "B.Fab")
        (effects (font (size 0.25 0.25) (thickness 0.04)) (justify mirror))
    )
    (fp_rect (start -0.925 0.47) (end 0.925 -0.47)
      (stroke (width 0.05) (type default)) (fill none) (layer "B.CrtYd"))
    (fp_line (start -0.494 -0.248) (end -0.494 0.25)
      (stroke (width 0.15) (type solid)) (layer "B.Fab"))
    (fp_line (start -0.494 0.25) (end 0.504 0.25)
      (stroke (width 0.15) (type solid)) (layer "B.Fab"))
    (fp_line (start 0.504 -0.248) (end -0.494 -0.248)
      (stroke (width 0.15) (type solid)) (layer "B.Fab"))
    (fp_line (start 0.504 0.25) (end 0.504 -0.248)
      (stroke (width 0.15) (type solid)) (layer "B.Fab"))
    (pad "1" smd roundrect (at -0.48 0 270) (size 0.59 0.64) (layers "B.Cu" "B.Paste" "B.Mask") (roundrect_rratio 0.25)
      (net 1 "GND") (pintype "passive"))
    (pad "2" smd roundrect (at 0.48 0 270) (size 0.59 0.64) (layers "B.Cu" "B.Paste" "B.Mask") (roundrect_rratio 0.25)
      (net 211 "VCC1V2") (pintype "passive"))
  )

  (footprint "antmicro-footprints:C_0402_1005Metric" (layer "B.Cu")
    (at 105.04 99.55 -90)
    (descr "Capacitor SMD 0402")
    (tags "capacitor SMD 0402")
    (property "Author" "Antmicro")
    (property "Dielectric" "")
    (property "License" "Apache-2.0")
    (property "MPN" "GRM155R61A475MEAAD")
    (property "Manufacturer" "Murata")
    (property "Public" "False")
    (property "Sheetfile" "ethernet.kicad_sch")
    (property "Sheetname" "Ethernet")
    (property "Val" "4u7")
    (property "Voltage" "")
    (property "ki_description" "SMD Multilayer Ceramic Capacitor, 4.7 µF, 10 V, 0402 [1005 Metric], ± 20%, X5R, GRM Series")
    (property "ki_keywords" "0402, SMT, CAPACITOR, PASSIVE")
    (attr smd)
    (fp_text reference "C6" (at -1.555 0.03 90) (layer "B.SilkS")
        (effects (font (size 0.7 0.7) (thickness 0.127)) (justify mirror))
    )
    (fp_text value "C_4u7_0402" (at 0 -1.17 90) (layer "B.Fab")
        (effects (font (size 1 1) (thickness 0.15)) (justify mirror))
    )
    (fp_text user "Author: Antmicro" (at -0.939 -3.399 90) (layer "B.Fab") hide
        (effects (font (size 0.7 0.7) (thickness 0.15)) (justify left bottom mirror))
    )
    (fp_text user "${REFERENCE}" (at 0 0 90) (layer "B.Fab")
        (effects (font (size 0.25 0.25) (thickness 0.04)) (justify mirror))
    )
    (fp_text user "License: Apache-2.0" (at -0.939 -5.799 90) (layer "B.Fab") hide
        (effects (font (size 0.7 0.7) (thickness 0.15)) (justify left bottom mirror))
    )
    (fp_rect (start -0.925 0.47) (end 0.925 -0.47)
      (stroke (width 0.05) (type default)) (fill none) (layer "B.CrtYd"))
    (fp_line (start -0.494 -0.248) (end -0.494 0.25)
      (stroke (width 0.15) (type solid)) (layer "B.Fab"))
    (fp_line (start -0.494 0.25) (end 0.504 0.25)
      (stroke (width 0.15) (type solid)) (layer "B.Fab"))
    (fp_line (start 0.504 -0.248) (end -0.494 -0.248)
      (stroke (width 0.15) (type solid)) (layer "B.Fab"))
    (fp_line (start 0.504 0.25) (end 0.504 -0.248)
      (stroke (width 0.15) (type solid)) (layer "B.Fab"))
    (pad "1" smd roundrect (at -0.48 0 270) (size 0.59 0.64) (layers "B.Cu" "B.Paste" "B.Mask") (roundrect_rratio 0.25)
      (net 1 "GND") (pintype "passive"))
    (pad "2" smd roundrect (at 0.48 0 270) (size 0.59 0.64) (layers "B.Cu" "B.Paste" "B.Mask") (roundrect_rratio 0.25)
      (net 2 "VCC3V3") (pintype "passive"))
  )

  (footprint "antmicro-footprints:C_0402_1005Metric" (layer "B.Cu")
    (at 104.03 100.3 -90)
    (descr "Capacitor SMD 0402")
    (tags "capacitor SMD 0402")
    (property "Author" "Antmicro")
    (property "Dielectric" "")
    (property "License" "Apache-2.0")
    (property "MPN" "C1005X5R1E474M050BB")
    (property "Manufacturer" "TDK")
    (property "Public" "False")
    (property "Sheetfile" "ethernet.kicad_sch")
    (property "Sheetname" "Ethernet")
    (property "Val" "470n")
    (property "Voltage" "")
    (property "ki_description" "SMD Multilayer Ceramic Capacitor, 0.47 µF, 25 V, 0402 [1005 Metric], ± 20%, X5R, C")
    (property "ki_keywords" "0402, SMT, CAPACITOR, PASSIVE, CERAMIC, MLCC")
    (attr smd)
    (fp_text reference "C3" (at 1.575 -0.05 90) (layer "B.SilkS")
        (effects (font (size 0.7 0.7) (thickness 0.127)) (justify mirror))
    )
    (fp_text value "C_470n_0402" (at 0 -1.17 90) (layer "B.Fab")
        (effects (font (size 1 1) (thickness 0.15)) (justify mirror))
    )
    (fp_text user "License: Apache-2.0" (at -0.939 -5.799 90) (layer "B.Fab") hide
        (effects (font (size 0.7 0.7) (thickness 0.15)) (justify left bottom mirror))
    )
    (fp_text user "${REFERENCE}" (at 0 0 90) (layer "B.Fab")
        (effects (font (size 0.25 0.25) (thickness 0.04)) (justify mirror))
    )
    (fp_text user "Author: Antmicro" (at -0.939 -3.399 90) (layer "B.Fab") hide
        (effects (font (size 0.7 0.7) (thickness 0.15)) (justify left bottom mirror))
    )
    (fp_rect (start -0.925 0.47) (end 0.925 -0.47)
      (stroke (width 0.05) (type default)) (fill none) (layer "B.CrtYd"))
    (fp_line (start -0.494 -0.248) (end -0.494 0.25)
      (stroke (width 0.15) (type solid)) (layer "B.Fab"))
    (fp_line (start -0.494 0.25) (end 0.504 0.25)
      (stroke (width 0.15) (type solid)) (layer "B.Fab"))
    (fp_line (start 0.504 -0.248) (end -0.494 -0.248)
      (stroke (width 0.15) (type solid)) (layer "B.Fab"))
    (fp_line (start 0.504 0.25) (end 0.504 -0.248)
      (stroke (width 0.15) (type solid)) (layer "B.Fab"))
    (pad "1" smd roundrect (at -0.48 0 270) (size 0.59 0.64) (layers "B.Cu" "B.Paste" "B.Mask") (roundrect_rratio 0.25)
      (net 1 "GND") (pintype "passive"))
    (pad "2" smd roundrect (at 0.48 0 270) (size 0.59 0.64) (layers "B.Cu" "B.Paste" "B.Mask") (roundrect_rratio 0.25)
      (net 211 "VCC1V2") (pintype "passive"))
  )

  (footprint "antmicro-footprints:C_0402_1005Metric" (layer "B.Cu")
    (at 108.95 98.8 180)
    (descr "Capacitor SMD 0402")
    (tags "capacitor SMD 0402")
    (property "Author" "Antmicro")
    (property "Dielectric" "")
    (property "License" "Apache-2.0")
    (property "MPN" "C1005X5R1E474M050BB")
    (property "Manufacturer" "TDK")
    (property "Public" "False")
    (property "Sheetfile" "ethernet.kicad_sch")
    (property "Sheetname" "Ethernet")
    (property "Val" "470n")
    (property "Voltage" "")
    (property "ki_description" "SMD Multilayer Ceramic Capacitor, 0.47 µF, 25 V, 0402 [1005 Metric], ± 20%, X5R, C")
    (property "ki_keywords" "0402, SMT, CAPACITOR, PASSIVE, CERAMIC, MLCC")
    (attr smd)
    (fp_text reference "C2" (at -0.06 -0.955) (layer "B.SilkS")
        (effects (font (size 0.7 0.7) (thickness 0.127)) (justify mirror))
    )
    (fp_text value "C_470n_0402" (at 0 -1.17) (layer "B.Fab")
        (effects (font (size 1 1) (thickness 0.15)) (justify mirror))
    )
    (fp_text user "License: Apache-2.0" (at -0.939 -5.799) (layer "B.Fab") hide
        (effects (font (size 0.7 0.7) (thickness 0.15)) (justify left bottom mirror))
    )
    (fp_text user "Author: Antmicro" (at -0.939 -3.399) (layer "B.Fab") hide
        (effects (font (size 0.7 0.7) (thickness 0.15)) (justify left bottom mirror))
    )
    (fp_text user "${REFERENCE}" (at 0 0) (layer "B.Fab")
        (effects (font (size 0.25 0.25) (thickness 0.04)) (justify mirror))
    )
    (fp_rect (start -0.925 0.47) (end 0.925 -0.47)
      (stroke (width 0.05) (type default)) (fill none) (layer "B.CrtYd"))
    (fp_line (start -0.494 -0.248) (end -0.494 0.25)
      (stroke (width 0.15) (type solid)) (layer "B.Fab"))
    (fp_line (start -0.494 0.25) (end 0.504 0.25)
      (stroke (width 0.15) (type solid)) (layer "B.Fab"))
    (fp_line (start 0.504 -0.248) (end -0.494 -0.248)
      (stroke (width 0.15) (type solid)) (layer "B.Fab"))
    (fp_line (start 0.504 0.25) (end 0.504 -0.248)
      (stroke (width 0.15) (type solid)) (layer "B.Fab"))
    (pad "1" smd roundrect (at -0.48 0 180) (size 0.59 0.64) (layers "B.Cu" "B.Paste" "B.Mask") (roundrect_rratio 0.25)
      (net 1 "GND") (pintype "passive"))
    (pad "2" smd roundrect (at 0.48 0 180) (size 0.59 0.64) (layers "B.Cu" "B.Paste" "B.Mask") (roundrect_rratio 0.25)
      (net 211 "VCC1V2") (pintype "passive"))
  )

  (footprint "antmicro-footprints:FB_0603_1608Metric" (layer "B.Cu")
    (at 103.2 90.25 90)
    (property "Author" "Antmicro")
    (property "Current" "")
    (property "License" "Apache-2.0")
    (property "MPN" "BLM18PG121SN1D")
    (property "Manufacturer" "Murata")
    (property "Public" "False")
    (property "Sheetfile" "ethernet.kicad_sch")
    (property "Sheetname" "Ethernet")
    (property "Val" "120Z/2A")
    (property "ki_description" "Ferrite Bead, 0603 [1608 Metric], 120 ohm, 2 A, BLM18P, 0.05 ohm, ± 25%, DC power line")
    (property "ki_keywords" "0603, SMT, FERRITE BEAD, PASSIVE")
    (attr smd)
    (fp_text reference "FB2" (at 2.3 -0.1 -90) (layer "B.SilkS")
        (effects (font (size 0.7 0.7) (thickness 0.127)) (justify mirror))
    )
    (fp_text value "FB_120Z_2A_Murata-BLM18PG_0603" (at 0 -1.9 -90) (layer "B.Fab")
        (effects (font (size 1 1) (thickness 0.15)) (justify mirror))
    )
    (fp_text user "License: Apache-2.0" (at -1.653 -5.9 270) (layer "B.Fab") hide
        (effects (font (size 0.7 0.7) (thickness 0.15)) (justify left bottom mirror))
    )
    (fp_text user "${REFERENCE}" (at -1.653 -4.6 270) (layer "B.Fab") hide
        (effects (font (size 0.7 0.7) (thickness 0.15)) (justify left bottom mirror))
    )
    (fp_text user "Author: Antmicro" (at -1.653 -3.162 270) (layer "B.Fab") hide
        (effects (font (size 0.7 0.7) (thickness 0.15)) (justify left bottom mirror))
    )
    (fp_line (start -0.15 -0.4) (end 0.15 -0.4)
      (stroke (width 0.15) (type solid)) (layer "B.SilkS"))
    (fp_line (start -0.15 0.4) (end 0.15 0.4)
      (stroke (width 0.15) (type solid)) (layer "B.SilkS"))
    (fp_rect (start -1.25 0.65) (end 1.25 -0.65)
      (stroke (width 0.05) (type solid)) (fill none) (layer "B.CrtYd"))
    (fp_line (start -0.803 -0.406) (end -0.803 0.408)
      (stroke (width 0.15) (type solid)) (layer "B.Fab"))
    (fp_line (start 0.8 -0.406) (end -0.803 -0.406)
      (stroke (width 0.15) (type solid)) (layer "B.Fab"))
    (fp_line (start 0.8 0.408) (end -0.803 0.408)
      (stroke (width 0.15) (type solid)) (layer "B.Fab"))
    (fp_line (start 0.8 0.408) (end 0.8 -0.406)
      (stroke (width 0.15) (type solid)) (layer "B.Fab"))
    (pad "1" smd roundrect (at -0.7 0 90) (size 0.8 1) (layers "B.Cu" "B.Paste" "B.Mask") (roundrect_rratio 0.2)
      (net 9 "/Ethernet/AVDDL") (pintype "passive"))
    (pad "2" smd roundrect (at 0.7 0 90) (size 0.8 1) (layers "B.Cu" "B.Paste" "B.Mask") (roundrect_rratio 0.2)
      (net 211 "VCC1V2") (pintype "passive"))
  )

  (footprint "antmicro-footprints:FB_0603_1608Metric" (layer "B.Cu")
    (at 98.1 91.75 90)
    (property "Author" "Antmicro")
    (property "Current" "")
    (property "License" "Apache-2.0")
    (property "MPN" "BLM18PG121SN1D")
    (property "Manufacturer" "Murata")
    (property "Public" "False")
    (property "Sheetfile" "ethernet.kicad_sch")
    (property "Sheetname" "Ethernet")
    (property "Val" "120Z/2A")
    (property "ki_description" "Ferrite Bead, 0603 [1608 Metric], 120 ohm, 2 A, BLM18P, 0.05 ohm, ± 25%, DC power line")
    (property "ki_keywords" "0603, SMT, FERRITE BEAD, PASSIVE")
    (attr smd)
    (fp_text reference "FB1" (at -0.035 -1.15 90) (layer "B.SilkS")
        (effects (font (size 0.7 0.7) (thickness 0.127)) (justify mirror))
    )
    (fp_text value "FB_120Z_2A_Murata-BLM18PG_0603" (at 0 -1.9 90) (layer "B.Fab")
        (effects (font (size 1 1) (thickness 0.15)) (justify mirror))
    )
    (fp_text user "License: Apache-2.0" (at -1.653 -5.9 270) (layer "B.Fab") hide
        (effects (font (size 0.7 0.7) (thickness 0.15)) (justify left bottom mirror))
    )
    (fp_text user "Author: Antmicro" (at -1.653 -3.162 270) (layer "B.Fab") hide
        (effects (font (size 0.7 0.7) (thickness 0.15)) (justify left bottom mirror))
    )
    (fp_text user "${REFERENCE}" (at -1.653 -4.6 270) (layer "B.Fab") hide
        (effects (font (size 0.7 0.7) (thickness 0.15)) (justify left bottom mirror))
    )
    (fp_line (start -0.15 -0.4) (end 0.15 -0.4)
      (stroke (width 0.15) (type solid)) (layer "B.SilkS"))
    (fp_line (start -0.15 0.4) (end 0.15 0.4)
      (stroke (width 0.15) (type solid)) (layer "B.SilkS"))
    (fp_rect (start -1.25 0.65) (end 1.25 -0.65)
      (stroke (width 0.05) (type solid)) (fill none) (layer "B.CrtYd"))
    (fp_line (start -0.803 -0.406) (end -0.803 0.408)
      (stroke (width 0.15) (type solid)) (layer "B.Fab"))
    (fp_line (start 0.8 -0.406) (end -0.803 -0.406)
      (stroke (width 0.15) (type solid)) (layer "B.Fab"))
    (fp_line (start 0.8 0.408) (end -0.803 0.408)
      (stroke (width 0.15) (type solid)) (layer "B.Fab"))
    (fp_line (start 0.8 0.408) (end 0.8 -0.406)
      (stroke (width 0.15) (type solid)) (layer "B.Fab"))
    (pad "1" smd roundrect (at -0.7 0 90) (size 0.8 1) (layers "B.Cu" "B.Paste" "B.Mask") (roundrect_rratio 0.2)
      (net 2 "VCC3V3") (pintype "passive"))
    (pad "2" smd roundrect (at 0.7 0 90) (size 0.8 1) (layers "B.Cu" "B.Paste" "B.Mask") (roundrect_rratio 0.2)
      (net 4 "/Ethernet/AVDDH") (pintype "passive"))
  )

  (footprint "antmicro-footprints:C_0402_1005Metric" (layer "B.Cu")
    (at 108.95 95.65 180)
    (descr "Capacitor SMD 0402")
    (tags "capacitor SMD 0402")
    (property "Author" "Antmicro")
    (property "Dielectric" "X7R")
    (property "License" "Apache-2.0")
    (property "MPN" "GRM155R71H103KA88D")
    (property "Manufacturer" "Murata")
    (property "Public" "False")
    (property "Sheetfile" "ethernet.kicad_sch")
    (property "Sheetname" "Ethernet")
    (property "Val" "10n")
    (property "Voltage" "50V")
    (property "ki_description" "SMD Multilayer Ceramic Capacitor, 10000 pF, 50 V, 0402 [1005 Metric], ± 10%, X7R, GRM Series")
    (property "ki_keywords" "0402, SMT, CAPACITOR, PASSIVE")
    (attr smd)
    (fp_text reference "C25" (at 0.1 5.0525) (layer "B.SilkS")
        (effects (font (size 0.7 0.7) (thickness 0.127)) (justify mirror))
    )
    (fp_text value "C_10n_0402" (at 0 -1.17) (layer "B.Fab")
        (effects (font (size 1 1) (thickness 0.15)) (justify mirror))
    )
    (fp_text user "${REFERENCE}" (at 0 0) (layer "B.Fab")
        (effects (font (size 0.25 0.25) (thickness 0.04)) (justify mirror))
    )
    (fp_text user "Author: Antmicro" (at -0.939 -3.399) (layer "B.Fab") hide
        (effects (font (size 0.7 0.7) (thickness 0.15)) (justify left bottom mirror))
    )
    (fp_text user "License: Apache-2.0" (at -0.939 -5.799) (layer "B.Fab") hide
        (effects (font (size 0.7 0.7) (thickness 0.15)) (justify left bottom mirror))
    )
    (fp_rect (start -0.925 0.47) (end 0.925 -0.47)
      (stroke (width 0.05) (type default)) (fill none) (layer "B.CrtYd"))
    (fp_line (start -0.494 -0.248) (end -0.494 0.25)
      (stroke (width 0.15) (type solid)) (layer "B.Fab"))
    (fp_line (start -0.494 0.25) (end 0.504 0.25)
      (stroke (width 0.15) (type solid)) (layer "B.Fab"))
    (fp_line (start 0.504 -0.248) (end -0.494 -0.248)
      (stroke (width 0.15) (type solid)) (layer "B.Fab"))
    (fp_line (start 0.504 0.25) (end 0.504 -0.248)
      (stroke (width 0.15) (type solid)) (layer "B.Fab"))
    (pad "1" smd roundrect (at -0.48 0 180) (size 0.59 0.64) (layers "B.Cu" "B.Paste" "B.Mask") (roundrect_rratio 0.25)
      (net 1 "GND") (pintype "passive"))
    (pad "2" smd roundrect (at 0.48 0 180) (size 0.59 0.64) (layers "B.Cu" "B.Paste" "B.Mask") (roundrect_rratio 0.25)
      (net 10 "/Ethernet/AVDDL_PLL") (pintype "passive"))
  )

  (footprint "antmicro-footprints:C_0402_1005Metric" (layer "B.Cu")
    (at 106.3 95.7)
    (descr "Capacitor SMD 0402")
    (tags "capacitor SMD 0402")
    (property "Author" "Antmicro")
    (property "Dielectric" "X5R")
    (property "License" "Apache-2.0")
    (property "MPN" "GRM155R61H104KE14D")
    (property "Manufacturer" "Murata")
    (property "Public" "False")
    (property "Sheetfile" "ethernet.kicad_sch")
    (property "Sheetname" "Ethernet")
    (property "Val" "100n")
    (property "Voltage" "50V")
    (property "ki_description" "SMD Multilayer Ceramic Capacitor, 0.1 µF, 50 V, 0402 [1005 Metric], ± 10%, X5R, GRM Series")
    (property "ki_keywords" "0402, SMT, CAPACITOR, PASSIVE, CERAMIC, MLCC")
    (attr smd)
    (fp_text reference "C24" (at -1.91 0.005) (layer "B.SilkS")
        (effects (font (size 0.7 0.7) (thickness 0.127)) (justify mirror))
    )
    (fp_text value "C_100n_0402" (at 0 -1.17) (layer "B.Fab")
        (effects (font (size 1 1) (thickness 0.15)) (justify mirror))
    )
    (fp_text user "License: Apache-2.0" (at -0.939 -5.799 180) (layer "B.Fab") hide
        (effects (font (size 0.7 0.7) (thickness 0.15)) (justify left bottom mirror))
    )
    (fp_text user "${REFERENCE}" (at 0 0) (layer "B.Fab")
        (effects (font (size 0.25 0.25) (thickness 0.04)) (justify mirror))
    )
    (fp_text user "Author: Antmicro" (at -0.939 -3.399 180) (layer "B.Fab") hide
        (effects (font (size 0.7 0.7) (thickness 0.15)) (justify left bottom mirror))
    )
    (fp_rect (start -0.925 0.47) (end 0.925 -0.47)
      (stroke (width 0.05) (type default)) (fill none) (layer "B.CrtYd"))
    (fp_line (start -0.494 -0.248) (end -0.494 0.25)
      (stroke (width 0.15) (type solid)) (layer "B.Fab"))
    (fp_line (start -0.494 0.25) (end 0.504 0.25)
      (stroke (width 0.15) (type solid)) (layer "B.Fab"))
    (fp_line (start 0.504 -0.248) (end -0.494 -0.248)
      (stroke (width 0.15) (type solid)) (layer "B.Fab"))
    (fp_line (start 0.504 0.25) (end 0.504 -0.248)
      (stroke (width 0.15) (type solid)) (layer "B.Fab"))
    (pad "1" smd roundrect (at -0.48 0) (size 0.59 0.64) (layers "B.Cu" "B.Paste" "B.Mask") (roundrect_rratio 0.25)
      (net 1 "GND") (pintype "passive"))
    (pad "2" smd roundrect (at 0.48 0) (size 0.59 0.64) (layers "B.Cu" "B.Paste" "B.Mask") (roundrect_rratio 0.25)
      (net 10 "/Ethernet/AVDDL_PLL") (pintype "passive"))
  )

  (footprint "antmicro-footprints:C_0402_1005Metric" (layer "B.Cu")
    (at 104.45 90.55 -90)
    (descr "Capacitor SMD 0402")
    (tags "capacitor SMD 0402")
    (property "Author" "Antmicro")
    (property "Dielectric" "X7R")
    (property "License" "Apache-2.0")
    (property "MPN" "GRM155R71H103KA88D")
    (property "Manufacturer" "Murata")
    (property "Public" "False")
    (property "Sheetfile" "ethernet.kicad_sch")
    (property "Sheetname" "Ethernet")
    (property "Val" "10n")
    (property "Voltage" "50V")
    (property "ki_description" "SMD Multilayer Ceramic Capacitor, 10000 pF, 50 V, 0402 [1005 Metric], ± 10%, X7R, GRM Series")
    (property "ki_keywords" "0402, SMT, CAPACITOR, PASSIVE")
    (attr smd)
    (fp_text reference "C23" (at -1.885 -0.05 90) (layer "B.SilkS")
        (effects (font (size 0.7 0.7) (thickness 0.127)) (justify mirror))
    )
    (fp_text value "C_10n_0402" (at 0 -1.17 90) (layer "B.Fab")
        (effects (font (size 1 1) (thickness 0.15)) (justify mirror))
    )
    (fp_text user "Author: Antmicro" (at -0.939 -3.399 90) (layer "B.Fab") hide
        (effects (font (size 0.7 0.7) (thickness 0.15)) (justify left bottom mirror))
    )
    (fp_text user "License: Apache-2.0" (at -0.939 -5.799 90) (layer "B.Fab") hide
        (effects (font (size 0.7 0.7) (thickness 0.15)) (justify left bottom mirror))
    )
    (fp_text user "${REFERENCE}" (at 0 0 90) (layer "B.Fab")
        (effects (font (size 0.25 0.25) (thickness 0.04)) (justify mirror))
    )
    (fp_rect (start -0.925 0.47) (end 0.925 -0.47)
      (stroke (width 0.05) (type default)) (fill none) (layer "B.CrtYd"))
    (fp_line (start -0.494 -0.248) (end -0.494 0.25)
      (stroke (width 0.15) (type solid)) (layer "B.Fab"))
    (fp_line (start -0.494 0.25) (end 0.504 0.25)
      (stroke (width 0.15) (type solid)) (layer "B.Fab"))
    (fp_line (start 0.504 -0.248) (end -0.494 -0.248)
      (stroke (width 0.15) (type solid)) (layer "B.Fab"))
    (fp_line (start 0.504 0.25) (end 0.504 -0.248)
      (stroke (width 0.15) (type solid)) (layer "B.Fab"))
    (pad "1" smd roundrect (at -0.48 0 270) (size 0.59 0.64) (layers "B.Cu" "B.Paste" "B.Mask") (roundrect_rratio 0.25)
      (net 1 "GND") (pintype "passive"))
    (pad "2" smd roundrect (at 0.48 0 270) (size 0.59 0.64) (layers "B.Cu" "B.Paste" "B.Mask") (roundrect_rratio 0.25)
      (net 9 "/Ethernet/AVDDL") (pintype "passive"))
  )

  (footprint "antmicro-footprints:C_0402_1005Metric" (layer "B.Cu")
    (at 102.01 100.3 -90)
    (descr "Capacitor SMD 0402")
    (tags "capacitor SMD 0402")
    (property "Author" "Antmicro")
    (property "Dielectric" "")
    (property "License" "Apache-2.0")
    (property "MPN" "GRM155R61A475MEAAD")
    (property "Manufacturer" "Murata")
    (property "Public" "False")
    (property "Sheetfile" "ethernet.kicad_sch")
    (property "Sheetname" "Ethernet")
    (property "Val" "4u7")
    (property "Voltage" "")
    (property "ki_description" "SMD Multilayer Ceramic Capacitor, 4.7 µF, 10 V, 0402 [1005 Metric], ± 20%, X5R, GRM Series")
    (property "ki_keywords" "0402, SMT, CAPACITOR, PASSIVE")
    (attr smd)
    (fp_text reference "C1" (at 1.575 -0.05 90) (layer "B.SilkS")
        (effects (font (size 0.7 0.7) (thickness 0.127)) (justify mirror))
    )
    (fp_text value "C_4u7_0402" (at 0 -1.17 90) (layer "B.Fab")
        (effects (font (size 1 1) (thickness 0.15)) (justify mirror))
    )
    (fp_text user "Author: Antmicro" (at -0.939 -3.399 90) (layer "B.Fab") hide
        (effects (font (size 0.7 0.7) (thickness 0.15)) (justify left bottom mirror))
    )
    (fp_text user "License: Apache-2.0" (at -0.939 -5.799 90) (layer "B.Fab") hide
        (effects (font (size 0.7 0.7) (thickness 0.15)) (justify left bottom mirror))
    )
    (fp_text user "${REFERENCE}" (at 0 0 90) (layer "B.Fab")
        (effects (font (size 0.25 0.25) (thickness 0.04)) (justify mirror))
    )
    (fp_rect (start -0.925 0.47) (end 0.925 -0.47)
      (stroke (width 0.05) (type default)) (fill none) (layer "B.CrtYd"))
    (fp_line (start -0.494 -0.248) (end -0.494 0.25)
      (stroke (width 0.15) (type solid)) (layer "B.Fab"))
    (fp_line (start -0.494 0.25) (end 0.504 0.25)
      (stroke (width 0.15) (type solid)) (layer "B.Fab"))
    (fp_line (start 0.504 -0.248) (end -0.494 -0.248)
      (stroke (width 0.15) (type solid)) (layer "B.Fab"))
    (fp_line (start 0.504 0.25) (end 0.504 -0.248)
      (stroke (width 0.15) (type solid)) (layer "B.Fab"))
    (pad "1" smd roundrect (at -0.48 0 270) (size 0.59 0.64) (layers "B.Cu" "B.Paste" "B.Mask") (roundrect_rratio 0.25)
      (net 1 "GND") (pintype "passive"))
    (pad "2" smd roundrect (at 0.48 0 270) (size 0.59 0.64) (layers "B.Cu" "B.Paste" "B.Mask") (roundrect_rratio 0.25)
      (net 211 "VCC1V2") (pintype "passive"))
  )

  (footprint "antmicro-footprints:C_0402_1005Metric" (layer "B.Cu")
    (at 108.95 96.7)
    (descr "Capacitor SMD 0402")
    (tags "capacitor SMD 0402")
    (property "Author" "Antmicro")
    (property "Dielectric" "X5R")
    (property "License" "Apache-2.0")
    (property "MPN" "GRM155R61H104KE14D")
    (property "Manufacturer" "Murata")
    (property "Public" "False")
    (property "Sheetfile" "ethernet.kicad_sch")
    (property "Sheetname" "Ethernet")
    (property "Val" "100n")
    (property "Voltage" "50V")
    (property "ki_description" "SMD Multilayer Ceramic Capacitor, 0.1 µF, 50 V, 0402 [1005 Metric], ± 10%, X5R, GRM Series")
    (property "ki_keywords" "0402, SMT, CAPACITOR, PASSIVE, CERAMIC, MLCC")
    (attr smd)
    (fp_text reference "C47" (at 0.1 4.935) (layer "B.SilkS")
        (effects (font (size 0.7 0.7) (thickness 0.127)) (justify mirror))
    )
    (fp_text value "C_100n_0402" (at 0 -1.17) (layer "B.Fab")
        (effects (font (size 1 1) (thickness 0.15)) (justify mirror))
    )
    (fp_text user "${REFERENCE}" (at 0 0) (layer "B.Fab")
        (effects (font (size 0.25 0.25) (thickness 0.04)) (justify mirror))
    )
    (fp_text user "License: Apache-2.0" (at -0.939 -5.799 180) (layer "B.Fab") hide
        (effects (font (size 0.7 0.7) (thickness 0.15)) (justify left bottom mirror))
    )
    (fp_text user "Author: Antmicro" (at -0.939 -3.399 180) (layer "B.Fab") hide
        (effects (font (size 0.7 0.7) (thickness 0.15)) (justify left bottom mirror))
    )
    (fp_rect (start -0.925 0.47) (end 0.925 -0.47)
      (stroke (width 0.05) (type default)) (fill none) (layer "B.CrtYd"))
    (fp_line (start -0.494 -0.248) (end -0.494 0.25)
      (stroke (width 0.15) (type solid)) (layer "B.Fab"))
    (fp_line (start -0.494 0.25) (end 0.504 0.25)
      (stroke (width 0.15) (type solid)) (layer "B.Fab"))
    (fp_line (start 0.504 -0.248) (end -0.494 -0.248)
      (stroke (width 0.15) (type solid)) (layer "B.Fab"))
    (fp_line (start 0.504 0.25) (end 0.504 -0.248)
      (stroke (width 0.15) (type solid)) (layer "B.Fab"))
    (pad "1" smd roundrect (at -0.48 0) (size 0.59 0.64) (layers "B.Cu" "B.Paste" "B.Mask") (roundrect_rratio 0.25)
      (net 163 "ETH_~{RESET}") (pintype "passive"))
    (pad "2" smd roundrect (at 0.48 0) (size 0.59 0.64) (layers "B.Cu" "B.Paste" "B.Mask") (roundrect_rratio 0.25)
      (net 1 "GND") (pintype "passive"))
  )

  (footprint "antmicro-footprints:C_0402_1005Metric" (layer "B.Cu")
    (at 129.65 114)
    (descr "Capacitor SMD 0402")
    (tags "capacitor SMD 0402")
    (property "Author" "Antmicro")
    (property "Dielectric" "X5R")
    (property "License" "Apache-2.0")
    (property "MPN" "GRM155R61H104KE14D")
    (property "Manufacturer" "Murata")
    (property "Public" "False")
    (property "Sheetfile" "interfaces.kicad_sch")
    (property "Sheetname" "Interfaces")
    (property "Val" "100n")
    (property "Voltage" "50V")
    (property "ki_description" "SMD Multilayer Ceramic Capacitor, 0.1 µF, 50 V, 0402 [1005 Metric], ± 10%, X5R, GRM Series")
    (property "ki_keywords" "0402, SMT, CAPACITOR, PASSIVE, CERAMIC, MLCC")
    (attr smd)
    (fp_text reference "C69" (at -2 0) (layer "B.SilkS")
        (effects (font (size 0.7 0.7) (thickness 0.127)) (justify mirror))
    )
    (fp_text value "C_100n_0402" (at 0 -1.17) (layer "B.Fab")
        (effects (font (size 1 1) (thickness 0.15)) (justify mirror))
    )
    (fp_text user "License: Apache-2.0" (at -0.939 -5.799 180) (layer "B.Fab") hide
        (effects (font (size 0.7 0.7) (thickness 0.15)) (justify left bottom mirror))
    )
    (fp_text user "${REFERENCE}" (at 0 0) (layer "B.Fab")
        (effects (font (size 0.25 0.25) (thickness 0.04)) (justify mirror))
    )
    (fp_text user "Author: Antmicro" (at -0.939 -3.399 180) (layer "B.Fab") hide
        (effects (font (size 0.7 0.7) (thickness 0.15)) (justify left bottom mirror))
    )
    (fp_rect (start -0.925 0.47) (end 0.925 -0.47)
      (stroke (width 0.05) (type default)) (fill none) (layer "B.CrtYd"))
    (fp_line (start -0.494 -0.248) (end -0.494 0.25)
      (stroke (width 0.15) (type solid)) (layer "B.Fab"))
    (fp_line (start -0.494 0.25) (end 0.504 0.25)
      (stroke (width 0.15) (type solid)) (layer "B.Fab"))
    (fp_line (start 0.504 -0.248) (end -0.494 -0.248)
      (stroke (width 0.15) (type solid)) (layer "B.Fab"))
    (fp_line (start 0.504 0.25) (end 0.504 -0.248)
      (stroke (width 0.15) (type solid)) (layer "B.Fab"))
    (pad "1" smd roundrect (at -0.48 0) (size 0.59 0.64) (layers "B.Cu" "B.Paste" "B.Mask") (roundrect_rratio 0.25)
      (net 2 "VCC3V3") (pintype "passive"))
    (pad "2" smd roundrect (at 0.48 0) (size 0.59 0.64) (layers "B.Cu" "B.Paste" "B.Mask") (roundrect_rratio 0.25)
      (net 1 "GND") (pintype "passive"))
  )

  (footprint "antmicro-footprints:C_0402_1005Metric" (layer "B.Cu")
    (at 121.55 115.8 -90)
    (descr "Capacitor SMD 0402")
    (tags "capacitor SMD 0402")
    (property "Author" "Antmicro")
    (property "Dielectric" "X5R")
    (property "License" "Apache-2.0")
    (property "MPN" "GRM155R61H104KE14D")
    (property "Manufacturer" "Murata")
    (property "Public" "False")
    (property "Sheetfile" "interfaces.kicad_sch")
    (property "Sheetname" "Interfaces")
    (property "Val" "100n")
    (property "Voltage" "50V")
    (property "ki_description" "SMD Multilayer Ceramic Capacitor, 0.1 µF, 50 V, 0402 [1005 Metric], ± 10%, X5R, GRM Series")
    (property "ki_keywords" "0402, SMT, CAPACITOR, PASSIVE, CERAMIC, MLCC")
    (attr smd)
    (fp_text reference "C76" (at -0.025 1.05 90) (layer "B.SilkS")
        (effects (font (size 0.7 0.7) (thickness 0.127)) (justify mirror))
    )
    (fp_text value "C_100n_0402" (at 0 -1.17 90) (layer "B.Fab")
        (effects (font (size 1 1) (thickness 0.15)) (justify mirror))
    )
    (fp_text user "Author: Antmicro" (at -0.939 -3.399 90) (layer "B.Fab") hide
        (effects (font (size 0.7 0.7) (thickness 0.15)) (justify left bottom mirror))
    )
    (fp_text user "License: Apache-2.0" (at -0.939 -5.799 90) (layer "B.Fab") hide
        (effects (font (size 0.7 0.7) (thickness 0.15)) (justify left bottom mirror))
    )
    (fp_text user "${REFERENCE}" (at 0 0 90) (layer "B.Fab")
        (effects (font (size 0.25 0.25) (thickness 0.04)) (justify mirror))
    )
    (fp_rect (start -0.925 0.47) (end 0.925 -0.47)
      (stroke (width 0.05) (type default)) (fill none) (layer "B.CrtYd"))
    (fp_line (start -0.494 -0.248) (end -0.494 0.25)
      (stroke (width 0.15) (type solid)) (layer "B.Fab"))
    (fp_line (start -0.494 0.25) (end 0.504 0.25)
      (stroke (width 0.15) (type solid)) (layer "B.Fab"))
    (fp_line (start 0.504 -0.248) (end -0.494 -0.248)
      (stroke (width 0.15) (type solid)) (layer "B.Fab"))
    (fp_line (start 0.504 0.25) (end 0.504 -0.248)
      (stroke (width 0.15) (type solid)) (layer "B.Fab"))
    (pad "1" smd roundrect (at -0.48 0 270) (size 0.59 0.64) (layers "B.Cu" "B.Paste" "B.Mask") (roundrect_rratio 0.25)
      (net 1 "GND") (pintype "passive"))
    (pad "2" smd roundrect (at 0.48 0 270) (size 0.59 0.64) (layers "B.Cu" "B.Paste" "B.Mask") (roundrect_rratio 0.25)
      (net 672 "Net-(C76-Pad2)") (pintype "passive"))
  )

  (footprint "antmicro-footprints:C_0402_1005Metric" (layer "B.Cu")
    (at 129.65 116.533333)
    (descr "Capacitor SMD 0402")
    (tags "capacitor SMD 0402")
    (property "Author" "Antmicro")
    (property "Dielectric" "")
    (property "License" "Apache-2.0")
    (property "MPN" "GRM155R61A475MEAAD")
    (property "Manufacturer" "Murata")
    (property "Public" "False")
    (property "Sheetfile" "interfaces.kicad_sch")
    (property "Sheetname" "Interfaces")
    (property "Val" "4u7")
    (property "Voltage" "")
    (property "ki_description" "SMD Multilayer Ceramic Capacitor, 4.7 µF, 10 V, 0402 [1005 Metric], ± 20%, X5R, GRM Series")
    (property "ki_keywords" "0402, SMT, CAPACITOR, PASSIVE")
    (attr smd)
    (fp_text reference "C70" (at 2 -0.008333) (layer "B.SilkS")
        (effects (font (size 0.7 0.7) (thickness 0.127)) (justify mirror))
    )
    (fp_text value "C_4u7_0402" (at 0 -1.17) (layer "B.Fab")
        (effects (font (size 1 1) (thickness 0.15)) (justify mirror))
    )
    (fp_text user "Author: Antmicro" (at -0.939 -3.399 180) (layer "B.Fab") hide
        (effects (font (size 0.7 0.7) (thickness 0.15)) (justify left bottom mirror))
    )
    (fp_text user "License: Apache-2.0" (at -0.939 -5.799 180) (layer "B.Fab") hide
        (effects (font (size 0.7 0.7) (thickness 0.15)) (justify left bottom mirror))
    )
    (fp_text user "${REFERENCE}" (at 0 0) (layer "B.Fab")
        (effects (font (size 0.25 0.25) (thickness 0.04)) (justify mirror))
    )
    (fp_rect (start -0.925 0.47) (end 0.925 -0.47)
      (stroke (width 0.05) (type default)) (fill none) (layer "B.CrtYd"))
    (fp_line (start -0.494 -0.248) (end -0.494 0.25)
      (stroke (width 0.15) (type solid)) (layer "B.Fab"))
    (fp_line (start -0.494 0.25) (end 0.504 0.25)
      (stroke (width 0.15) (type solid)) (layer "B.Fab"))
    (fp_line (start 0.504 -0.248) (end -0.494 -0.248)
      (stroke (width 0.15) (type solid)) (layer "B.Fab"))
    (fp_line (start 0.504 0.25) (end 0.504 -0.248)
      (stroke (width 0.15) (type solid)) (layer "B.Fab"))
    (pad "1" smd roundrect (at -0.48 0) (size 0.59 0.64) (layers "B.Cu" "B.Paste" "B.Mask") (roundrect_rratio 0.25)
      (net 226 "Net-(U9-VDDA1.8)") (pintype "passive"))
    (pad "2" smd roundrect (at 0.48 0) (size 0.59 0.64) (layers "B.Cu" "B.Paste" "B.Mask") (roundrect_rratio 0.25)
      (net 1 "GND") (pintype "passive"))
  )

  (footprint "antmicro-footprints:C_0402_1005Metric" (layer "B.Cu")
    (at 129.65 117.541666 180)
    (descr "Capacitor SMD 0402")
    (tags "capacitor SMD 0402")
    (property "Author" "Antmicro")
    (property "Dielectric" "")
    (property "License" "Apache-2.0")
    (property "MPN" "GRM155R61A475MEAAD")
    (property "Manufacturer" "Murata")
    (property "Public" "False")
    (property "Sheetfile" "interfaces.kicad_sch")
    (property "Sheetname" "Interfaces")
    (property "Val" "4u7")
    (property "Voltage" "")
    (property "ki_description" "SMD Multilayer Ceramic Capacitor, 4.7 µF, 10 V, 0402 [1005 Metric], ± 20%, X5R, GRM Series")
    (property "ki_keywords" "0402, SMT, CAPACITOR, PASSIVE")
    (attr smd)
    (fp_text reference "C77" (at 2 0.008334) (layer "B.SilkS")
        (effects (font (size 0.7 0.7) (thickness 0.127)) (justify mirror))
    )
    (fp_text value "C_4u7_0402" (at 0 -1.17) (layer "B.Fab")
        (effects (font (size 1 1) (thickness 0.15)) (justify mirror))
    )
    (fp_text user "Author: Antmicro" (at -0.939 -3.399) (layer "B.Fab") hide
        (effects (font (size 0.7 0.7) (thickness 0.15)) (justify left bottom mirror))
    )
    (fp_text user "${REFERENCE}" (at 0 0) (layer "B.Fab")
        (effects (font (size 0.25 0.25) (thickness 0.04)) (justify mirror))
    )
    (fp_text user "License: Apache-2.0" (at -0.939 -5.799) (layer "B.Fab") hide
        (effects (font (size 0.7 0.7) (thickness 0.15)) (justify left bottom mirror))
    )
    (fp_rect (start -0.925 0.47) (end 0.925 -0.47)
      (stroke (width 0.05) (type default)) (fill none) (layer "B.CrtYd"))
    (fp_line (start -0.494 -0.248) (end -0.494 0.25)
      (stroke (width 0.15) (type solid)) (layer "B.Fab"))
    (fp_line (start -0.494 0.25) (end 0.504 0.25)
      (stroke (width 0.15) (type solid)) (layer "B.Fab"))
    (fp_line (start 0.504 -0.248) (end -0.494 -0.248)
      (stroke (width 0.15) (type solid)) (layer "B.Fab"))
    (fp_line (start 0.504 0.25) (end 0.504 -0.248)
      (stroke (width 0.15) (type solid)) (layer "B.Fab"))
    (pad "1" smd roundrect (at -0.48 0 180) (size 0.59 0.64) (layers "B.Cu" "B.Paste" "B.Mask") (roundrect_rratio 0.25)
      (net 1 "GND") (pintype "passive"))
    (pad "2" smd roundrect (at 0.48 0 180) (size 0.59 0.64) (layers "B.Cu" "B.Paste" "B.Mask") (roundrect_rratio 0.25)
      (net 672 "Net-(C76-Pad2)") (pintype "passive"))
  )

  (footprint "antmicro-footprints:C_0402_1005Metric" (layer "B.Cu")
    (at 95 82.5)
    (descr "Capacitor SMD 0402")
    (tags "capacitor SMD 0402")
    (property "Author" "Antmicro")
    (property "Dielectric" "X5R")
    (property "License" "Apache-2.0")
    (property "MPN" "GRM155R61H104KE14D")
    (property "Manufacturer" "Murata")
    (property "Public" "False")
    (property "Sheetfile" "ethernet.kicad_sch")
    (property "Sheetname" "Ethernet")
    (property "Val" "100n")
    (property "Voltage" "50V")
    (property "ki_description" "SMD Multilayer Ceramic Capacitor, 0.1 µF, 50 V, 0402 [1005 Metric], ± 10%, X5R, GRM Series")
    (property "ki_keywords" "0402, SMT, CAPACITOR, PASSIVE, CERAMIC, MLCC")
    (attr smd)
    (fp_text reference "C29" (at -0.1 -2.03) (layer "B.SilkS")
        (effects (font (size 0.7 0.7) (thickness 0.127)) (justify mirror))
    )
    (fp_text value "C_100n_0402" (at 0 -1.17) (layer "B.Fab")
        (effects (font (size 1 1) (thickness 0.15)) (justify mirror))
    )
    (fp_text user "License: Apache-2.0" (at -0.939 -5.799 180) (layer "B.Fab") hide
        (effects (font (size 0.7 0.7) (thickness 0.15)) (justify left bottom mirror))
    )
    (fp_text user "Author: Antmicro" (at -0.939 -3.399 180) (layer "B.Fab") hide
        (effects (font (size 0.7 0.7) (thickness 0.15)) (justify left bottom mirror))
    )
    (fp_text user "${REFERENCE}" (at 0 0) (layer "B.Fab")
        (effects (font (size 0.25 0.25) (thickness 0.04)) (justify mirror))
    )
    (fp_rect (start -0.925 0.47) (end 0.925 -0.47)
      (stroke (width 0.05) (type default)) (fill none) (layer "B.CrtYd"))
    (fp_line (start -0.494 -0.248) (end -0.494 0.25)
      (stroke (width 0.15) (type solid)) (layer "B.Fab"))
    (fp_line (start -0.494 0.25) (end 0.504 0.25)
      (stroke (width 0.15) (type solid)) (layer "B.Fab"))
    (fp_line (start 0.504 -0.248) (end -0.494 -0.248)
      (stroke (width 0.15) (type solid)) (layer "B.Fab"))
    (fp_line (start 0.504 0.25) (end 0.504 -0.248)
      (stroke (width 0.15) (type solid)) (layer "B.Fab"))
    (pad "1" smd roundrect (at -0.48 0) (size 0.59 0.64) (layers "B.Cu" "B.Paste" "B.Mask") (roundrect_rratio 0.25)
      (net 1 "GND") (pintype "passive"))
    (pad "2" smd roundrect (at 0.48 0) (size 0.59 0.64) (layers "B.Cu" "B.Paste" "B.Mask") (roundrect_rratio 0.25)
      (net 13 "Net-(J1-TRCT3)") (pintype "passive"))
  )

  (footprint "antmicro-footprints:C_0402_1005Metric" (layer "B.Cu")
    (at 95 83.5)
    (descr "Capacitor SMD 0402")
    (tags "capacitor SMD 0402")
    (property "Author" "Antmicro")
    (property "Dielectric" "X5R")
    (property "License" "Apache-2.0")
    (property "MPN" "GRM155R61H104KE14D")
    (property "Manufacturer" "Murata")
    (property "Public" "False")
    (property "Sheetfile" "ethernet.kicad_sch")
    (property "Sheetname" "Ethernet")
    (property "Val" "100n")
    (property "Voltage" "50V")
    (property "ki_description" "SMD Multilayer Ceramic Capacitor, 0.1 µF, 50 V, 0402 [1005 Metric], ± 10%, X5R, GRM Series")
    (property "ki_keywords" "0402, SMT, CAPACITOR, PASSIVE, CERAMIC, MLCC")
    (attr smd)
    (fp_text reference "C30" (at -0.1 -2.03) (layer "B.SilkS")
        (effects (font (size 0.7 0.7) (thickness 0.127)) (justify mirror))
    )
    (fp_text value "C_100n_0402" (at 0 -1.17) (layer "B.Fab")
        (effects (font (size 1 1) (thickness 0.15)) (justify mirror))
    )
    (fp_text user "${REFERENCE}" (at 0 0) (layer "B.Fab")
        (effects (font (size 0.25 0.25) (thickness 0.04)) (justify mirror))
    )
    (fp_text user "Author: Antmicro" (at -0.939 -3.399 180) (layer "B.Fab") hide
        (effects (font (size 0.7 0.7) (thickness 0.15)) (justify left bottom mirror))
    )
    (fp_text user "License: Apache-2.0" (at -0.939 -5.799 180) (layer "B.Fab") hide
        (effects (font (size 0.7 0.7) (thickness 0.15)) (justify left bottom mirror))
    )
    (fp_rect (start -0.925 0.47) (end 0.925 -0.47)
      (stroke (width 0.05) (type default)) (fill none) (layer "B.CrtYd"))
    (fp_line (start -0.494 -0.248) (end -0.494 0.25)
      (stroke (width 0.15) (type solid)) (layer "B.Fab"))
    (fp_line (start -0.494 0.25) (end 0.504 0.25)
      (stroke (width 0.15) (type solid)) (layer "B.Fab"))
    (fp_line (start 0.504 -0.248) (end -0.494 -0.248)
      (stroke (width 0.15) (type solid)) (layer "B.Fab"))
    (fp_line (start 0.504 0.25) (end 0.504 -0.248)
      (stroke (width 0.15) (type solid)) (layer "B.Fab"))
    (pad "1" smd roundrect (at -0.48 0) (size 0.59 0.64) (layers "B.Cu" "B.Paste" "B.Mask") (roundrect_rratio 0.25)
      (net 1 "GND") (pintype "passive"))
    (pad "2" smd roundrect (at 0.48 0) (size 0.59 0.64) (layers "B.Cu" "B.Paste" "B.Mask") (roundrect_rratio 0.25)
      (net 14 "Net-(J1-TRCT4)") (pintype "passive"))
  )

  (footprint "antmicro-footprints:R_0402_1005Metric" (layer "B.Cu")
    (at 81.09 122.595)
    (descr "Resistor SMD 0402")
    (tags "resistor SMD 0402")
    (property "Author" "Antmicro")
    (property "License" "Apache-2.0")
    (property "MPN" "CR0402-FX-51R0GLF")
    (property "Manufacturer" "Bourns")
    (property "Public" "False")
    (property "Sheetfile" "ddr3.kicad_sch")
    (property "Sheetname" "DDR3")
    (property "Tolerance" "1%")
    (property "Val" "51R")
    (property "ki_description" "SMD Chip Resistor, 51 ohm, ± 1%, 63 mW, 0402 [1005 Metric], Thick Film, General Purpose")
    (property "ki_keywords" "0402, SMT, RESISTOR, PASSIVE")
    (attr smd)
    (fp_text reference "R83" (at 0.23 -0.86 180) (layer "B.SilkS")
        (effects (font (size 0.7 0.7) (thickness 0.127)) (justify mirror))
    )
    (fp_text value "R_51R_0402" (at 0 -1.17) (layer "B.Fab")
        (effects (font (size 1 1) (thickness 0.15)) (justify mirror))
    )
    (fp_text user "Author: Antmicro" (at -0.95 -4.169 180) (layer "B.Fab") hide
        (effects (font (size 0.7 0.7) (thickness 0.15)) (justify left bottom mirror))
    )
    (fp_text user "${REFERENCE}" (at 0 0) (layer "B.Fab")
        (effects (font (size 0.25 0.25) (thickness 0.04)) (justify mirror))
    )
    (fp_text user "License: Apache-2.0" (at -0.95 -5.169 180) (layer "B.Fab") hide
        (effects (font (size 0.7 0.7) (thickness 0.15)) (justify left bottom mirror))
    )
    (fp_rect (start -0.925 0.47) (end 0.925 -0.47)
      (stroke (width 0.05) (type default)) (fill none) (layer "B.CrtYd"))
    (fp_rect (start -0.5 0.25) (end 0.5 -0.25)
      (stroke (width 0.15) (type solid)) (fill none) (layer "B.Fab"))
    (pad "1" smd roundrect (at -0.48 0) (size 0.59 0.64) (layers "B.Cu" "B.Paste" "B.Mask") (roundrect_rratio 0.25)
      (net 228 "Net-(C94-Pad1)") (pintype "passive"))
    (pad "2" smd roundrect (at 0.48 0) (size 0.59 0.64) (layers "B.Cu" "B.Paste" "B.Mask") (roundrect_rratio 0.25)
      (net 262 "DDR3_CLK-") (pintype "passive"))
  )

  (footprint "antmicro-footprints:C_0402_1005Metric" (layer "B.Cu")
    (at 83.15 138.765 -90)
    (descr "Capacitor SMD 0402")
    (tags "capacitor SMD 0402")
    (property "Author" "Antmicro")
    (property "Dielectric" "")
    (property "License" "Apache-2.0")
    (property "MPN" "C1005X5R1E474M050BB")
    (property "Manufacturer" "TDK")
    (property "Public" "False")
    (property "Sheetfile" "rot.kicad_sch")
    (property "Sheetname" "RoT")
    (property "Val" "470n")
    (property "Voltage" "")
    (property "ki_description" "SMD Multilayer Ceramic Capacitor, 0.47 µF, 25 V, 0402 [1005 Metric], ± 20%, X5R, C")
    (property "ki_keywords" "0402, SMT, CAPACITOR, PASSIVE, CERAMIC, MLCC")
    (attr smd)
    (fp_text reference "C43" (at -3.085 0.199996 90) (layer "B.SilkS")
        (effects (font (size 0.7 0.7) (thickness 0.127)) (justify mirror))
    )
    (fp_text value "C_470n_0402" (at 0 -1.17 90) (layer "B.Fab")
        (effects (font (size 1 1) (thickness 0.15)) (justify mirror))
    )
    (fp_text user "${REFERENCE}" (at 0 0 90) (layer "B.Fab")
        (effects (font (size 0.25 0.25) (thickness 0.04)) (justify mirror))
    )
    (fp_text user "Author: Antmicro" (at -0.939 -3.399 90) (layer "B.Fab") hide
        (effects (font (size 0.7 0.7) (thickness 0.15)) (justify left bottom mirror))
    )
    (fp_text user "License: Apache-2.0" (at -0.939 -5.799 90) (layer "B.Fab") hide
        (effects (font (size 0.7 0.7) (thickness 0.15)) (justify left bottom mirror))
    )
    (fp_rect (start -0.925 0.47) (end 0.925 -0.47)
      (stroke (width 0.05) (type default)) (fill none) (layer "B.CrtYd"))
    (fp_line (start -0.494 -0.248) (end -0.494 0.25)
      (stroke (width 0.15) (type solid)) (layer "B.Fab"))
    (fp_line (start -0.494 0.25) (end 0.504 0.25)
      (stroke (width 0.15) (type solid)) (layer "B.Fab"))
    (fp_line (start 0.504 -0.248) (end -0.494 -0.248)
      (stroke (width 0.15) (type solid)) (layer "B.Fab"))
    (fp_line (start 0.504 0.25) (end 0.504 -0.248)
      (stroke (width 0.15) (type solid)) (layer "B.Fab"))
    (pad "1" smd roundrect (at -0.48 0 270) (size 0.59 0.64) (layers "B.Cu" "B.Paste" "B.Mask") (roundrect_rratio 0.25)
      (net 1 "GND") (pintype "passive"))
    (pad "2" smd roundrect (at 0.48 0 270) (size 0.59 0.64) (layers "B.Cu" "B.Paste" "B.Mask") (roundrect_rratio 0.25)
      (net 2 "VCC3V3") (pintype "passive"))
  )

  (footprint "antmicro-footprints:C_0402_1005Metric" (layer "B.Cu")
    (at 82.6 130.55)
    (descr "Capacitor SMD 0402")
    (tags "capacitor SMD 0402")
    (property "Author" "Antmicro")
    (property "Dielectric" "")
    (property "License" "Apache-2.0")
    (property "MPN" "C1005X5R1E474M050BB")
    (property "Manufacturer" "TDK")
    (property "Public" "False")
    (property "Sheetfile" "rot.kicad_sch")
    (property "Sheetname" "RoT")
    (property "Val" "470n")
    (property "Voltage" "")
    (property "ki_description" "SMD Multilayer Ceramic Capacitor, 0.47 µF, 25 V, 0402 [1005 Metric], ± 20%, X5R, C")
    (property "ki_keywords" "0402, SMT, CAPACITOR, PASSIVE, CERAMIC, MLCC")
    (attr smd)
    (fp_text reference "C44" (at 0.02 -1.035) (layer "B.SilkS")
        (effects (font (size 0.7 0.7) (thickness 0.127)) (justify mirror))
    )
    (fp_text value "C_470n_0402" (at 0 -1.17) (layer "B.Fab")
        (effects (font (size 1 1) (thickness 0.15)) (justify mirror))
    )
    (fp_text user "${REFERENCE}" (at 0 0) (layer "B.Fab")
        (effects (font (size 0.25 0.25) (thickness 0.04)) (justify mirror))
    )
    (fp_text user "License: Apache-2.0" (at -0.939 -5.799 180) (layer "B.Fab") hide
        (effects (font (size 0.7 0.7) (thickness 0.15)) (justify left bottom mirror))
    )
    (fp_text user "Author: Antmicro" (at -0.939 -3.399 180) (layer "B.Fab") hide
        (effects (font (size 0.7 0.7) (thickness 0.15)) (justify left bottom mirror))
    )
    (fp_rect (start -0.925 0.47) (end 0.925 -0.47)
      (stroke (width 0.05) (type default)) (fill none) (layer "B.CrtYd"))
    (fp_line (start -0.494 -0.248) (end -0.494 0.25)
      (stroke (width 0.15) (type solid)) (layer "B.Fab"))
    (fp_line (start -0.494 0.25) (end 0.504 0.25)
      (stroke (width 0.15) (type solid)) (layer "B.Fab"))
    (fp_line (start 0.504 -0.248) (end -0.494 -0.248)
      (stroke (width 0.15) (type solid)) (layer "B.Fab"))
    (fp_line (start 0.504 0.25) (end 0.504 -0.248)
      (stroke (width 0.15) (type solid)) (layer "B.Fab"))
    (pad "1" smd roundrect (at -0.48 0) (size 0.59 0.64) (layers "B.Cu" "B.Paste" "B.Mask") (roundrect_rratio 0.25)
      (net 1 "GND") (pintype "passive"))
    (pad "2" smd roundrect (at 0.48 0) (size 0.59 0.64) (layers "B.Cu" "B.Paste" "B.Mask") (roundrect_rratio 0.25)
      (net 2 "VCC3V3") (pintype "passive"))
  )

  (footprint "antmicro-footprints:C_0402_1005Metric" (layer "B.Cu")
    (at 71.4 130.65)
    (descr "Capacitor SMD 0402")
    (tags "capacitor SMD 0402")
    (property "Author" "Antmicro")
    (property "Dielectric" "")
    (property "License" "Apache-2.0")
    (property "MPN" "C1005X5R1E474M050BB")
    (property "Manufacturer" "TDK")
    (property "Public" "False")
    (property "Sheetfile" "rot.kicad_sch")
    (property "Sheetname" "RoT")
    (property "Val" "470n")
    (property "Voltage" "")
    (property "ki_description" "SMD Multilayer Ceramic Capacitor, 0.47 µF, 25 V, 0402 [1005 Metric], ± 20%, X5R, C")
    (property "ki_keywords" "0402, SMT, CAPACITOR, PASSIVE, CERAMIC, MLCC")
    (attr smd)
    (fp_text reference "C45" (at 0 1.17) (layer "B.SilkS")
        (effects (font (size 0.7 0.7) (thickness 0.127)) (justify mirror))
    )
    (fp_text value "C_470n_0402" (at 0 -1.17) (layer "B.Fab")
        (effects (font (size 1 1) (thickness 0.15)) (justify mirror))
    )
    (fp_text user "License: Apache-2.0" (at -0.939 -5.799 180) (layer "B.Fab") hide
        (effects (font (size 0.7 0.7) (thickness 0.15)) (justify left bottom mirror))
    )
    (fp_text user "${REFERENCE}" (at 0 0) (layer "B.Fab")
        (effects (font (size 0.25 0.25) (thickness 0.04)) (justify mirror))
    )
    (fp_text user "Author: Antmicro" (at -0.939 -3.399 180) (layer "B.Fab") hide
        (effects (font (size 0.7 0.7) (thickness 0.15)) (justify left bottom mirror))
    )
    (fp_rect (start -0.925 0.47) (end 0.925 -0.47)
      (stroke (width 0.05) (type default)) (fill none) (layer "B.CrtYd"))
    (fp_line (start -0.494 -0.248) (end -0.494 0.25)
      (stroke (width 0.15) (type solid)) (layer "B.Fab"))
    (fp_line (start -0.494 0.25) (end 0.504 0.25)
      (stroke (width 0.15) (type solid)) (layer "B.Fab"))
    (fp_line (start 0.504 -0.248) (end -0.494 -0.248)
      (stroke (width 0.15) (type solid)) (layer "B.Fab"))
    (fp_line (start 0.504 0.25) (end 0.504 -0.248)
      (stroke (width 0.15) (type solid)) (layer "B.Fab"))
    (pad "1" smd roundrect (at -0.48 0) (size 0.59 0.64) (layers "B.Cu" "B.Paste" "B.Mask") (roundrect_rratio 0.25)
      (net 1 "GND") (pintype "passive"))
    (pad "2" smd roundrect (at 0.48 0) (size 0.59 0.64) (layers "B.Cu" "B.Paste" "B.Mask") (roundrect_rratio 0.25)
      (net 2 "VCC3V3") (pintype "passive"))
  )

  (footprint "antmicro-footprints:R_0402_1005Metric" (layer "B.Cu")
    (at 78.975 147.8 90)
    (descr "Resistor SMD 0402")
    (tags "resistor SMD 0402")
    (property "Author" "Antmicro")
    (property "License" "Apache-2.0")
    (property "MPN" "CR0402-FX-4701GLF")
    (property "Manufacturer" "Bourns")
    (property "Public" "False")
    (property "Sheetfile" "rot.kicad_sch")
    (property "Sheetname" "RoT")
    (property "Tolerance" "1%")
    (property "Val" "4k7")
    (property "ki_description" "SMD Chip Resistor, 4.7 kohm, ± 1%, 62.5 mW, 0402 [1005 Metric], Thick Film, General Purpose")
    (property "ki_keywords" "0402, SMT, RESISTOR, PASSIVE")
    (attr smd)
    (fp_text reference "R21" (at -2.75 1.125 270) (layer "B.SilkS")
        (effects (font (size 0.7 0.7) (thickness 0.127)) (justify mirror))
    )
    (fp_text value "R_4k7_0402" (at 0 -1.17 270) (layer "B.Fab")
        (effects (font (size 1 1) (thickness 0.15)) (justify mirror))
    )
    (fp_text user "License: Apache-2.0" (at -0.95 -5.169 270) (layer "B.Fab") hide
        (effects (font (size 0.7 0.7) (thickness 0.15)) (justify left bottom mirror))
    )
    (fp_text user "${REFERENCE}" (at 0 0 270) (layer "B.Fab")
        (effects (font (size 0.25 0.25) (thickness 0.04)) (justify mirror))
    )
    (fp_text user "Author: Antmicro" (at -0.95 -4.169 270) (layer "B.Fab") hide
        (effects (font (size 0.7 0.7) (thickness 0.15)) (justify left bottom mirror))
    )
    (fp_rect (start -0.925 0.47) (end 0.925 -0.47)
      (stroke (width 0.05) (type default)) (fill none) (layer "B.CrtYd"))
    (fp_rect (start -0.5 0.25) (end 0.5 -0.25)
      (stroke (width 0.15) (type solid)) (fill none) (layer "B.Fab"))
    (pad "1" smd roundrect (at -0.48 0 90) (size 0.59 0.64) (layers "B.Cu" "B.Paste" "B.Mask") (roundrect_rratio 0.25)
      (net 2 "VCC3V3") (pintype "passive"))
    (pad "2" smd roundrect (at 0.48 0 90) (size 0.59 0.64) (layers "B.Cu" "B.Paste" "B.Mask") (roundrect_rratio 0.25)
      (net 134 "QSPIB2_CS_N") (pintype "passive"))
  )

  (footprint "antmicro-footprints:R_0402_1005Metric" (layer "B.Cu")
    (at 67.725 138.85 90)
    (descr "Resistor SMD 0402")
    (tags "resistor SMD 0402")
    (property "Author" "Antmicro")
    (property "License" "Apache-2.0")
    (property "MPN" "CR0402-FX-4701GLF")
    (property "Manufacturer" "Bourns")
    (property "Public" "False")
    (property "Sheetfile" "rot.kicad_sch")
    (property "Sheetname" "RoT")
    (property "Tolerance" "1%")
    (property "Val" "4k7")
    (property "ki_description" "SMD Chip Resistor, 4.7 kohm, ± 1%, 62.5 mW, 0402 [1005 Metric], Thick Film, General Purpose")
    (property "ki_keywords" "0402, SMT, RESISTOR, PASSIVE")
    (attr smd)
    (fp_text reference "R23" (at -2.95 0.061666 90) (layer "B.SilkS")
        (effects (font (size 0.7 0.7) (thickness 0.127)) (justify mirror))
    )
    (fp_text value "R_4k7_0402" (at 0 -1.17 90) (layer "B.Fab")
        (effects (font (size 1 1) (thickness 0.15)) (justify mirror))
    )
    (fp_text user "${REFERENCE}" (at 0 0 90) (layer "B.Fab")
        (effects (font (size 0.25 0.25) (thickness 0.04)) (justify mirror))
    )
    (fp_text user "Author: Antmicro" (at -0.95 -4.169 270) (layer "B.Fab") hide
        (effects (font (size 0.7 0.7) (thickness 0.15)) (justify left bottom mirror))
    )
    (fp_text user "License: Apache-2.0" (at -0.95 -5.169 270) (layer "B.Fab") hide
        (effects (font (size 0.7 0.7) (thickness 0.15)) (justify left bottom mirror))
    )
    (fp_rect (start -0.925 0.47) (end 0.925 -0.47)
      (stroke (width 0.05) (type default)) (fill none) (layer "B.CrtYd"))
    (fp_rect (start -0.5 0.25) (end 0.5 -0.25)
      (stroke (width 0.15) (type solid)) (fill none) (layer "B.Fab"))
    (pad "1" smd roundrect (at -0.48 0 90) (size 0.59 0.64) (layers "B.Cu" "B.Paste" "B.Mask") (roundrect_rratio 0.25)
      (net 2 "VCC3V3") (pintype "passive"))
    (pad "2" smd roundrect (at 0.48 0 90) (size 0.59 0.64) (layers "B.Cu" "B.Paste" "B.Mask") (roundrect_rratio 0.25)
      (net 145 "QSPIA2_CS_N") (pintype "passive"))
  )

  (footprint "antmicro-footprints:R_0402_1005Metric" (layer "B.Cu")
    (at 80.975 147.8 90)
    (descr "Resistor SMD 0402")
    (tags "resistor SMD 0402")
    (property "Author" "Antmicro")
    (property "License" "Apache-2.0")
    (property "MPN" "CR0402-FX-1001GLF")
    (property "Manufacturer" "Bourns")
    (property "Public" "False")
    (property "Sheetfile" "rot.kicad_sch")
    (property "Sheetname" "RoT")
    (property "Tolerance" "1%")
    (property "Val" "1k")
    (property "ki_description" "SMD Chip Resistor, 1 kohm, ± 1%, 63 mW, 0402 [1005 Metric], Thick Film, General Purpose")
    (property "ki_keywords" "0402, SMT, RESISTOR, PASSIVE")
    (attr smd)
    (fp_text reference "R25" (at -2.75 1.225 270) (layer "B.SilkS")
        (effects (font (size 0.7 0.7) (thickness 0.127)) (justify mirror))
    )
    (fp_text value "R_1k_0402" (at 0 -1.17 270) (layer "B.Fab")
        (effects (font (size 1 1) (thickness 0.15)) (justify mirror))
    )
    (fp_text user "${REFERENCE}" (at 0 0 270) (layer "B.Fab")
        (effects (font (size 0.25 0.25) (thickness 0.04)) (justify mirror))
    )
    (fp_text user "Author: Antmicro" (at -0.95 -4.169 270) (layer "B.Fab") hide
        (effects (font (size 0.7 0.7) (thickness 0.15)) (justify left bottom mirror))
    )
    (fp_text user "License: Apache-2.0" (at -0.95 -5.169 270) (layer "B.Fab") hide
        (effects (font (size 0.7 0.7) (thickness 0.15)) (justify left bottom mirror))
    )
    (fp_rect (start -0.925 0.47) (end 0.925 -0.47)
      (stroke (width 0.05) (type default)) (fill none) (layer "B.CrtYd"))
    (fp_rect (start -0.5 0.25) (end 0.5 -0.25)
      (stroke (width 0.15) (type solid)) (fill none) (layer "B.Fab"))
    (pad "1" smd roundrect (at -0.48 0 90) (size 0.59 0.64) (layers "B.Cu" "B.Paste" "B.Mask") (roundrect_rratio 0.25)
      (net 2 "VCC3V3") (pintype "passive"))
    (pad "2" smd roundrect (at 0.48 0 90) (size 0.59 0.64) (layers "B.Cu" "B.Paste" "B.Mask") (roundrect_rratio 0.25)
      (net 124 "QSPIB_CLK") (pintype "passive"))
  )

  (footprint "antmicro-footprints:R_0402_1005Metric" (layer "B.Cu")
    (at 69.725 138.85 90)
    (descr "Resistor SMD 0402")
    (tags "resistor SMD 0402")
    (property "Author" "Antmicro")
    (property "License" "Apache-2.0")
    (property "MPN" "CR0402-FX-1001GLF")
    (property "Manufacturer" "Bourns")
    (property "Public" "False")
    (property "Sheetfile" "rot.kicad_sch")
    (property "Sheetname" "RoT")
    (property "Tolerance" "1%")
    (property "Val" "1k")
    (property "ki_description" "SMD Chip Resistor, 1 kohm, ± 1%, 63 mW, 0402 [1005 Metric], Thick Film, General Purpose")
    (property "ki_keywords" "0402, SMT, RESISTOR, PASSIVE")
    (attr smd)
    (fp_text reference "R27" (at -2.95 0.243332 90) (layer "B.SilkS")
        (effects (font (size 0.7 0.7) (thickness 0.127)) (justify mirror))
    )
    (fp_text value "R_1k_0402" (at 0 -1.17 90) (layer "B.Fab")
        (effects (font (size 1 1) (thickness 0.15)) (justify mirror))
    )
    (fp_text user "License: Apache-2.0" (at -0.95 -5.169 270) (layer "B.Fab") hide
        (effects (font (size 0.7 0.7) (thickness 0.15)) (justify left bottom mirror))
    )
    (fp_text user "Author: Antmicro" (at -0.95 -4.169 270) (layer "B.Fab") hide
        (effects (font (size 0.7 0.7) (thickness 0.15)) (justify left bottom mirror))
    )
    (fp_text user "${REFERENCE}" (at 0 0 90) (layer "B.Fab")
        (effects (font (size 0.25 0.25) (thickness 0.04)) (justify mirror))
    )
    (fp_rect (start -0.925 0.47) (end 0.925 -0.47)
      (stroke (width 0.05) (type default)) (fill none) (layer "B.CrtYd"))
    (fp_rect (start -0.5 0.25) (end 0.5 -0.25)
      (stroke (width 0.15) (type solid)) (fill none) (layer "B.Fab"))
    (pad "1" smd roundrect (at -0.48 0 90) (size 0.59 0.64) (layers "B.Cu" "B.Paste" "B.Mask") (roundrect_rratio 0.25)
      (net 2 "VCC3V3") (pintype "passive"))
    (pad "2" smd roundrect (at 0.48 0 90) (size 0.59 0.64) (layers "B.Cu" "B.Paste" "B.Mask") (roundrect_rratio 0.25)
      (net 135 "QSPIA_CLK") (pintype "passive"))
  )

  (footprint "antmicro-footprints:R_0402_1005Metric" (layer "B.Cu")
    (at 81.975 147.8 -90)
    (descr "Resistor SMD 0402")
    (tags "resistor SMD 0402")
    (property "Author" "Antmicro")
    (property "License" "Apache-2.0")
    (property "MPN" "CR0402-FX-1002GLF")
    (property "Manufacturer" "Bourns")
    (property "Public" "False")
    (property "Sheetfile" "rot.kicad_sch")
    (property "Sheetname" "RoT")
    (property "Tolerance" "1%")
    (property "Val" "10k")
    (property "ki_description" "SMD Chip Resistor, 10 kohm, ± 1%, 62.5 mW, 0402 [1005 Metric], Thick Film, General Purpose")
    (property "ki_keywords" "0402, SMT, RESISTOR, PASSIVE")
    (attr smd)
    (fp_text reference "R29" (at 2.75 0.825 -90) (layer "B.SilkS")
        (effects (font (size 0.7 0.7) (thickness 0.127)) (justify mirror))
    )
    (fp_text value "R_10k_0402" (at 0 -1.17 -90) (layer "B.Fab")
        (effects (font (size 1 1) (thickness 0.15)) (justify mirror))
    )
    (fp_text user "${REFERENCE}" (at 0 0 -90) (layer "B.Fab")
        (effects (font (size 0.25 0.25) (thickness 0.04)) (justify mirror))
    )
    (fp_text user "Author: Antmicro" (at -0.95 -4.169 90) (layer "B.Fab") hide
        (effects (font (size 0.7 0.7) (thickness 0.15)) (justify left bottom mirror))
    )
    (fp_text user "License: Apache-2.0" (at -0.95 -5.169 90) (layer "B.Fab") hide
        (effects (font (size 0.7 0.7) (thickness 0.15)) (justify left bottom mirror))
    )
    (fp_rect (start -0.925 0.47) (end 0.925 -0.47)
      (stroke (width 0.05) (type default)) (fill none) (layer "B.CrtYd"))
    (fp_rect (start -0.5 0.25) (end 0.5 -0.25)
      (stroke (width 0.15) (type solid)) (fill none) (layer "B.Fab"))
    (pad "1" smd roundrect (at -0.48 0 270) (size 0.59 0.64) (layers "B.Cu" "B.Paste" "B.Mask") (roundrect_rratio 0.25)
      (net 130 "QSPIB2_D0") (pintype "passive"))
    (pad "2" smd roundrect (at 0.48 0 270) (size 0.59 0.64) (layers "B.Cu" "B.Paste" "B.Mask") (roundrect_rratio 0.25)
      (net 2 "VCC3V3") (pintype "passive"))
  )

  (footprint "antmicro-footprints:R_0402_1005Metric" (layer "B.Cu")
    (at 70.725 138.835 -90)
    (descr "Resistor SMD 0402")
    (tags "resistor SMD 0402")
    (property "Author" "Antmicro")
    (property "License" "Apache-2.0")
    (property "MPN" "CR0402-FX-1002GLF")
    (property "Manufacturer" "Bourns")
    (property "Public" "False")
    (property "Sheetfile" "rot.kicad_sch")
    (property "Sheetname" "RoT")
    (property "Tolerance" "1%")
    (property "Val" "10k")
    (property "ki_description" "SMD Chip Resistor, 10 kohm, ± 1%, 62.5 mW, 0402 [1005 Metric], Thick Film, General Purpose")
    (property "ki_keywords" "0402, SMT, RESISTOR, PASSIVE")
    (attr smd)
    (fp_text reference "R31" (at 2.965 -0.334165 90) (layer "B.SilkS")
        (effects (font (size 0.7 0.7) (thickness 0.127)) (justify mirror))
    )
    (fp_text value "R_10k_0402" (at 0 -1.17 90) (layer "B.Fab")
        (effects (font (size 1 1) (thickness 0.15)) (justify mirror))
    )
    (fp_text user "License: Apache-2.0" (at -0.95 -5.169 90) (layer "B.Fab") hide
        (effects (font (size 0.7 0.7) (thickness 0.15)) (justify left bottom mirror))
    )
    (fp_text user "${REFERENCE}" (at 0 0 90) (layer "B.Fab")
        (effects (font (size 0.25 0.25) (thickness 0.04)) (justify mirror))
    )
    (fp_text user "Author: Antmicro" (at -0.95 -4.169 90) (layer "B.Fab") hide
        (effects (font (size 0.7 0.7) (thickness 0.15)) (justify left bottom mirror))
    )
    (fp_rect (start -0.925 0.47) (end 0.925 -0.47)
      (stroke (width 0.05) (type default)) (fill none) (layer "B.CrtYd"))
    (fp_rect (start -0.5 0.25) (end 0.5 -0.25)
      (stroke (width 0.15) (type solid)) (fill none) (layer "B.Fab"))
    (pad "1" smd roundrect (at -0.48 0 270) (size 0.59 0.64) (layers "B.Cu" "B.Paste" "B.Mask") (roundrect_rratio 0.25)
      (net 141 "QSPIA2_D0") (pintype "passive"))
    (pad "2" smd roundrect (at 0.48 0 270) (size 0.59 0.64) (layers "B.Cu" "B.Paste" "B.Mask") (roundrect_rratio 0.25)
      (net 2 "VCC3V3") (pintype "passive"))
  )

  (footprint "antmicro-footprints:R_0402_1005Metric" (layer "B.Cu")
    (at 76.975 147.8 -90)
    (descr "Resistor SMD 0402")
    (tags "resistor SMD 0402")
    (property "Author" "Antmicro")
    (property "License" "Apache-2.0")
    (property "MPN" "CR0402-FX-1002GLF")
    (property "Manufacturer" "Bourns")
    (property "Public" "False")
    (property "Sheetfile" "rot.kicad_sch")
    (property "Sheetname" "RoT")
    (property "Tolerance" "1%")
    (property "Val" "10k")
    (property "ki_description" "SMD Chip Resistor, 10 kohm, ± 1%, 62.5 mW, 0402 [1005 Metric], Thick Film, General Purpose")
    (property "ki_keywords" "0402, SMT, RESISTOR, PASSIVE")
    (attr smd)
    (fp_text reference "R33" (at 2.75 0.025 -90) (layer "B.SilkS")
        (effects (font (size 0.7 0.7) (thickness 0.127)) (justify mirror))
    )
    (fp_text value "R_10k_0402" (at 0 -1.17 -90) (layer "B.Fab")
        (effects (font (size 1 1) (thickness 0.15)) (justify mirror))
    )
    (fp_text user "${REFERENCE}" (at 0 0 -90) (layer "B.Fab")
        (effects (font (size 0.25 0.25) (thickness 0.04)) (justify mirror))
    )
    (fp_text user "Author: Antmicro" (at -0.95 -4.169 90) (layer "B.Fab") hide
        (effects (font (size 0.7 0.7) (thickness 0.15)) (justify left bottom mirror))
    )
    (fp_text user "License: Apache-2.0" (at -0.95 -5.169 90) (layer "B.Fab") hide
        (effects (font (size 0.7 0.7) (thickness 0.15)) (justify left bottom mirror))
    )
    (fp_rect (start -0.925 0.47) (end 0.925 -0.47)
      (stroke (width 0.05) (type default)) (fill none) (layer "B.CrtYd"))
    (fp_rect (start -0.5 0.25) (end 0.5 -0.25)
      (stroke (width 0.15) (type solid)) (fill none) (layer "B.Fab"))
    (pad "1" smd roundrect (at -0.48 0 270) (size 0.59 0.64) (layers "B.Cu" "B.Paste" "B.Mask") (roundrect_rratio 0.25)
      (net 132 "QSPIB2_D2") (pintype "passive"))
    (pad "2" smd roundrect (at 0.48 0 270) (size 0.59 0.64) (layers "B.Cu" "B.Paste" "B.Mask") (roundrect_rratio 0.25)
      (net 2 "VCC3V3") (pintype "passive"))
  )

  (footprint "antmicro-footprints:R_0402_1005Metric" (layer "B.Cu")
    (at 65.725 138.85 -90)
    (descr "Resistor SMD 0402")
    (tags "resistor SMD 0402")
    (property "Author" "Antmicro")
    (property "License" "Apache-2.0")
    (property "MPN" "CR0402-FX-1002GLF")
    (property "Manufacturer" "Bourns")
    (property "Public" "False")
    (property "Sheetfile" "rot.kicad_sch")
    (property "Sheetname" "RoT")
    (property "Tolerance" "1%")
    (property "Val" "10k")
    (property "ki_description" "SMD Chip Resistor, 10 kohm, ± 1%, 62.5 mW, 0402 [1005 Metric], Thick Film, General Purpose")
    (property "ki_keywords" "0402, SMT, RESISTOR, PASSIVE")
    (attr smd)
    (fp_text reference "R35" (at 2.95 0.12 90) (layer "B.SilkS")
        (effects (font (size 0.7 0.7) (thickness 0.127)) (justify mirror))
    )
    (fp_text value "R_10k_0402" (at 0 -1.17 90) (layer "B.Fab")
        (effects (font (size 1 1) (thickness 0.15)) (justify mirror))
    )
    (fp_text user "${REFERENCE}" (at 0 0 90) (layer "B.Fab")
        (effects (font (size 0.25 0.25) (thickness 0.04)) (justify mirror))
    )
    (fp_text user "Author: Antmicro" (at -0.95 -4.169 90) (layer "B.Fab") hide
        (effects (font (size 0.7 0.7) (thickness 0.15)) (justify left bottom mirror))
    )
    (fp_text user "License: Apache-2.0" (at -0.95 -5.169 90) (layer "B.Fab") hide
        (effects (font (size 0.7 0.7) (thickness 0.15)) (justify left bottom mirror))
    )
    (fp_rect (start -0.925 0.47) (end 0.925 -0.47)
      (stroke (width 0.05) (type default)) (fill none) (layer "B.CrtYd"))
    (fp_rect (start -0.5 0.25) (end 0.5 -0.25)
      (stroke (width 0.15) (type solid)) (fill none) (layer "B.Fab"))
    (pad "1" smd roundrect (at -0.48 0 270) (size 0.59 0.64) (layers "B.Cu" "B.Paste" "B.Mask") (roundrect_rratio 0.25)
      (net 143 "QSPIA2_D2") (pintype "passive"))
    (pad "2" smd roundrect (at 0.48 0 270) (size 0.59 0.64) (layers "B.Cu" "B.Paste" "B.Mask") (roundrect_rratio 0.25)
      (net 2 "VCC3V3") (pintype "passive"))
  )

  (footprint "antmicro-footprints:R_0402_1005Metric" (layer "B.Cu")
    (at 79.975 147.8 -90)
    (descr "Resistor SMD 0402")
    (tags "resistor SMD 0402")
    (property "Author" "Antmicro")
    (property "License" "Apache-2.0")
    (property "MPN" "CR0402-FX-1002GLF")
    (property "Manufacturer" "Bourns")
    (property "Public" "False")
    (property "Sheetfile" "rot.kicad_sch")
    (property "Sheetname" "RoT")
    (property "Tolerance" "1%")
    (property "Val" "10k")
    (property "ki_description" "SMD Chip Resistor, 10 kohm, ± 1%, 62.5 mW, 0402 [1005 Metric], Thick Film, General Purpose")
    (property "ki_keywords" "0402, SMT, RESISTOR, PASSIVE")
    (attr smd)
    (fp_text reference "R37" (at 2.75 0.925 -90) (layer "B.SilkS")
        (effects (font (size 0.7 0.7) (thickness 0.127)) (justify mirror))
    )
    (fp_text value "R_10k_0402" (at 0 -1.17 -90) (layer "B.Fab")
        (effects (font (size 1 1) (thickness 0.15)) (justify mirror))
    )
    (fp_text user "Author: Antmicro" (at -0.95 -4.169 90) (layer "B.Fab") hide
        (effects (font (size 0.7 0.7) (thickness 0.15)) (justify left bottom mirror))
    )
    (fp_text user "License: Apache-2.0" (at -0.95 -5.169 90) (layer "B.Fab") hide
        (effects (font (size 0.7 0.7) (thickness 0.15)) (justify left bottom mirror))
    )
    (fp_text user "${REFERENCE}" (at 0 0 -90) (layer "B.Fab")
        (effects (font (size 0.25 0.25) (thickness 0.04)) (justify mirror))
    )
    (fp_rect (start -0.925 0.47) (end 0.925 -0.47)
      (stroke (width 0.05) (type default)) (fill none) (layer "B.CrtYd"))
    (fp_rect (start -0.5 0.25) (end 0.5 -0.25)
      (stroke (width 0.15) (type solid)) (fill none) (layer "B.Fab"))
    (pad "1" smd roundrect (at -0.48 0 270) (size 0.59 0.64) (layers "B.Cu" "B.Paste" "B.Mask") (roundrect_rratio 0.25)
      (net 133 "QSPIB2_D3") (pintype "passive"))
    (pad "2" smd roundrect (at 0.48 0 270) (size 0.59 0.64) (layers "B.Cu" "B.Paste" "B.Mask") (roundrect_rratio 0.25)
      (net 2 "VCC3V3") (pintype "passive"))
  )

  (footprint "antmicro-footprints:R_0402_1005Metric" (layer "B.Cu")
    (at 68.725 138.85 -90)
    (descr "Resistor SMD 0402")
    (tags "resistor SMD 0402")
    (property "Author" "Antmicro")
    (property "License" "Apache-2.0")
    (property "MPN" "CR0402-FX-1002GLF")
    (property "Manufacturer" "Bourns")
    (property "Public" "False")
    (property "Sheetfile" "rot.kicad_sch")
    (property "Sheetname" "RoT")
    (property "Tolerance" "1%")
    (property "Val" "10k")
    (property "ki_description" "SMD Chip Resistor, 10 kohm, ± 1%, 62.5 mW, 0402 [1005 Metric], Thick Film, General Purpose")
    (property "ki_keywords" "0402, SMT, RESISTOR, PASSIVE")
    (attr smd)
    (fp_text reference "R39" (at 2.95 -0.152499 90) (layer "B.SilkS")
        (effects (font (size 0.7 0.7) (thickness 0.127)) (justify mirror))
    )
    (fp_text value "R_10k_0402" (at 0 -1.17 90) (layer "B.Fab")
        (effects (font (size 1 1) (thickness 0.15)) (justify mirror))
    )
    (fp_text user "Author: Antmicro" (at -0.95 -4.169 90) (layer "B.Fab") hide
        (effects (font (size 0.7 0.7) (thickness 0.15)) (justify left bottom mirror))
    )
    (fp_text user "${REFERENCE}" (at 0 0 90) (layer "B.Fab")
        (effects (font (size 0.25 0.25) (thickness 0.04)) (justify mirror))
    )
    (fp_text user "License: Apache-2.0" (at -0.95 -5.169 90) (layer "B.Fab") hide
        (effects (font (size 0.7 0.7) (thickness 0.15)) (justify left bottom mirror))
    )
    (fp_rect (start -0.925 0.47) (end 0.925 -0.47)
      (stroke (width 0.05) (type default)) (fill none) (layer "B.CrtYd"))
    (fp_rect (start -0.5 0.25) (end 0.5 -0.25)
      (stroke (width 0.15) (type solid)) (fill none) (layer "B.Fab"))
    (pad "1" smd roundrect (at -0.48 0 270) (size 0.59 0.64) (layers "B.Cu" "B.Paste" "B.Mask") (roundrect_rratio 0.25)
      (net 144 "QSPIA2_D3") (pintype "passive"))
    (pad "2" smd roundrect (at 0.48 0 270) (size 0.59 0.64) (layers "B.Cu" "B.Paste" "B.Mask") (roundrect_rratio 0.25)
      (net 2 "VCC3V3") (pintype "passive"))
  )

  (footprint "antmicro-footprints:R_0402_1005Metric" (layer "B.Cu")
    (at 77.975 147.8 -90)
    (descr "Resistor SMD 0402")
    (tags "resistor SMD 0402")
    (property "Author" "Antmicro")
    (property "License" "Apache-2.0")
    (property "MPN" "CR0402-FX-1002GLF")
    (property "Manufacturer" "Bourns")
    (property "Public" "False")
    (property "Sheetfile" "rot.kicad_sch")
    (property "Sheetname" "RoT")
    (property "Tolerance" "1%")
    (property "Val" "10k")
    (property "ki_description" "SMD Chip Resistor, 10 kohm, ± 1%, 62.5 mW, 0402 [1005 Metric], Thick Film, General Purpose")
    (property "ki_keywords" "0402, SMT, RESISTOR, PASSIVE")
    (attr smd)
    (fp_text reference "R41" (at 2.75 -0.025 -90) (layer "B.SilkS")
        (effects (font (size 0.7 0.7) (thickness 0.127)) (justify mirror))
    )
    (fp_text value "R_10k_0402" (at 0 -1.17 -90) (layer "B.Fab")
        (effects (font (size 1 1) (thickness 0.15)) (justify mirror))
    )
    (fp_text user "License: Apache-2.0" (at -0.95 -5.169 90) (layer "B.Fab") hide
        (effects (font (size 0.7 0.7) (thickness 0.15)) (justify left bottom mirror))
    )
    (fp_text user "${REFERENCE}" (at 0 0 -90) (layer "B.Fab")
        (effects (font (size 0.25 0.25) (thickness 0.04)) (justify mirror))
    )
    (fp_text user "Author: Antmicro" (at -0.95 -4.169 90) (layer "B.Fab") hide
        (effects (font (size 0.7 0.7) (thickness 0.15)) (justify left bottom mirror))
    )
    (fp_rect (start -0.925 0.47) (end 0.925 -0.47)
      (stroke (width 0.05) (type default)) (fill none) (layer "B.CrtYd"))
    (fp_rect (start -0.5 0.25) (end 0.5 -0.25)
      (stroke (width 0.15) (type solid)) (fill none) (layer "B.Fab"))
    (pad "1" smd roundrect (at -0.48 0 270) (size 0.59 0.64) (layers "B.Cu" "B.Paste" "B.Mask") (roundrect_rratio 0.25)
      (net 131 "QSPIB2_D1") (pintype "passive"))
    (pad "2" smd roundrect (at 0.48 0 270) (size 0.59 0.64) (layers "B.Cu" "B.Paste" "B.Mask") (roundrect_rratio 0.25)
      (net 2 "VCC3V3") (pintype "passive"))
  )

  (footprint "antmicro-footprints:R_0402_1005Metric" (layer "B.Cu")
    (at 66.725 138.85 -90)
    (descr "Resistor SMD 0402")
    (tags "resistor SMD 0402")
    (property "Author" "Antmicro")
    (property "License" "Apache-2.0")
    (property "MPN" "CR0402-FX-1002GLF")
    (property "Manufacturer" "Bourns")
    (property "Public" "False")
    (property "Sheetfile" "rot.kicad_sch")
    (property "Sheetname" "RoT")
    (property "Tolerance" "1%")
    (property "Val" "10k")
    (property "ki_description" "SMD Chip Resistor, 10 kohm, ± 1%, 62.5 mW, 0402 [1005 Metric], Thick Film, General Purpose")
    (property "ki_keywords" "0402, SMT, RESISTOR, PASSIVE")
    (attr smd)
    (fp_text reference "R43" (at 2.95 0.029167 90) (layer "B.SilkS")
        (effects (font (size 0.7 0.7) (thickness 0.127)) (justify mirror))
    )
    (fp_text value "R_10k_0402" (at 0 -1.17 90) (layer "B.Fab")
        (effects (font (size 1 1) (thickness 0.15)) (justify mirror))
    )
    (fp_text user "${REFERENCE}" (at 0 0 90) (layer "B.Fab")
        (effects (font (size 0.25 0.25) (thickness 0.04)) (justify mirror))
    )
    (fp_text user "Author: Antmicro" (at -0.95 -4.169 90) (layer "B.Fab") hide
        (effects (font (size 0.7 0.7) (thickness 0.15)) (justify left bottom mirror))
    )
    (fp_text user "License: Apache-2.0" (at -0.95 -5.169 90) (layer "B.Fab") hide
        (effects (font (size 0.7 0.7) (thickness 0.15)) (justify left bottom mirror))
    )
    (fp_rect (start -0.925 0.47) (end 0.925 -0.47)
      (stroke (width 0.05) (type default)) (fill none) (layer "B.CrtYd"))
    (fp_rect (start -0.5 0.25) (end 0.5 -0.25)
      (stroke (width 0.15) (type solid)) (fill none) (layer "B.Fab"))
    (pad "1" smd roundrect (at -0.48 0 270) (size 0.59 0.64) (layers "B.Cu" "B.Paste" "B.Mask") (roundrect_rratio 0.25)
      (net 142 "QSPIA2_D1") (pintype "passive"))
    (pad "2" smd roundrect (at 0.48 0 270) (size 0.59 0.64) (layers "B.Cu" "B.Paste" "B.Mask") (roundrect_rratio 0.25)
      (net 2 "VCC3V3") (pintype "passive"))
  )

  (footprint "antmicro-footprints:C_0402_1005Metric" (layer "B.Cu")
    (at 71.9 138.815 -90)
    (descr "Capacitor SMD 0402")
    (tags "capacitor SMD 0402")
    (property "Author" "Antmicro")
    (property "Dielectric" "")
    (property "License" "Apache-2.0")
    (property "MPN" "C1005X5R1E474M050BB")
    (property "Manufacturer" "TDK")
    (property "Public" "False")
    (property "Sheetfile" "rot.kicad_sch")
    (property "Sheetname" "RoT")
    (property "Val" "470n")
    (property "Voltage" "")
    (property "ki_description" "SMD Multilayer Ceramic Capacitor, 0.47 µF, 25 V, 0402 [1005 Metric], ± 20%, X5R, C")
    (property "ki_keywords" "0402, SMT, CAPACITOR, PASSIVE, CERAMIC, MLCC")
    (attr smd)
    (fp_text reference "C46" (at -2.985 0.249998 90) (layer "B.SilkS")
        (effects (font (size 0.7 0.7) (thickness 0.127)) (justify mirror))
    )
    (fp_text value "C_470n_0402" (at 0 -1.17 90) (layer "B.Fab")
        (effects (font (size 1 1) (thickness 0.15)) (justify mirror))
    )
    (fp_text user "License: Apache-2.0" (at -0.939 -5.799 90) (layer "B.Fab") hide
        (effects (font (size 0.7 0.7) (thickness 0.15)) (justify left bottom mirror))
    )
    (fp_text user "${REFERENCE}" (at 0 0 90) (layer "B.Fab")
        (effects (font (size 0.25 0.25) (thickness 0.04)) (justify mirror))
    )
    (fp_text user "Author: Antmicro" (at -0.939 -3.399 90) (layer "B.Fab") hide
        (effects (font (size 0.7 0.7) (thickness 0.15)) (justify left bottom mirror))
    )
    (fp_rect (start -0.925 0.47) (end 0.925 -0.47)
      (stroke (width 0.05) (type default)) (fill none) (layer "B.CrtYd"))
    (fp_line (start -0.494 -0.248) (end -0.494 0.25)
      (stroke (width 0.15) (type solid)) (layer "B.Fab"))
    (fp_line (start -0.494 0.25) (end 0.504 0.25)
      (stroke (width 0.15) (type solid)) (layer "B.Fab"))
    (fp_line (start 0.504 -0.248) (end -0.494 -0.248)
      (stroke (width 0.15) (type solid)) (layer "B.Fab"))
    (fp_line (start 0.504 0.25) (end 0.504 -0.248)
      (stroke (width 0.15) (type solid)) (layer "B.Fab"))
    (pad "1" smd roundrect (at -0.48 0 270) (size 0.59 0.64) (layers "B.Cu" "B.Paste" "B.Mask") (roundrect_rratio 0.25)
      (net 1 "GND") (pintype "passive"))
    (pad "2" smd roundrect (at 0.48 0 270) (size 0.59 0.64) (layers "B.Cu" "B.Paste" "B.Mask") (roundrect_rratio 0.25)
      (net 2 "VCC3V3") (pintype "passive"))
  )

  (footprint "antmicro-footprints:R_0402_1005Metric" (layer "B.Cu")
    (at 67.725 147.8 90)
    (descr "Resistor SMD 0402")
    (tags "resistor SMD 0402")
    (property "Author" "Antmicro")
    (property "License" "Apache-2.0")
    (property "MPN" "CR0402-FX-4701GLF")
    (property "Manufacturer" "Bourns")
    (property "Public" "False")
    (property "Sheetfile" "rot.kicad_sch")
    (property "Sheetname" "RoT")
    (property "Tolerance" "1%")
    (property "Val" "4k7")
    (property "ki_description" "SMD Chip Resistor, 4.7 kohm, ± 1%, 62.5 mW, 0402 [1005 Metric], Thick Film, General Purpose")
    (property "ki_keywords" "0402, SMT, RESISTOR, PASSIVE")
    (attr smd)
    (fp_text reference "R24" (at -2.65 0.048 90) (layer "B.SilkS")
        (effects (font (size 0.7 0.7) (thickness 0.127)) (justify mirror))
    )
    (fp_text value "R_4k7_0402" (at 0 -1.17 90) (layer "B.Fab")
        (effects (font (size 1 1) (thickness 0.15)) (justify mirror))
    )
    (fp_text user "License: Apache-2.0" (at -0.95 -5.169 270) (layer "B.Fab") hide
        (effects (font (size 0.7 0.7) (thickness 0.15)) (justify left bottom mirror))
    )
    (fp_text user "${REFERENCE}" (at 0 0 90) (layer "B.Fab")
        (effects (font (size 0.25 0.25) (thickness 0.04)) (justify mirror))
    )
    (fp_text user "Author: Antmicro" (at -0.95 -4.169 270) (layer "B.Fab") hide
        (effects (font (size 0.7 0.7) (thickness 0.15)) (justify left bottom mirror))
    )
    (fp_rect (start -0.925 0.47) (end 0.925 -0.47)
      (stroke (width 0.05) (type default)) (fill none) (layer "B.CrtYd"))
    (fp_rect (start -0.5 0.25) (end 0.5 -0.25)
      (stroke (width 0.15) (type solid)) (fill none) (layer "B.Fab"))
    (pad "1" smd roundrect (at -0.48 0 90) (size 0.59 0.64) (layers "B.Cu" "B.Paste" "B.Mask") (roundrect_rratio 0.25)
      (net 2 "VCC3V3") (pintype "passive"))
    (pad "2" smd roundrect (at 0.48 0 90) (size 0.59 0.64) (layers "B.Cu" "B.Paste" "B.Mask") (roundrect_rratio 0.25)
      (net 140 "QSPIA1_CS_N") (pintype "passive"))
  )

  (footprint "antmicro-footprints:R_0402_1005Metric" (layer "B.Cu")
    (at 69.725 147.8 90)
    (descr "Resistor SMD 0402")
    (tags "resistor SMD 0402")
    (property "Author" "Antmicro")
    (property "License" "Apache-2.0")
    (property "MPN" "CR0402-FX-1001GLF")
    (property "Manufacturer" "Bourns")
    (property "Public" "False")
    (property "Sheetfile" "rot.kicad_sch")
    (property "Sheetname" "RoT")
    (property "Tolerance" "1%")
    (property "Val" "1k")
    (property "ki_description" "SMD Chip Resistor, 1 kohm, ± 1%, 63 mW, 0402 [1005 Metric], Thick Film, General Purpose")
    (property "ki_keywords" "0402, SMT, RESISTOR, PASSIVE")
    (attr smd)
    (fp_text reference "R28" (at -2.65 0.066 90) (layer "B.SilkS")
        (effects (font (size 0.7 0.7) (thickness 0.127)) (justify mirror))
    )
    (fp_text value "R_1k_0402" (at 0 -1.17 90) (layer "B.Fab")
        (effects (font (size 1 1) (thickness 0.15)) (justify mirror))
    )
    (fp_text user "${REFERENCE}" (at 0 0 90) (layer "B.Fab")
        (effects (font (size 0.25 0.25) (thickness 0.04)) (justify mirror))
    )
    (fp_text user "License: Apache-2.0" (at -0.95 -5.169 270) (layer "B.Fab") hide
        (effects (font (size 0.7 0.7) (thickness 0.15)) (justify left bottom mirror))
    )
    (fp_text user "Author: Antmicro" (at -0.95 -4.169 270) (layer "B.Fab") hide
        (effects (font (size 0.7 0.7) (thickness 0.15)) (justify left bottom mirror))
    )
    (fp_rect (start -0.925 0.47) (end 0.925 -0.47)
      (stroke (width 0.05) (type default)) (fill none) (layer "B.CrtYd"))
    (fp_rect (start -0.5 0.25) (end 0.5 -0.25)
      (stroke (width 0.15) (type solid)) (fill none) (layer "B.Fab"))
    (pad "1" smd roundrect (at -0.48 0 90) (size 0.59 0.64) (layers "B.Cu" "B.Paste" "B.Mask") (roundrect_rratio 0.25)
      (net 2 "VCC3V3") (pintype "passive"))
    (pad "2" smd roundrect (at 0.48 0 90) (size 0.59 0.64) (layers "B.Cu" "B.Paste" "B.Mask") (roundrect_rratio 0.25)
      (net 135 "QSPIA_CLK") (pintype "passive"))
  )

  (footprint "antmicro-footprints:R_0402_1005Metric" (layer "B.Cu")
    (at 70.725 147.8 -90)
    (descr "Resistor SMD 0402")
    (tags "resistor SMD 0402")
    (property "Author" "Antmicro")
    (property "License" "Apache-2.0")
    (property "MPN" "CR0402-FX-1002GLF")
    (property "Manufacturer" "Bourns")
    (property "Public" "False")
    (property "Sheetfile" "rot.kicad_sch")
    (property "Sheetname" "RoT")
    (property "Tolerance" "1%")
    (property "Val" "10k")
    (property "ki_description" "SMD Chip Resistor, 10 kohm, ± 1%, 62.5 mW, 0402 [1005 Metric], Thick Film, General Purpose")
    (property "ki_keywords" "0402, SMT, RESISTOR, PASSIVE")
    (attr smd)
    (fp_text reference "R32" (at 2.65 -0.075 90) (layer "B.SilkS")
        (effects (font (size 0.7 0.7) (thickness 0.127)) (justify mirror))
    )
    (fp_text value "R_10k_0402" (at 0 -1.17 90) (layer "B.Fab")
        (effects (font (size 1 1) (thickness 0.15)) (justify mirror))
    )
    (fp_text user "License: Apache-2.0" (at -0.95 -5.169 90) (layer "B.Fab") hide
        (effects (font (size 0.7 0.7) (thickness 0.15)) (justify left bottom mirror))
    )
    (fp_text user "Author: Antmicro" (at -0.95 -4.169 90) (layer "B.Fab") hide
        (effects (font (size 0.7 0.7) (thickness 0.15)) (justify left bottom mirror))
    )
    (fp_text user "${REFERENCE}" (at 0 0 90) (layer "B.Fab")
        (effects (font (size 0.25 0.25) (thickness 0.04)) (justify mirror))
    )
    (fp_rect (start -0.925 0.47) (end 0.925 -0.47)
      (stroke (width 0.05) (type default)) (fill none) (layer "B.CrtYd"))
    (fp_rect (start -0.5 0.25) (end 0.5 -0.25)
      (stroke (width 0.15) (type solid)) (fill none) (layer "B.Fab"))
    (pad "1" smd roundrect (at -0.48 0 270) (size 0.59 0.64) (layers "B.Cu" "B.Paste" "B.Mask") (roundrect_rratio 0.25)
      (net 136 "QSPIA1_D0") (pintype "passive"))
    (pad "2" smd roundrect (at 0.48 0 270) (size 0.59 0.64) (layers "B.Cu" "B.Paste" "B.Mask") (roundrect_rratio 0.25)
      (net 2 "VCC3V3") (pintype "passive"))
  )

  (footprint "antmicro-footprints:R_0402_1005Metric" (layer "B.Cu")
    (at 65.725 147.8 -90)
    (descr "Resistor SMD 0402")
    (tags "resistor SMD 0402")
    (property "Author" "Antmicro")
    (property "License" "Apache-2.0")
    (property "MPN" "CR0402-FX-1002GLF")
    (property "Manufacturer" "Bourns")
    (property "Public" "False")
    (property "Sheetfile" "rot.kicad_sch")
    (property "Sheetname" "RoT")
    (property "Tolerance" "1%")
    (property "Val" "10k")
    (property "ki_description" "SMD Chip Resistor, 10 kohm, ± 1%, 62.5 mW, 0402 [1005 Metric], Thick Film, General Purpose")
    (property "ki_keywords" "0402, SMT, RESISTOR, PASSIVE")
    (attr smd)
    (fp_text reference "R36" (at 2.65 -0.03 90) (layer "B.SilkS")
        (effects (font (size 0.7 0.7) (thickness 0.127)) (justify mirror))
    )
    (fp_text value "R_10k_0402" (at 0 -1.17 90) (layer "B.Fab")
        (effects (font (size 1 1) (thickness 0.15)) (justify mirror))
    )
    (fp_text user "License: Apache-2.0" (at -0.95 -5.169 90) (layer "B.Fab") hide
        (effects (font (size 0.7 0.7) (thickness 0.15)) (justify left bottom mirror))
    )
    (fp_text user "${REFERENCE}" (at 0 0 90) (layer "B.Fab")
        (effects (font (size 0.25 0.25) (thickness 0.04)) (justify mirror))
    )
    (fp_text user "Author: Antmicro" (at -0.95 -4.169 90) (layer "B.Fab") hide
        (effects (font (size 0.7 0.7) (thickness 0.15)) (justify left bottom mirror))
    )
    (fp_rect (start -0.925 0.47) (end 0.925 -0.47)
      (stroke (width 0.05) (type default)) (fill none) (layer "B.CrtYd"))
    (fp_rect (start -0.5 0.25) (end 0.5 -0.25)
      (stroke (width 0.15) (type solid)) (fill none) (layer "B.Fab"))
    (pad "1" smd roundrect (at -0.48 0 270) (size 0.59 0.64) (layers "B.Cu" "B.Paste" "B.Mask") (roundrect_rratio 0.25)
      (net 138 "QSPIA1_D2") (pintype "passive"))
    (pad "2" smd roundrect (at 0.48 0 270) (size 0.59 0.64) (layers "B.Cu" "B.Paste" "B.Mask") (roundrect_rratio 0.25)
      (net 2 "VCC3V3") (pintype "passive"))
  )

  (footprint "antmicro-footprints:R_0402_1005Metric" (layer "B.Cu")
    (at 68.725 147.8 -90)
    (descr "Resistor SMD 0402")
    (tags "resistor SMD 0402")
    (property "Author" "Antmicro")
    (property "License" "Apache-2.0")
    (property "MPN" "CR0402-FX-1002GLF")
    (property "Manufacturer" "Bourns")
    (property "Public" "False")
    (property "Sheetfile" "rot.kicad_sch")
    (property "Sheetname" "RoT")
    (property "Tolerance" "1%")
    (property "Val" "10k")
    (property "ki_description" "SMD Chip Resistor, 10 kohm, ± 1%, 62.5 mW, 0402 [1005 Metric], Thick Film, General Purpose")
    (property "ki_keywords" "0402, SMT, RESISTOR, PASSIVE")
    (attr smd)
    (fp_text reference "R40" (at 2.65 -0.057 90) (layer "B.SilkS")
        (effects (font (size 0.7 0.7) (thickness 0.127)) (justify mirror))
    )
    (fp_text value "R_10k_0402" (at 0 -1.17 90) (layer "B.Fab")
        (effects (font (size 1 1) (thickness 0.15)) (justify mirror))
    )
    (fp_text user "${REFERENCE}" (at 0 0 90) (layer "B.Fab")
        (effects (font (size 0.25 0.25) (thickness 0.04)) (justify mirror))
    )
    (fp_text user "Author: Antmicro" (at -0.95 -4.169 90) (layer "B.Fab") hide
        (effects (font (size 0.7 0.7) (thickness 0.15)) (justify left bottom mirror))
    )
    (fp_text user "License: Apache-2.0" (at -0.95 -5.169 90) (layer "B.Fab") hide
        (effects (font (size 0.7 0.7) (thickness 0.15)) (justify left bottom mirror))
    )
    (fp_rect (start -0.925 0.47) (end 0.925 -0.47)
      (stroke (width 0.05) (type default)) (fill none) (layer "B.CrtYd"))
    (fp_rect (start -0.5 0.25) (end 0.5 -0.25)
      (stroke (width 0.15) (type solid)) (fill none) (layer "B.Fab"))
    (pad "1" smd roundrect (at -0.48 0 270) (size 0.59 0.64) (layers "B.Cu" "B.Paste" "B.Mask") (roundrect_rratio 0.25)
      (net 139 "QSPIA1_D3") (pintype "passive"))
    (pad "2" smd roundrect (at 0.48 0 270) (size 0.59 0.64) (layers "B.Cu" "B.Paste" "B.Mask") (roundrect_rratio 0.25)
      (net 2 "VCC3V3") (pintype "passive"))
  )

  (footprint "antmicro-footprints:R_0402_1005Metric" (layer "B.Cu")
    (at 66.725 147.8 -90)
    (descr "Resistor SMD 0402")
    (tags "resistor SMD 0402")
    (property "Author" "Antmicro")
    (property "License" "Apache-2.0")
    (property "MPN" "CR0402-FX-1002GLF")
    (property "Manufacturer" "Bourns")
    (property "Public" "False")
    (property "Sheetfile" "rot.kicad_sch")
    (property "Sheetname" "RoT")
    (property "Tolerance" "1%")
    (property "Val" "10k")
    (property "ki_description" "SMD Chip Resistor, 10 kohm, ± 1%, 62.5 mW, 0402 [1005 Metric], Thick Film, General Purpose")
    (property "ki_keywords" "0402, SMT, RESISTOR, PASSIVE")
    (attr smd)
    (fp_text reference "R44" (at 2.65 -0.039 90) (layer "B.SilkS")
        (effects (font (size 0.7 0.7) (thickness 0.127)) (justify mirror))
    )
    (fp_text value "R_10k_0402" (at 0 -1.17 90) (layer "B.Fab")
        (effects (font (size 1 1) (thickness 0.15)) (justify mirror))
    )
    (fp_text user "${REFERENCE}" (at 0 0 90) (layer "B.Fab")
        (effects (font (size 0.25 0.25) (thickness 0.04)) (justify mirror))
    )
    (fp_text user "License: Apache-2.0" (at -0.95 -5.169 90) (layer "B.Fab") hide
        (effects (font (size 0.7 0.7) (thickness 0.15)) (justify left bottom mirror))
    )
    (fp_text user "Author: Antmicro" (at -0.95 -4.169 90) (layer "B.Fab") hide
        (effects (font (size 0.7 0.7) (thickness 0.15)) (justify left bottom mirror))
    )
    (fp_rect (start -0.925 0.47) (end 0.925 -0.47)
      (stroke (width 0.05) (type default)) (fill none) (layer "B.CrtYd"))
    (fp_rect (start -0.5 0.25) (end 0.5 -0.25)
      (stroke (width 0.15) (type solid)) (fill none) (layer "B.Fab"))
    (pad "1" smd roundrect (at -0.48 0 270) (size 0.59 0.64) (layers "B.Cu" "B.Paste" "B.Mask") (roundrect_rratio 0.25)
      (net 137 "QSPIA1_D1") (pintype "passive"))
    (pad "2" smd roundrect (at 0.48 0 270) (size 0.59 0.64) (layers "B.Cu" "B.Paste" "B.Mask") (roundrect_rratio 0.25)
      (net 2 "VCC3V3") (pintype "passive"))
  )

  (footprint "antmicro-footprints:R_0402_1005Metric" (layer "B.Cu")
    (at 78.975 138.8 90)
    (descr "Resistor SMD 0402")
    (tags "resistor SMD 0402")
    (property "Author" "Antmicro")
    (property "License" "Apache-2.0")
    (property "MPN" "CR0402-FX-4701GLF")
    (property "Manufacturer" "Bourns")
    (property "Public" "False")
    (property "Sheetfile" "rot.kicad_sch")
    (property "Sheetname" "RoT")
    (property "Tolerance" "1%")
    (property "Val" "4k7")
    (property "ki_description" "SMD Chip Resistor, 4.7 kohm, ± 1%, 62.5 mW, 0402 [1005 Metric], Thick Film, General Purpose")
    (property "ki_keywords" "0402, SMT, RESISTOR, PASSIVE")
    (attr smd)
    (fp_text reference "R22" (at -3.05 0.278332 90) (layer "B.SilkS")
        (effects (font (size 0.7 0.7) (thickness 0.127)) (justify mirror))
    )
    (fp_text value "R_4k7_0402" (at 0 -1.17 90) (layer "B.Fab")
        (effects (font (size 1 1) (thickness 0.15)) (justify mirror))
    )
    (fp_text user "License: Apache-2.0" (at -0.95 -5.169 270) (layer "B.Fab") hide
        (effects (font (size 0.7 0.7) (thickness 0.15)) (justify left bottom mirror))
    )
    (fp_text user "Author: Antmicro" (at -0.95 -4.169 270) (layer "B.Fab") hide
        (effects (font (size 0.7 0.7) (thickness 0.15)) (justify left bottom mirror))
    )
    (fp_text user "${REFERENCE}" (at 0 0 90) (layer "B.Fab")
        (effects (font (size 0.25 0.25) (thickness 0.04)) (justify mirror))
    )
    (fp_rect (start -0.925 0.47) (end 0.925 -0.47)
      (stroke (width 0.05) (type default)) (fill none) (layer "B.CrtYd"))
    (fp_rect (start -0.5 0.25) (end 0.5 -0.25)
      (stroke (width 0.15) (type solid)) (fill none) (layer "B.Fab"))
    (pad "1" smd roundrect (at -0.48 0 90) (size 0.59 0.64) (layers "B.Cu" "B.Paste" "B.Mask") (roundrect_rratio 0.25)
      (net 2 "VCC3V3") (pintype "passive"))
    (pad "2" smd roundrect (at 0.48 0 90) (size 0.59 0.64) (layers "B.Cu" "B.Paste" "B.Mask") (roundrect_rratio 0.25)
      (net 129 "QSPIB1_CS_N") (pintype "passive"))
  )

  (footprint "antmicro-footprints:R_0402_1005Metric" (layer "B.Cu")
    (at 80.975 138.8 90)
    (descr "Resistor SMD 0402")
    (tags "resistor SMD 0402")
    (property "Author" "Antmicro")
    (property "License" "Apache-2.0")
    (property "MPN" "CR0402-FX-1001GLF")
    (property "Manufacturer" "Bourns")
    (property "Public" "False")
    (property "Sheetfile" "rot.kicad_sch")
    (property "Sheetname" "RoT")
    (property "Tolerance" "1%")
    (property "Val" "1k")
    (property "ki_description" "SMD Chip Resistor, 1 kohm, ± 1%, 63 mW, 0402 [1005 Metric], Thick Film, General Purpose")
    (property "ki_keywords" "0402, SMT, RESISTOR, PASSIVE")
    (attr smd)
    (fp_text reference "R26" (at -3.05 0.326664 90) (layer "B.SilkS")
        (effects (font (size 0.7 0.7) (thickness 0.127)) (justify mirror))
    )
    (fp_text value "R_1k_0402" (at 0 -1.17 90) (layer "B.Fab")
        (effects (font (size 1 1) (thickness 0.15)) (justify mirror))
    )
    (fp_text user "Author: Antmicro" (at -0.95 -4.169 270) (layer "B.Fab") hide
        (effects (font (size 0.7 0.7) (thickness 0.15)) (justify left bottom mirror))
    )
    (fp_text user "License: Apache-2.0" (at -0.95 -5.169 270) (layer "B.Fab") hide
        (effects (font (size 0.7 0.7) (thickness 0.15)) (justify left bottom mirror))
    )
    (fp_text user "${REFERENCE}" (at 0 0 90) (layer "B.Fab")
        (effects (font (size 0.25 0.25) (thickness 0.04)) (justify mirror))
    )
    (fp_rect (start -0.925 0.47) (end 0.925 -0.47)
      (stroke (width 0.05) (type default)) (fill none) (layer "B.CrtYd"))
    (fp_rect (start -0.5 0.25) (end 0.5 -0.25)
      (stroke (width 0.15) (type solid)) (fill none) (layer "B.Fab"))
    (pad "1" smd roundrect (at -0.48 0 90) (size 0.59 0.64) (layers "B.Cu" "B.Paste" "B.Mask") (roundrect_rratio 0.25)
      (net 2 "VCC3V3") (pintype "passive"))
    (pad "2" smd roundrect (at 0.48 0 90) (size 0.59 0.64) (layers "B.Cu" "B.Paste" "B.Mask") (roundrect_rratio 0.25)
      (net 124 "QSPIB_CLK") (pintype "passive"))
  )

  (footprint "antmicro-footprints:R_0402_1005Metric" (layer "B.Cu")
    (at 81.975 138.8 -90)
    (descr "Resistor SMD 0402")
    (tags "resistor SMD 0402")
    (property "Author" "Antmicro")
    (property "License" "Apache-2.0")
    (property "MPN" "CR0402-FX-1002GLF")
    (property "Manufacturer" "Bourns")
    (property "Public" "False")
    (property "Sheetfile" "rot.kicad_sch")
    (property "Sheetname" "RoT")
    (property "Tolerance" "1%")
    (property "Val" "10k")
    (property "ki_description" "SMD Chip Resistor, 10 kohm, ± 1%, 62.5 mW, 0402 [1005 Metric], Thick Film, General Purpose")
    (property "ki_keywords" "0402, SMT, RESISTOR, PASSIVE")
    (attr smd)
    (fp_text reference "R30" (at 3.05 -0.35083 90) (layer "B.SilkS")
        (effects (font (size 0.7 0.7) (thickness 0.127)) (justify mirror))
    )
    (fp_text value "R_10k_0402" (at 0 -1.17 90) (layer "B.Fab")
        (effects (font (size 1 1) (thickness 0.15)) (justify mirror))
    )
    (fp_text user "${REFERENCE}" (at 0 0 90) (layer "B.Fab")
        (effects (font (size 0.25 0.25) (thickness 0.04)) (justify mirror))
    )
    (fp_text user "License: Apache-2.0" (at -0.95 -5.169 90) (layer "B.Fab") hide
        (effects (font (size 0.7 0.7) (thickness 0.15)) (justify left bottom mirror))
    )
    (fp_text user "Author: Antmicro" (at -0.95 -4.169 90) (layer "B.Fab") hide
        (effects (font (size 0.7 0.7) (thickness 0.15)) (justify left bottom mirror))
    )
    (fp_rect (start -0.925 0.47) (end 0.925 -0.47)
      (stroke (width 0.05) (type default)) (fill none) (layer "B.CrtYd"))
    (fp_rect (start -0.5 0.25) (end 0.5 -0.25)
      (stroke (width 0.15) (type solid)) (fill none) (layer "B.Fab"))
    (pad "1" smd roundrect (at -0.48 0 270) (size 0.59 0.64) (layers "B.Cu" "B.Paste" "B.Mask") (roundrect_rratio 0.25)
      (net 125 "QSPIB1_D0") (pintype "passive"))
    (pad "2" smd roundrect (at 0.48 0 270) (size 0.59 0.64) (layers "B.Cu" "B.Paste" "B.Mask") (roundrect_rratio 0.25)
      (net 2 "VCC3V3") (pintype "passive"))
  )

  (footprint "antmicro-footprints:R_0402_1005Metric" (layer "B.Cu")
    (at 76.975 138.8 -90)
    (descr "Resistor SMD 0402")
    (tags "resistor SMD 0402")
    (property "Author" "Antmicro")
    (property "License" "Apache-2.0")
    (property "MPN" "CR0402-FX-1002GLF")
    (property "Manufacturer" "Bourns")
    (property "Public" "False")
    (property "Sheetfile" "rot.kicad_sch")
    (property "Sheetname" "RoT")
    (property "Tolerance" "1%")
    (property "Val" "10k")
    (property "ki_description" "SMD Chip Resistor, 10 kohm, ± 1%, 62.5 mW, 0402 [1005 Metric], Thick Film, General Purpose")
    (property "ki_keywords" "0402, SMT, RESISTOR, PASSIVE")
    (attr smd)
    (fp_text reference "R34" (at 3.05 -0.23 90) (layer "B.SilkS")
        (effects (font (size 0.7 0.7) (thickness 0.127)) (justify mirror))
    )
    (fp_text value "R_10k_0402" (at 0 -1.17 90) (layer "B.Fab")
        (effects (font (size 1 1) (thickness 0.15)) (justify mirror))
    )
    (fp_text user "Author: Antmicro" (at -0.95 -4.169 90) (layer "B.Fab") hide
        (effects (font (size 0.7 0.7) (thickness 0.15)) (justify left bottom mirror))
    )
    (fp_text user "${REFERENCE}" (at 0 0 90) (layer "B.Fab")
        (effects (font (size 0.25 0.25) (thickness 0.04)) (justify mirror))
    )
    (fp_text user "License: Apache-2.0" (at -0.95 -5.169 90) (layer "B.Fab") hide
        (effects (font (size 0.7 0.7) (thickness 0.15)) (justify left bottom mirror))
    )
    (fp_rect (start -0.925 0.47) (end 0.925 -0.47)
      (stroke (width 0.05) (type default)) (fill none) (layer "B.CrtYd"))
    (fp_rect (start -0.5 0.25) (end 0.5 -0.25)
      (stroke (width 0.15) (type solid)) (fill none) (layer "B.Fab"))
    (pad "1" smd roundrect (at -0.48 0 270) (size 0.59 0.64) (layers "B.Cu" "B.Paste" "B.Mask") (roundrect_rratio 0.25)
      (net 127 "QSPIB1_D2") (pintype "passive"))
    (pad "2" smd roundrect (at 0.48 0 270) (size 0.59 0.64) (layers "B.Cu" "B.Paste" "B.Mask") (roundrect_rratio 0.25)
      (net 2 "VCC3V3") (pintype "passive"))
  )

  (footprint "antmicro-footprints:R_0402_1005Metric" (layer "B.Cu")
    (at 79.975 138.8 -90)
    (descr "Resistor SMD 0402")
    (tags "resistor SMD 0402")
    (property "Author" "Antmicro")
    (property "License" "Apache-2.0")
    (property "MPN" "CR0402-FX-1002GLF")
    (property "Manufacturer" "Bourns")
    (property "Public" "False")
    (property "Sheetfile" "rot.kicad_sch")
    (property "Sheetname" "RoT")
    (property "Tolerance" "1%")
    (property "Val" "10k")
    (property "ki_description" "SMD Chip Resistor, 10 kohm, ± 1%, 62.5 mW, 0402 [1005 Metric], Thick Film, General Purpose")
    (property "ki_keywords" "0402, SMT, RESISTOR, PASSIVE")
    (attr smd)
    (fp_text reference "R38" (at 3.05 -0.302498 90) (layer "B.SilkS")
        (effects (font (size 0.7 0.7) (thickness 0.127)) (justify mirror))
    )
    (fp_text value "R_10k_0402" (at 0 -1.17 90) (layer "B.Fab")
        (effects (font (size 1 1) (thickness 0.15)) (justify mirror))
    )
    (fp_text user "${REFERENCE}" (at 0 0 90) (layer "B.Fab")
        (effects (font (size 0.25 0.25) (thickness 0.04)) (justify mirror))
    )
    (fp_text user "Author: Antmicro" (at -0.95 -4.169 90) (layer "B.Fab") hide
        (effects (font (size 0.7 0.7) (thickness 0.15)) (justify left bottom mirror))
    )
    (fp_text user "License: Apache-2.0" (at -0.95 -5.169 90) (layer "B.Fab") hide
        (effects (font (size 0.7 0.7) (thickness 0.15)) (justify left bottom mirror))
    )
    (fp_rect (start -0.925 0.47) (end 0.925 -0.47)
      (stroke (width 0.05) (type default)) (fill none) (layer "B.CrtYd"))
    (fp_rect (start -0.5 0.25) (end 0.5 -0.25)
      (stroke (width 0.15) (type solid)) (fill none) (layer "B.Fab"))
    (pad "1" smd roundrect (at -0.48 0 270) (size 0.59 0.64) (layers "B.Cu" "B.Paste" "B.Mask") (roundrect_rratio 0.25)
      (net 128 "QSPIB1_D3") (pintype "passive"))
    (pad "2" smd roundrect (at 0.48 0 270) (size 0.59 0.64) (layers "B.Cu" "B.Paste" "B.Mask") (roundrect_rratio 0.25)
      (net 2 "VCC3V3") (pintype "passive"))
  )

  (footprint "antmicro-footprints:R_0402_1005Metric" (layer "B.Cu")
    (at 77.975 138.8 -90)
    (descr "Resistor SMD 0402")
    (tags "resistor SMD 0402")
    (property "Author" "Antmicro")
    (property "License" "Apache-2.0")
    (property "MPN" "CR0402-FX-1002GLF")
    (property "Manufacturer" "Bourns")
    (property "Public" "False")
    (property "Sheetfile" "rot.kicad_sch")
    (property "Sheetname" "RoT")
    (property "Tolerance" "1%")
    (property "Val" "10k")
    (property "ki_description" "SMD Chip Resistor, 10 kohm, ± 1%, 62.5 mW, 0402 [1005 Metric], Thick Film, General Purpose")
    (property "ki_keywords" "0402, SMT, RESISTOR, PASSIVE")
    (attr smd)
    (fp_text reference "R42" (at 3.05 -0.254166 90) (layer "B.SilkS")
        (effects (font (size 0.7 0.7) (thickness 0.127)) (justify mirror))
    )
    (fp_text value "R_10k_0402" (at 0 -1.17 90) (layer "B.Fab")
        (effects (font (size 1 1) (thickness 0.15)) (justify mirror))
    )
    (fp_text user "Author: Antmicro" (at -0.95 -4.169 90) (layer "B.Fab") hide
        (effects (font (size 0.7 0.7) (thickness 0.15)) (justify left bottom mirror))
    )
    (fp_text user "License: Apache-2.0" (at -0.95 -5.169 90) (layer "B.Fab") hide
        (effects (font (size 0.7 0.7) (thickness 0.15)) (justify left bottom mirror))
    )
    (fp_text user "${REFERENCE}" (at 0 0 90) (layer "B.Fab")
        (effects (font (size 0.25 0.25) (thickness 0.04)) (justify mirror))
    )
    (fp_rect (start -0.925 0.47) (end 0.925 -0.47)
      (stroke (width 0.05) (type default)) (fill none) (layer "B.CrtYd"))
    (fp_rect (start -0.5 0.25) (end 0.5 -0.25)
      (stroke (width 0.15) (type solid)) (fill none) (layer "B.Fab"))
    (pad "1" smd roundrect (at -0.48 0 270) (size 0.59 0.64) (layers "B.Cu" "B.Paste" "B.Mask") (roundrect_rratio 0.25)
      (net 126 "QSPIB1_D1") (pintype "passive"))
    (pad "2" smd roundrect (at 0.48 0 270) (size 0.59 0.64) (layers "B.Cu" "B.Paste" "B.Mask") (roundrect_rratio 0.25)
      (net 2 "VCC3V3") (pintype "passive"))
  )

  (footprint "antmicro-footprints:C_0402_1005Metric" (layer "B.Cu")
    (at 85.85 132.7 90)
    (descr "Capacitor SMD 0402")
    (tags "capacitor SMD 0402")
    (property "Author" "Antmicro")
    (property "Dielectric" "X5R")
    (property "License" "Apache-2.0")
    (property "MPN" "GRM155R61H104KE14D")
    (property "Manufacturer" "Murata")
    (property "Public" "False")
    (property "Sheetfile" "fpga-banks.kicad_sch")
    (property "Sheetname" "FPGA banks")
    (property "Val" "100n")
    (property "Voltage" "50V")
    (property "ki_description" "SMD Multilayer Ceramic Capacitor, 0.1 µF, 50 V, 0402 [1005 Metric], ± 10%, X5R, GRM Series")
    (property "ki_keywords" "0402, SMT, CAPACITOR, PASSIVE, CERAMIC, MLCC")
    (attr smd)
    (fp_text reference "C208" (at 0 1.17 90) (layer "B.SilkS")
        (effects (font (size 0.7 0.7) (thickness 0.127)) (justify mirror))
    )
    (fp_text value "C_100n_0402" (at 0 -1.17 90) (layer "B.Fab")
        (effects (font (size 1 1) (thickness 0.15)) (justify mirror))
    )
    (fp_text user "Author: Antmicro" (at -0.939 -3.399 270) (layer "B.Fab") hide
        (effects (font (size 0.7 0.7) (thickness 0.15)) (justify left bottom mirror))
    )
    (fp_text user "${REFERENCE}" (at 0 0 90) (layer "B.Fab")
        (effects (font (size 0.25 0.25) (thickness 0.04)) (justify mirror))
    )
    (fp_text user "License: Apache-2.0" (at -0.939 -5.799 270) (layer "B.Fab") hide
        (effects (font (size 0.7 0.7) (thickness 0.15)) (justify left bottom mirror))
    )
    (fp_rect (start -0.925 0.47) (end 0.925 -0.47)
      (stroke (width 0.05) (type default)) (fill none) (layer "B.CrtYd"))
    (fp_line (start -0.494 -0.248) (end -0.494 0.25)
      (stroke (width 0.15) (type solid)) (layer "B.Fab"))
    (fp_line (start -0.494 0.25) (end 0.504 0.25)
      (stroke (width 0.15) (type solid)) (layer "B.Fab"))
    (fp_line (start 0.504 -0.248) (end -0.494 -0.248)
      (stroke (width 0.15) (type solid)) (layer "B.Fab"))
    (fp_line (start 0.504 0.25) (end 0.504 -0.248)
      (stroke (width 0.15) (type solid)) (layer "B.Fab"))
    (pad "1" smd roundrect (at -0.48 0 90) (size 0.59 0.64) (layers "B.Cu" "B.Paste" "B.Mask") (roundrect_rratio 0.25)
      (net 1 "GND") (pintype "passive"))
    (pad "2" smd roundrect (at 0.48 0 90) (size 0.59 0.64) (layers "B.Cu" "B.Paste" "B.Mask") (roundrect_rratio 0.25)
      (net 268 "PROGRAM_N") (pintype "passive"))
  )

  (footprint "antmicro-footprints:R_0402_1005Metric" (layer "B.Cu")
    (at 84.75 132.7 -90)
    (descr "Resistor SMD 0402")
    (tags "resistor SMD 0402")
    (property "Author" "Antmicro")
    (property "License" "Apache-2.0")
    (property "MPN" "CR0402-FX-1002GLF")
    (property "Manufacturer" "Bourns")
    (property "Public" "False")
    (property "Sheetfile" "fpga-banks.kicad_sch")
    (property "Sheetname" "FPGA banks")
    (property "Tolerance" "1%")
    (property "Val" "10k")
    (property "ki_description" "SMD Chip Resistor, 10 kohm, ± 1%, 62.5 mW, 0402 [1005 Metric], Thick Film, General Purpose")
    (property "ki_keywords" "0402, SMT, RESISTOR, PASSIVE")
    (attr smd)
    (fp_text reference "R131" (at 0.655 1.01 90) (layer "B.SilkS")
        (effects (font (size 0.7 0.7) (thickness 0.127)) (justify mirror))
    )
    (fp_text value "R_10k_0402" (at 0 -1.17 90) (layer "B.Fab")
        (effects (font (size 1 1) (thickness 0.15)) (justify mirror))
    )
    (fp_text user "Author: Antmicro" (at -0.95 -4.169 90) (layer "B.Fab") hide
        (effects (font (size 0.7 0.7) (thickness 0.15)) (justify left bottom mirror))
    )
    (fp_text user "License: Apache-2.0" (at -0.95 -5.169 90) (layer "B.Fab") hide
        (effects (font (size 0.7 0.7) (thickness 0.15)) (justify left bottom mirror))
    )
    (fp_text user "${REFERENCE}" (at 0 0 90) (layer "B.Fab")
        (effects (font (size 0.25 0.25) (thickness 0.04)) (justify mirror))
    )
    (fp_rect (start -0.925 0.47) (end 0.925 -0.47)
      (stroke (width 0.05) (type default)) (fill none) (layer "B.CrtYd"))
    (fp_rect (start -0.5 0.25) (end 0.5 -0.25)
      (stroke (width 0.15) (type solid)) (fill none) (layer "B.Fab"))
    (pad "1" smd roundrect (at -0.48 0 270) (size 0.59 0.64) (layers "B.Cu" "B.Paste" "B.Mask") (roundrect_rratio 0.25)
      (net 268 "PROGRAM_N") (pintype "passive"))
    (pad "2" smd roundrect (at 0.48 0 270) (size 0.59 0.64) (layers "B.Cu" "B.Paste" "B.Mask") (roundrect_rratio 0.25)
      (net 2 "VCC3V3") (pintype "passive"))
  )

  (footprint "antmicro-footprints:R_Array_8x0602_Panasonic_EXB2HV" (layer "B.Cu")
    (at 84.74 116.3 90)
    (descr "Chip Resistor Network, ROHM MNR18")
    (tags "resistor array")
    (property "Author" "Antmicro")
    (property "License" "Apache-2.0")
    (property "MPN" "EXB2HV510JV")
    (property "Manufacturer" "Panasonic")
    (property "Sheetfile" "ddr3.kicad_sch")
    (property "Sheetname" "DDR3")
    (property "Val" "8x51R_0602")
    (property "ki_description" "Fixed Network Resistor, 51 ohm, Isolated, 8 Resistors, 1506 [3816 Metric], Convex, ± 5%")
    (property "ki_keywords" "SMT, RESISTOR, PASSIVE, ARRAY")
    (attr smd)
    (fp_text reference "R124" (at 2.195 0.74) (layer "B.SilkS")
        (effects (font (size 0.7 0.7) (thickness 0.127)) (justify mirror))
    )
    (fp_text value "8x51R_0602_array" (at 0 -3 270) (layer "B.Fab")
        (effects (font (size 1 1) (thickness 0.15)) (justify mirror))
    )
    (fp_text user "Author: Antmicro" (at -1.55 -5.05 270) (layer "B.Fab") hide
        (effects (font (size 0.7 0.7) (thickness 0.15)) (justify left bottom mirror))
    )
    (fp_text user "License: Apache-2.0" (at -1.55 -7.45 270) (layer "B.Fab") hide
        (effects (font (size 0.7 0.7) (thickness 0.15)) (justify left bottom mirror))
    )
    (fp_text user "${REFERENCE}" (at 0 0) (layer "B.Fab")
        (effects (font (size 1 1) (thickness 0.15)) (justify mirror))
    )
    (fp_line (start 0.5 -2.12) (end -0.5 -2.12)
      (stroke (width 0.15) (type solid)) (layer "B.SilkS"))
    (fp_line (start 0.5 2.12) (end -0.5 2.12)
      (stroke (width 0.15) (type solid)) (layer "B.SilkS"))
    (fp_circle (center -1.05 2.05) (end -1 2.05)
      (stroke (width 0.15) (type solid)) (fill solid) (layer "B.SilkS"))
    (fp_rect (start -1.55 2.2) (end 1.55 -2.2)
      (stroke (width 0.05) (type solid)) (fill none) (layer "B.CrtYd"))
    (fp_line (start -0.8 -2) (end 0.8 -2)
      (stroke (width 0.15) (type solid)) (layer "B.Fab"))
    (fp_line (start -0.8 2) (end -0.8 -2)
      (stroke (width 0.15) (type solid)) (layer "B.Fab"))
    (fp_line (start 0.8 -2) (end 0.8 2)
      (stroke (width 0.15) (type solid)) (layer "B.Fab"))
    (fp_line (start 0.8 2) (end -0.8 2)
      (stroke (width 0.15) (type solid)) (layer "B.Fab"))
    (pad "1" smd rect (at -0.9 1.75 90) (size 0.8 0.3) (layers "B.Cu" "B.Paste" "B.Mask")
      (net 240 "DDR3_A7") (pinfunction "1") (pintype "passive"))
    (pad "2" smd rect (at -0.9 1.25 90) (size 0.8 0.3) (layers "B.Cu" "B.Paste" "B.Mask")
      (net 255 "DDR3_A3") (pinfunction "2") (pintype "passive"))
    (pad "3" smd rect (at -0.9 0.75 90) (size 0.8 0.3) (layers "B.Cu" "B.Paste" "B.Mask")
      (net 241 "DDR3_A2") (pinfunction "3") (pintype "passive"))
    (pad "4" smd rect (at -0.9 0.25 90) (size 0.8 0.3) (layers "B.Cu" "B.Paste" "B.Mask")
      (net 253 "DDR3_A5") (pinfunction "4") (pintype "passive"))
    (pad "5" smd rect (at -0.9 -0.25 90) (size 0.8 0.3) (layers "B.Cu" "B.Paste" "B.Mask")
      (net 239 "DDR3_A9") (pinfunction "5") (pintype "passive"))
    (pad "6" smd rect (at -0.9 -0.75 90) (size 0.8 0.3) (layers "B.Cu" "B.Paste" "B.Mask")
      (net 237 "DDR3_A13") (pinfunction "6") (pintype "passive"))
    (pad "7" smd rect (at -0.9 -1.25 90) (size 0.8 0.3) (layers "B.Cu" "B.Paste" "B.Mask")
      (net 238 "DDR3_A11") (pinfunction "7") (pintype "passive"))
    (pad "8" smd rect (at -0.9 -1.75 90) (size 0.8 0.3) (layers "B.Cu" "B.Paste" "B.Mask")
      (net 244 "DDR3_A14") (pinfunction "8") (pintype "passive"))
    (pad "9" smd rect (at 0.9 -1.75 90) (size 0.8 0.3) (layers "B.Cu" "B.Paste" "B.Mask")
      (net 166 "/DDR3/DDR3_VTT") (pinfunction "9") (pintype "passive"))
    (pad "10" smd rect (at 0.9 -1.25 90) (size 0.8 0.3) (layers "B.Cu" "B.Paste" "B.Mask")
      (net 166 "/DDR3/DDR3_VTT") (pinfunction "10") (pintype "passive"))
    (pad "11" smd rect (at 0.9 -0.75 90) (size 0.8 0.3) (layers "B.Cu" "B.Paste" "B.Mask")
      (net 166 "/DDR3/DDR3_VTT") (pinfunction "11") (pintype "passive"))
    (pad "12" smd rect (at 0.9 -0.25 90) (size 0.8 0.3) (layers "B.Cu" "B.Paste" "B.Mask")
      (net 166 "/DDR3/DDR3_VTT") (pinfunction "12") (pintype "passive"))
    (pad "13" smd rect (at 0.9 0.25 90) (size 0.8 0.3) (layers "B.Cu" "B.Paste" "B.Mask")
      (net 166 "/DDR3/DDR3_VTT") (pinfunction "13") (pintype "passive"))
    (pad "14" smd rect (at 0.9 0.75 90) (size 0.8 0.3) (layers "B.Cu" "B.Paste" "B.Mask")
      (net 166 "/DDR3/DDR3_VTT") (pinfunction "14") (pintype "passive"))
    (pad "15" smd rect (at 0.9 1.25 90) (size 0.8 0.3) (layers "B.Cu" "B.Paste" "B.Mask")
      (net 166 "/DDR3/DDR3_VTT") (pinfunction "15") (pintype "passive"))
    (pad "16" smd rect (at 0.9 1.75 90) (size 0.8 0.3) (layers "B.Cu" "B.Paste" "B.Mask")
      (net 166 "/DDR3/DDR3_VTT") (pinfunction "16") (pintype "passive"))
  )

  (footprint "antmicro-footprints:R_Array_8x0602_Panasonic_EXB2HV" (layer "B.Cu")
    (at 78.94 119.795 180)
    (descr "Chip Resistor Network, ROHM MNR18")
    (tags "resistor array")
    (property "Author" "Antmicro")
    (property "License" "Apache-2.0")
    (property "MPN" "EXB2HV510JV")
    (property "Manufacturer" "Panasonic")
    (property "Sheetfile" "ddr3.kicad_sch")
    (property "Sheetname" "DDR3")
    (property "Val" "8x51R_0602")
    (property "ki_description" "Fixed Network Resistor, 51 ohm, Isolated, 8 Resistors, 1506 [3816 Metric], Convex, ± 5%")
    (property "ki_keywords" "SMT, RESISTOR, PASSIVE, ARRAY")
    (attr smd)
    (fp_text reference "R125" (at 2.26 -0.68 90) (layer "B.SilkS")
        (effects (font (size 0.7 0.7) (thickness 0.127)) (justify mirror))
    )
    (fp_text value "8x51R_0602_array" (at 0 -3) (layer "B.Fab")
        (effects (font (size 1 1) (thickness 0.15)) (justify mirror))
    )
    (fp_text user "${REFERENCE}" (at 0 0 -90) (layer "B.Fab")
        (effects (font (size 1 1) (thickness 0.15)) (justify mirror))
    )
    (fp_text user "Author: Antmicro" (at -1.55 -5.05) (layer "B.Fab") hide
        (effects (font (size 0.7 0.7) (thickness 0.15)) (justify left bottom mirror))
    )
    (fp_text user "License: Apache-2.0" (at -1.55 -7.45) (layer "B.Fab") hide
        (effects (font (size 0.7 0.7) (thickness 0.15)) (justify left bottom mirror))
    )
    (fp_line (start 0.5 -2.12) (end -0.5 -2.12)
      (stroke (width 0.15) (type solid)) (layer "B.SilkS"))
    (fp_line (start 0.5 2.12) (end -0.5 2.12)
      (stroke (width 0.15) (type solid)) (layer "B.SilkS"))
    (fp_circle (center -1.05 2.05) (end -1 2.05)
      (stroke (width 0.15) (type solid)) (fill solid) (layer "B.SilkS"))
    (fp_rect (start -1.55 2.2) (end 1.55 -2.2)
      (stroke (width 0.05) (type solid)) (fill none) (layer "B.CrtYd"))
    (fp_line (start -0.8 -2) (end 0.8 -2)
      (stroke (width 0.15) (type solid)) (layer "B.Fab"))
    (fp_line (start -0.8 2) (end -0.8 -2)
      (stroke (width 0.15) (type solid)) (layer "B.Fab"))
    (fp_line (start 0.8 -2) (end 0.8 2)
      (stroke (width 0.15) (type solid)) (layer "B.Fab"))
    (fp_line (start 0.8 2) (end -0.8 2)
      (stroke (width 0.15) (type solid)) (layer "B.Fab"))
    (pad "1" smd rect (at -0.9 1.75 180) (size 0.8 0.3) (layers "B.Cu" "B.Paste" "B.Mask")
      (net 243 "DDR3_A8") (pinfunction "1") (pintype "passive"))
    (pad "2" smd rect (at -0.9 1.25 180) (size 0.8 0.3) (layers "B.Cu" "B.Paste" "B.Mask")
      (net 242 "DDR3_A6") (pinfunction "2") (pintype "passive"))
    (pad "3" smd rect (at -0.9 0.75 180) (size 0.8 0.3) (layers "B.Cu" "B.Paste" "B.Mask")
      (net 245 "DDR3_A4") (pinfunction "3") (pintype "passive"))
    (pad "4" smd rect (at -0.9 0.25 180) (size 0.8 0.3) (layers "B.Cu" "B.Paste" "B.Mask")
      (net 247 "DDR3_A1") (pinfunction "4") (pintype "passive"))
    (pad "5" smd rect (at -0.9 -0.25 180) (size 0.8 0.3) (layers "B.Cu" "B.Paste" "B.Mask")
      (net 248 "DDR3_A12") (pinfunction "5") (pintype "passive"))
    (pad "6" smd rect (at -0.9 -0.75 180) (size 0.8 0.3) (layers "B.Cu" "B.Paste" "B.Mask")
      (net 249 "DDR3_BA1") (pinfunction "6") (pintype "passive"))
    (pad "7" smd rect (at -0.9 -1.25 180) (size 0.8 0.3) (layers "B.Cu" "B.Paste" "B.Mask")
      (net 250 "DDR3_A10") (pinfunction "7") (pintype "passive"))
    (pad "8" smd rect (at -0.9 -1.75 180) (size 0.8 0.3) (layers "B.Cu" "B.Paste" "B.Mask")
      (net 260 "DDR3_CKE") (pinfunction "8") (pintype "passive"))
    (pad "9" smd rect (at 0.9 -1.75 180) (size 0.8 0.3) (layers "B.Cu" "B.Paste" "B.Mask")
      (net 166 "/DDR3/DDR3_VTT") (pinfunction "9") (pintype "passive"))
    (pad "10" smd rect (at 0.9 -1.25 180) (size 0.8 0.3) (layers "B.Cu" "B.Paste" "B.Mask")
      (net 166 "/DDR3/DDR3_VTT") (pinfunction "10") (pintype "passive"))
    (pad "11" smd rect (at 0.9 -0.75 180) (size 0.8 0.3) (layers "B.Cu" "B.Paste" "B.Mask")
      (net 166 "/DDR3/DDR3_VTT") (pinfunction "11") (pintype "passive"))
    (pad "12" smd rect (at 0.9 -0.25 180) (size 0.8 0.3) (layers "B.Cu" "B.Paste" "B.Mask")
      (net 166 "/DDR3/DDR3_VTT") (pinfunction "12") (pintype "passive"))
    (pad "13" smd rect (at 0.9 0.25 180) (size 0.8 0.3) (layers "B.Cu" "B.Paste" "B.Mask")
      (net 166 "/DDR3/DDR3_VTT") (pinfunction "13") (pintype "passive"))
    (pad "14" smd rect (at 0.9 0.75 180) (size 0.8 0.3) (layers "B.Cu" "B.Paste" "B.Mask")
      (net 166 "/DDR3/DDR3_VTT") (pinfunction "14") (pintype "passive"))
    (pad "15" smd rect (at 0.9 1.25 180) (size 0.8 0.3) (layers "B.Cu" "B.Paste" "B.Mask")
      (net 166 "/DDR3/DDR3_VTT") (pinfunction "15") (pintype "passive"))
    (pad "16" smd rect (at 0.9 1.75 180) (size 0.8 0.3) (layers "B.Cu" "B.Paste" "B.Mask")
      (net 166 "/DDR3/DDR3_VTT") (pinfunction "16") (pintype "passive"))
  )

  (footprint "antmicro-footprints:R_Array_8x0602_Panasonic_EXB2HV" (layer "B.Cu")
    (at 84.77 124.595 -90)
    (descr "Chip Resistor Network, ROHM MNR18")
    (tags "resistor array")
    (property "Author" "Antmicro")
    (property "License" "Apache-2.0")
    (property "MPN" "EXB2HV510JV")
    (property "Manufacturer" "Panasonic")
    (property "Sheetfile" "ddr3.kicad_sch")
    (property "Sheetname" "DDR3")
    (property "Val" "8x51R_0602")
    (property "ki_description" "Fixed Network Resistor, 51 ohm, Isolated, 8 Resistors, 1506 [3816 Metric], Convex, ± 5%")
    (property "ki_keywords" "SMT, RESISTOR, PASSIVE, ARRAY")
    (attr smd)
    (fp_text reference "R136" (at -0.84 -3.59 180) (layer "B.SilkS")
        (effects (font (size 0.7 0.7) (thickness 0.127)) (justify mirror))
    )
    (fp_text value "8x51R_0602_array" (at 0 -3 90) (layer "B.Fab")
        (effects (font (size 1 1) (thickness 0.15)) (justify mirror))
    )
    (fp_text user "${REFERENCE}" (at 0 0 180) (layer "B.Fab")
        (effects (font (size 1 1) (thickness 0.15)) (justify mirror))
    )
    (fp_text user "License: Apache-2.0" (at -1.55 -7.45 90) (layer "B.Fab") hide
        (effects (font (size 0.7 0.7) (thickness 0.15)) (justify left bottom mirror))
    )
    (fp_text user "Author: Antmicro" (at -1.55 -5.05 90) (layer "B.Fab") hide
        (effects (font (size 0.7 0.7) (thickness 0.15)) (justify left bottom mirror))
    )
    (fp_line (start 0.5 -2.12) (end -0.5 -2.12)
      (stroke (width 0.15) (type solid)) (layer "B.SilkS"))
    (fp_line (start 0.5 2.12) (end -0.5 2.12)
      (stroke (width 0.15) (type solid)) (layer "B.SilkS"))
    (fp_circle (center -1.05 2.05) (end -1 2.05)
      (stroke (width 0.15) (type solid)) (fill solid) (layer "B.SilkS"))
    (fp_rect (start -1.55 2.2) (end 1.55 -2.2)
      (stroke (width 0.05) (type solid)) (fill none) (layer "B.CrtYd"))
    (fp_line (start -0.8 -2) (end 0.8 -2)
      (stroke (width 0.15) (type solid)) (layer "B.Fab"))
    (fp_line (start -0.8 2) (end -0.8 -2)
      (stroke (width 0.15) (type solid)) (layer "B.Fab"))
    (fp_line (start 0.8 -2) (end 0.8 2)
      (stroke (width 0.15) (type solid)) (layer "B.Fab"))
    (fp_line (start 0.8 2) (end -0.8 2)
      (stroke (width 0.15) (type solid)) (layer "B.Fab"))
    (pad "1" smd rect (at -0.9 1.75 270) (size 0.8 0.3) (layers "B.Cu" "B.Paste" "B.Mask")
      (net 246 "DDR3_A0") (pinfunction "1") (pintype "passive"))
    (pad "2" smd rect (at -0.9 1.25 270) (size 0.8 0.3) (layers "B.Cu" "B.Paste" "B.Mask")
      (net 252 "DDR3_BA2") (pinfunction "2") (pintype "passive"))
    (pad "3" smd rect (at -0.9 0.75 270) (size 0.8 0.3) (layers "B.Cu" "B.Paste" "B.Mask")
      (net 251 "DDR3_WE") (pinfunction "3") (pintype "passive"))
    (pad "4" smd rect (at -0.9 0.25 270) (size 0.8 0.3) (layers "B.Cu" "B.Paste" "B.Mask")
      (net 258 "DDR3_RAS") (pinfunction "4") (pintype "passive"))
    (pad "5" smd rect (at -0.9 -0.25 270) (size 0.8 0.3) (layers "B.Cu" "B.Paste" "B.Mask")
      (net 254 "DDR3_CAS") (pinfunction "5") (pintype "passive"))
    (pad "6" smd rect (at -0.9 -0.75 270) (size 0.8 0.3) (layers "B.Cu" "B.Paste" "B.Mask")
      (net 257 "DDR3_CS") (pinfunction "6") (pintype "passive"))
    (pad "7" smd rect (at -0.9 -1.25 270) (size 0.8 0.3) (layers "B.Cu" "B.Paste" "B.Mask")
      (net 256 "DDR3_BA0") (pinfunction "7") (pintype "passive"))
    (pad "8" smd rect (at -0.9 -1.75 270) (size 0.8 0.3) (layers "B.Cu" "B.Paste" "B.Mask")
      (net 259 "DDR3_ODT") (pinfunction "8") (pintype "passive"))
    (pad "9" smd rect (at 0.9 -1.75 270) (size 0.8 0.3) (layers "B.Cu" "B.Paste" "B.Mask")
      (net 166 "/DDR3/DDR3_VTT") (pinfunction "9") (pintype "passive"))
    (pad "10" smd rect (at 0.9 -1.25 270) (size 0.8 0.3) (layers "B.Cu" "B.Paste" "B.Mask")
      (net 166 "/DDR3/DDR3_VTT") (pinfunction "10") (pintype "passive"))
    (pad "11" smd rect (at 0.9 -0.75 270) (size 0.8 0.3) (layers "B.Cu" "B.Paste" "B.Mask")
      (net 166 "/DDR3/DDR3_VTT") (pinfunction "11") (pintype "passive"))
    (pad "12" smd rect (at 0.9 -0.25 270) (size 0.8 0.3) (layers "B.Cu" "B.Paste" "B.Mask")
      (net 166 "/DDR3/DDR3_VTT") (pinfunction "12") (pintype "passive"))
    (pad "13" smd rect (at 0.9 0.25 270) (size 0.8 0.3) (layers "B.Cu" "B.Paste" "B.Mask")
      (net 166 "/DDR3/DDR3_VTT") (pinfunction "13") (pintype "passive"))
    (pad "14" smd rect (at 0.9 0.75 270) (size 0.8 0.3) (layers "B.Cu" "B.Paste" "B.Mask")
      (net 166 "/DDR3/DDR3_VTT") (pinfunction "14") (pintype "passive"))
    (pad "15" smd rect (at 0.9 1.25 270) (size 0.8 0.3) (layers "B.Cu" "B.Paste" "B.Mask")
      (net 166 "/DDR3/DDR3_VTT") (pinfunction "15") (pintype "passive"))
    (pad "16" smd rect (at 0.9 1.75 270) (size 0.8 0.3) (layers "B.Cu" "B.Paste" "B.Mask")
      (net 166 "/DDR3/DDR3_VTT") (pinfunction "16") (pintype "passive"))
  )

  (footprint "antmicro-footprints:R_0402_1005Metric" (layer "B.Cu")
    (at 87.45 135.6 90)
    (descr "Resistor SMD 0402")
    (tags "resistor SMD 0402")
    (property "Author" "Antmicro")
    (property "Current" "1A")
    (property "DNP" "DNP")
    (property "License" "Apache-2.0")
    (property "MPN" "ERJ2GE0R00X")
    (property "Manufacturer" "Panasonic")
    (property "Public" "False")
    (property "Sheetfile" "fpga-banks.kicad_sch")
    (property "Sheetname" "FPGA banks")
    (property "Tolerance" "")
    (property "Val" "0R")
    (property "dnp" "")
    (property "exclude_from_bom" "")
    (property "ki_description" "SMD Chip Resistor, Jumper, 0 ohm, 100 mW, 0402 [1005 Metric], Thick Film, General Purpose")
    (property "ki_keywords" "0402, SMT, RESISTOR, PASSIVE")
    (attr smd exclude_from_pos_files exclude_from_bom)
    (fp_text reference "R133" (at -2.35 0.02 90) (layer "B.SilkS")
        (effects (font (size 0.7 0.7) (thickness 0.127)) (justify mirror))
    )
    (fp_text value "R_0R_0402" (at 0 -1.17 90) (layer "B.Fab")
        (effects (font (size 1 1) (thickness 0.15)) (justify mirror))
    )
    (fp_text user "License: Apache-2.0" (at -0.95 -5.169 270) (layer "B.Fab") hide
        (effects (font (size 0.7 0.7) (thickness 0.15)) (justify left bottom mirror))
    )
    (fp_text user "${REFERENCE}" (at 0 0 90) (layer "B.Fab")
        (effects (font (size 0.25 0.25) (thickness 0.04)) (justify mirror))
    )
    (fp_text user "Author: Antmicro" (at -0.95 -4.169 270) (layer "B.Fab") hide
        (effects (font (size 0.7 0.7) (thickness 0.15)) (justify left bottom mirror))
    )
    (fp_rect (start -0.925 0.47) (end 0.925 -0.47)
      (stroke (width 0.05) (type default)) (fill none) (layer "B.CrtYd"))
    (fp_rect (start -0.5 0.25) (end 0.5 -0.25)
      (stroke (width 0.15) (type solid)) (fill none) (layer "B.Fab"))
    (pad "1" smd roundrect (at -0.48 0 90) (size 0.59 0.64) (layers "B.Cu" "B.Paste" "B.Mask") (roundrect_rratio 0.25)
      (net 53 "SPI0_CS_N") (pintype "passive"))
    (pad "2" smd roundrect (at 0.48 0 90) (size 0.59 0.64) (layers "B.Cu" "B.Paste" "B.Mask") (roundrect_rratio 0.25)
      (net 428 "Net-(U21I-PB4B)") (pintype "passive"))
  )

  (footprint "antmicro-footprints:R_0402_1005Metric" (layer "B.Cu")
    (at 89.55 135.6 90)
    (descr "Resistor SMD 0402")
    (tags "resistor SMD 0402")
    (property "Author" "Antmicro")
    (property "Current" "1A")
    (property "DNP" "DNP")
    (property "License" "Apache-2.0")
    (property "MPN" "ERJ2GE0R00X")
    (property "Manufacturer" "Panasonic")
    (property "Public" "False")
    (property "Sheetfile" "fpga-banks.kicad_sch")
    (property "Sheetname" "FPGA banks")
    (property "Tolerance" "")
    (property "Val" "0R")
    (property "dnp" "")
    (property "exclude_from_bom" "")
    (property "ki_description" "SMD Chip Resistor, Jumper, 0 ohm, 100 mW, 0402 [1005 Metric], Thick Film, General Purpose")
    (property "ki_keywords" "0402, SMT, RESISTOR, PASSIVE")
    (attr smd exclude_from_pos_files exclude_from_bom)
    (fp_text reference "R134" (at -2.35 0.02 90) (layer "B.SilkS")
        (effects (font (size 0.7 0.7) (thickness 0.127)) (justify mirror))
    )
    (fp_text value "R_0R_0402" (at 0 -1.17 90) (layer "B.Fab")
        (effects (font (size 1 1) (thickness 0.15)) (justify mirror))
    )
    (fp_text user "${REFERENCE}" (at 0 0 90) (layer "B.Fab")
        (effects (font (size 0.25 0.25) (thickness 0.04)) (justify mirror))
    )
    (fp_text user "Author: Antmicro" (at -0.95 -4.169 270) (layer "B.Fab") hide
        (effects (font (size 0.7 0.7) (thickness 0.15)) (justify left bottom mirror))
    )
    (fp_text user "License: Apache-2.0" (at -0.95 -5.169 270) (layer "B.Fab") hide
        (effects (font (size 0.7 0.7) (thickness 0.15)) (justify left bottom mirror))
    )
    (fp_rect (start -0.925 0.47) (end 0.925 -0.47)
      (stroke (width 0.05) (type default)) (fill none) (layer "B.CrtYd"))
    (fp_rect (start -0.5 0.25) (end 0.5 -0.25)
      (stroke (width 0.15) (type solid)) (fill none) (layer "B.Fab"))
    (pad "1" smd roundrect (at -0.48 0 90) (size 0.59 0.64) (layers "B.Cu" "B.Paste" "B.Mask") (roundrect_rratio 0.25)
      (net 55 "SPI0_MOSI") (pintype "passive"))
    (pad "2" smd roundrect (at 0.48 0 90) (size 0.59 0.64) (layers "B.Cu" "B.Paste" "B.Mask") (roundrect_rratio 0.25)
      (net 429 "Net-(U21I-PB6B)") (pintype "passive"))
  )

  (footprint "antmicro-footprints:R_0402_1005Metric" (layer "B.Cu")
    (at 88.5 135.6 90)
    (descr "Resistor SMD 0402")
    (tags "resistor SMD 0402")
    (property "Author" "Antmicro")
    (property "Current" "1A")
    (property "DNP" "DNP")
    (property "License" "Apache-2.0")
    (property "MPN" "ERJ2GE0R00X")
    (property "Manufacturer" "Panasonic")
    (property "Public" "False")
    (property "Sheetfile" "fpga-banks.kicad_sch")
    (property "Sheetname" "FPGA banks")
    (property "Tolerance" "")
    (property "Val" "0R")
    (property "dnp" "")
    (property "exclude_from_bom" "")
    (property "ki_description" "SMD Chip Resistor, Jumper, 0 ohm, 100 mW, 0402 [1005 Metric], Thick Film, General Purpose")
    (property "ki_keywords" "0402, SMT, RESISTOR, PASSIVE")
    (attr smd exclude_from_pos_files exclude_from_bom)
    (fp_text reference "R135" (at -2.35 0.02 90) (layer "B.SilkS")
        (effects (font (size 0.7 0.7) (thickness 0.127)) (justify mirror))
    )
    (fp_text value "R_0R_0402" (at 0 -1.17 90) (layer "B.Fab")
        (effects (font (size 1 1) (thickness 0.15)) (justify mirror))
    )
    (fp_text user "Author: Antmicro" (at -0.95 -4.169 270) (layer "B.Fab") hide
        (effects (font (size 0.7 0.7) (thickness 0.15)) (justify left bottom mirror))
    )
    (fp_text user "${REFERENCE}" (at 0 0 90) (layer "B.Fab")
        (effects (font (size 0.25 0.25) (thickness 0.04)) (justify mirror))
    )
    (fp_text user "License: Apache-2.0" (at -0.95 -5.169 270) (layer "B.Fab") hide
        (effects (font (size 0.7 0.7) (thickness 0.15)) (justify left bottom mirror))
    )
    (fp_rect (start -0.925 0.47) (end 0.925 -0.47)
      (stroke (width 0.05) (type default)) (fill none) (layer "B.CrtYd"))
    (fp_rect (start -0.5 0.25) (end 0.5 -0.25)
      (stroke (width 0.15) (type solid)) (fill none) (layer "B.Fab"))
    (pad "1" smd roundrect (at -0.48 0 90) (size 0.59 0.64) (layers "B.Cu" "B.Paste" "B.Mask") (roundrect_rratio 0.25)
      (net 56 "SPI0_MISO") (pintype "passive"))
    (pad "2" smd roundrect (at 0.48 0 90) (size 0.59 0.64) (layers "B.Cu" "B.Paste" "B.Mask") (roundrect_rratio 0.25)
      (net 431 "Net-(U21I-PB6A)") (pintype "passive"))
  )

  (footprint "antmicro-footprints:R_0402_1005Metric" (layer "B.Cu")
    (at 90.649 143.0942)
    (descr "Resistor SMD 0402")
    (tags "resistor SMD 0402")
    (property "Author" "Antmicro")
    (property "License" "Apache-2.0")
    (property "MPN" "CR0402-FX-3573GLF")
    (property "Manufacturer" "Bourns")
    (property "Public" "False")
    (property "Sheetfile" "interfaces.kicad_sch")
    (property "Sheetname" "Interfaces")
    (property "Tolerance" "1%")
    (property "Val" "357k")
    (property "ki_description" "SMD Chip Resistor")
    (property "ki_keywords" "0402, SMT, RESISTOR, PASSIVE")
    (attr smd)
    (fp_text reference "R49" (at -2.2 -0.03) (layer "B.SilkS")
        (effects (font (size 0.7 0.7) (thickness 0.127)) (justify mirror))
    )
    (fp_text value "R_357k_0402" (at 0 -1.17) (layer "B.Fab")
        (effects (font (size 1 1) (thickness 0.15)) (justify mirror))
    )
    (fp_text user "Author: Antmicro" (at -0.95 -4.169 180) (layer "B.Fab") hide
        (effects (font (size 0.7 0.7) (thickness 0.15)) (justify left bottom mirror))
    )
    (fp_text user "${REFERENCE}" (at 0 0) (layer "B.Fab")
        (effects (font (size 0.25 0.25) (thickness 0.04)) (justify mirror))
    )
    (fp_text user "License: Apache-2.0" (at -0.95 -5.169 180) (layer "B.Fab") hide
        (effects (font (size 0.7 0.7) (thickness 0.15)) (justify left bottom mirror))
    )
    (fp_rect (start -0.925 0.47) (end 0.925 -0.47)
      (stroke (width 0.05) (type default)) (fill none) (layer "B.CrtYd"))
    (fp_rect (start -0.5 0.25) (end 0.5 -0.25)
      (stroke (width 0.15) (type solid)) (fill none) (layer "B.Fab"))
    (pad "1" smd roundrect (at -0.48 0) (size 0.59 0.64) (layers "B.Cu" "B.Paste" "B.Mask") (roundrect_rratio 0.25)
      (net 2 "VCC3V3") (pintype "passive"))
    (pad "2" smd roundrect (at 0.48 0) (size 0.59 0.64) (layers "B.Cu" "B.Paste" "B.Mask") (roundrect_rratio 0.25)
      (net 167 "I3C[0]_SDA_3V3") (pintype "passive"))
  )

  (footprint "antmicro-footprints:R_0402_1005Metric" (layer "B.Cu")
    (at 90.649 142.0742)
    (descr "Resistor SMD 0402")
    (tags "resistor SMD 0402")
    (property "Author" "Antmicro")
    (property "License" "Apache-2.0")
    (property "MPN" "CR0402-FX-3573GLF")
    (property "Manufacturer" "Bourns")
    (property "Public" "False")
    (property "Sheetfile" "interfaces.kicad_sch")
    (property "Sheetname" "Interfaces")
    (property "Tolerance" "1%")
    (property "Val" "357k")
    (property "ki_description" "SMD Chip Resistor")
    (property "ki_keywords" "0402, SMT, RESISTOR, PASSIVE")
    (attr smd)
    (fp_text reference "R50" (at -2.2 -0.03) (layer "B.SilkS")
        (effects (font (size 0.7 0.7) (thickness 0.127)) (justify mirror))
    )
    (fp_text value "R_357k_0402" (at 0 -1.17) (layer "B.Fab")
        (effects (font (size 1 1) (thickness 0.15)) (justify mirror))
    )
    (fp_text user "License: Apache-2.0" (at -0.95 -5.169 180) (layer "B.Fab") hide
        (effects (font (size 0.7 0.7) (thickness 0.15)) (justify left bottom mirror))
    )
    (fp_text user "${REFERENCE}" (at 0 0) (layer "B.Fab")
        (effects (font (size 0.25 0.25) (thickness 0.04)) (justify mirror))
    )
    (fp_text user "Author: Antmicro" (at -0.95 -4.169 180) (layer "B.Fab") hide
        (effects (font (size 0.7 0.7) (thickness 0.15)) (justify left bottom mirror))
    )
    (fp_rect (start -0.925 0.47) (end 0.925 -0.47)
      (stroke (width 0.05) (type default)) (fill none) (layer "B.CrtYd"))
    (fp_rect (start -0.5 0.25) (end 0.5 -0.25)
      (stroke (width 0.15) (type solid)) (fill none) (layer "B.Fab"))
    (pad "1" smd roundrect (at -0.48 0) (size 0.59 0.64) (layers "B.Cu" "B.Paste" "B.Mask") (roundrect_rratio 0.25)
      (net 2 "VCC3V3") (pintype "passive"))
    (pad "2" smd roundrect (at 0.48 0) (size 0.59 0.64) (layers "B.Cu" "B.Paste" "B.Mask") (roundrect_rratio 0.25)
      (net 168 "I3C[0]_SCL_3V3") (pintype "passive"))
  )

  (footprint "antmicro-footprints:R_0402_1005Metric" (layer "B.Cu")
    (at 90.649 145.0742)
    (descr "Resistor SMD 0402")
    (tags "resistor SMD 0402")
    (property "Author" "Antmicro")
    (property "License" "Apache-2.0")
    (property "MPN" "CR0402-FX-3573GLF")
    (property "Manufacturer" "Bourns")
    (property "Public" "False")
    (property "Sheetfile" "interfaces.kicad_sch")
    (property "Sheetname" "Interfaces")
    (property "Tolerance" "1%")
    (property "Val" "357k")
    (property "ki_description" "SMD Chip Resistor")
    (property "ki_keywords" "0402, SMT, RESISTOR, PASSIVE")
    (attr smd)
    (fp_text reference "R51" (at -2.2 -0.03) (layer "B.SilkS")
        (effects (font (size 0.7 0.7) (thickness 0.127)) (justify mirror))
    )
    (fp_text value "R_357k_0402" (at 0 -1.17) (layer "B.Fab")
        (effects (font (size 1 1) (thickness 0.15)) (justify mirror))
    )
    (fp_text user "${REFERENCE}" (at 0 0) (layer "B.Fab")
        (effects (font (size 0.25 0.25) (thickness 0.04)) (justify mirror))
    )
    (fp_text user "Author: Antmicro" (at -0.95 -4.169 180) (layer "B.Fab") hide
        (effects (font (size 0.7 0.7) (thickness 0.15)) (justify left bottom mirror))
    )
    (fp_text user "License: Apache-2.0" (at -0.95 -5.169 180) (layer "B.Fab") hide
        (effects (font (size 0.7 0.7) (thickness 0.15)) (justify left bottom mirror))
    )
    (fp_rect (start -0.925 0.47) (end 0.925 -0.47)
      (stroke (width 0.05) (type default)) (fill none) (layer "B.CrtYd"))
    (fp_rect (start -0.5 0.25) (end 0.5 -0.25)
      (stroke (width 0.15) (type solid)) (fill none) (layer "B.Fab"))
    (pad "1" smd roundrect (at -0.48 0) (size 0.59 0.64) (layers "B.Cu" "B.Paste" "B.Mask") (roundrect_rratio 0.25)
      (net 2 "VCC3V3") (pintype "passive"))
    (pad "2" smd roundrect (at 0.48 0) (size 0.59 0.64) (layers "B.Cu" "B.Paste" "B.Mask") (roundrect_rratio 0.25)
      (net 169 "I3C[1]_SDA_3V3") (pintype "passive"))
  )

  (footprint "antmicro-footprints:R_0402_1005Metric" (layer "B.Cu")
    (at 90.649 144.0742)
    (descr "Resistor SMD 0402")
    (tags "resistor SMD 0402")
    (property "Author" "Antmicro")
    (property "License" "Apache-2.0")
    (property "MPN" "CR0402-FX-3573GLF")
    (property "Manufacturer" "Bourns")
    (property "Public" "False")
    (property "Sheetfile" "interfaces.kicad_sch")
    (property "Sheetname" "Interfaces")
    (property "Tolerance" "1%")
    (property "Val" "357k")
    (property "ki_description" "SMD Chip Resistor")
    (property "ki_keywords" "0402, SMT, RESISTOR, PASSIVE")
    (attr smd)
    (fp_text reference "R52" (at -2.2 -0.03) (layer "B.SilkS")
        (effects (font (size 0.7 0.7) (thickness 0.127)) (justify mirror))
    )
    (fp_text value "R_357k_0402" (at 0 -1.17) (layer "B.Fab")
        (effects (font (size 1 1) (thickness 0.15)) (justify mirror))
    )
    (fp_text user "Author: Antmicro" (at -0.95 -4.169 180) (layer "B.Fab") hide
        (effects (font (size 0.7 0.7) (thickness 0.15)) (justify left bottom mirror))
    )
    (fp_text user "License: Apache-2.0" (at -0.95 -5.169 180) (layer "B.Fab") hide
        (effects (font (size 0.7 0.7) (thickness 0.15)) (justify left bottom mirror))
    )
    (fp_text user "${REFERENCE}" (at 0 0) (layer "B.Fab")
        (effects (font (size 0.25 0.25) (thickness 0.04)) (justify mirror))
    )
    (fp_rect (start -0.925 0.47) (end 0.925 -0.47)
      (stroke (width 0.05) (type default)) (fill none) (layer "B.CrtYd"))
    (fp_rect (start -0.5 0.25) (end 0.5 -0.25)
      (stroke (width 0.15) (type solid)) (fill none) (layer "B.Fab"))
    (pad "1" smd roundrect (at -0.48 0) (size 0.59 0.64) (layers "B.Cu" "B.Paste" "B.Mask") (roundrect_rratio 0.25)
      (net 2 "VCC3V3") (pintype "passive"))
    (pad "2" smd roundrect (at 0.48 0) (size 0.59 0.64) (layers "B.Cu" "B.Paste" "B.Mask") (roundrect_rratio 0.25)
      (net 170 "I3C[1]_SCL_3V3") (pintype "passive"))
  )

  (footprint "antmicro-footprints:R_0402_1005Metric" (layer "B.Cu")
    (at 90.649 147.0742)
    (descr "Resistor SMD 0402")
    (tags "resistor SMD 0402")
    (property "Author" "Antmicro")
    (property "License" "Apache-2.0")
    (property "MPN" "CR0402-FX-3573GLF")
    (property "Manufacturer" "Bourns")
    (property "Public" "False")
    (property "Sheetfile" "interfaces.kicad_sch")
    (property "Sheetname" "Interfaces")
    (property "Tolerance" "1%")
    (property "Val" "357k")
    (property "ki_description" "SMD Chip Resistor")
    (property "ki_keywords" "0402, SMT, RESISTOR, PASSIVE")
    (attr smd)
    (fp_text reference "R53" (at -2.2 -0.03) (layer "B.SilkS")
        (effects (font (size 0.7 0.7) (thickness 0.127)) (justify mirror))
    )
    (fp_text value "R_357k_0402" (at 0 -1.17) (layer "B.Fab")
        (effects (font (size 1 1) (thickness 0.15)) (justify mirror))
    )
    (fp_text user "Author: Antmicro" (at -0.95 -4.169 180) (layer "B.Fab") hide
        (effects (font (size 0.7 0.7) (thickness 0.15)) (justify left bottom mirror))
    )
    (fp_text user "${REFERENCE}" (at 0 0) (layer "B.Fab")
        (effects (font (size 0.25 0.25) (thickness 0.04)) (justify mirror))
    )
    (fp_text user "License: Apache-2.0" (at -0.95 -5.169 180) (layer "B.Fab") hide
        (effects (font (size 0.7 0.7) (thickness 0.15)) (justify left bottom mirror))
    )
    (fp_rect (start -0.925 0.47) (end 0.925 -0.47)
      (stroke (width 0.05) (type default)) (fill none) (layer "B.CrtYd"))
    (fp_rect (start -0.5 0.25) (end 0.5 -0.25)
      (stroke (width 0.15) (type solid)) (fill none) (layer "B.Fab"))
    (pad "1" smd roundrect (at -0.48 0) (size 0.59 0.64) (layers "B.Cu" "B.Paste" "B.Mask") (roundrect_rratio 0.25)
      (net 2 "VCC3V3") (pintype "passive"))
    (pad "2" smd roundrect (at 0.48 0) (size 0.59 0.64) (layers "B.Cu" "B.Paste" "B.Mask") (roundrect_rratio 0.25)
      (net 171 "I3C[2]_SDA_3V3") (pintype "passive"))
  )

  (footprint "antmicro-footprints:R_0402_1005Metric" (layer "B.Cu")
    (at 90.649 146.0742)
    (descr "Resistor SMD 0402")
    (tags "resistor SMD 0402")
    (property "Author" "Antmicro")
    (property "License" "Apache-2.0")
    (property "MPN" "CR0402-FX-3573GLF")
    (property "Manufacturer" "Bourns")
    (property "Public" "False")
    (property "Sheetfile" "interfaces.kicad_sch")
    (property "Sheetname" "Interfaces")
    (property "Tolerance" "1%")
    (property "Val" "357k")
    (property "ki_description" "SMD Chip Resistor")
    (property "ki_keywords" "0402, SMT, RESISTOR, PASSIVE")
    (attr smd)
    (fp_text reference "R54" (at -2.2 -0.03) (layer "B.SilkS")
        (effects (font (size 0.7 0.7) (thickness 0.127)) (justify mirror))
    )
    (fp_text value "R_357k_0402" (at 0 -1.17) (layer "B.Fab")
        (effects (font (size 1 1) (thickness 0.15)) (justify mirror))
    )
    (fp_text user "Author: Antmicro" (at -0.95 -4.169 180) (layer "B.Fab") hide
        (effects (font (size 0.7 0.7) (thickness 0.15)) (justify left bottom mirror))
    )
    (fp_text user "${REFERENCE}" (at 0 0) (layer "B.Fab")
        (effects (font (size 0.25 0.25) (thickness 0.04)) (justify mirror))
    )
    (fp_text user "License: Apache-2.0" (at -0.95 -5.169 180) (layer "B.Fab") hide
        (effects (font (size 0.7 0.7) (thickness 0.15)) (justify left bottom mirror))
    )
    (fp_rect (start -0.925 0.47) (end 0.925 -0.47)
      (stroke (width 0.05) (type default)) (fill none) (layer "B.CrtYd"))
    (fp_rect (start -0.5 0.25) (end 0.5 -0.25)
      (stroke (width 0.15) (type solid)) (fill none) (layer "B.Fab"))
    (pad "1" smd roundrect (at -0.48 0) (size 0.59 0.64) (layers "B.Cu" "B.Paste" "B.Mask") (roundrect_rratio 0.25)
      (net 2 "VCC3V3") (pintype "passive"))
    (pad "2" smd roundrect (at 0.48 0) (size 0.59 0.64) (layers "B.Cu" "B.Paste" "B.Mask") (roundrect_rratio 0.25)
      (net 172 "I3C[2]_SCL_3V3") (pintype "passive"))
  )

  (footprint "antmicro-footprints:R_0402_1005Metric" (layer "B.Cu")
    (at 90.649 149.0742)
    (descr "Resistor SMD 0402")
    (tags "resistor SMD 0402")
    (property "Author" "Antmicro")
    (property "License" "Apache-2.0")
    (property "MPN" "CR0402-FX-3573GLF")
    (property "Manufacturer" "Bourns")
    (property "Public" "False")
    (property "Sheetfile" "interfaces.kicad_sch")
    (property "Sheetname" "Interfaces")
    (property "Tolerance" "1%")
    (property "Val" "357k")
    (property "ki_description" "SMD Chip Resistor")
    (property "ki_keywords" "0402, SMT, RESISTOR, PASSIVE")
    (attr smd)
    (fp_text reference "R55" (at -2.2 -0.03) (layer "B.SilkS")
        (effects (font (size 0.7 0.7) (thickness 0.127)) (justify mirror))
    )
    (fp_text value "R_357k_0402" (at 0 -1.17) (layer "B.Fab")
        (effects (font (size 1 1) (thickness 0.15)) (justify mirror))
    )
    (fp_text user "License: Apache-2.0" (at -0.95 -5.169 180) (layer "B.Fab") hide
        (effects (font (size 0.7 0.7) (thickness 0.15)) (justify left bottom mirror))
    )
    (fp_text user "${REFERENCE}" (at 0 0) (layer "B.Fab")
        (effects (font (size 0.25 0.25) (thickness 0.04)) (justify mirror))
    )
    (fp_text user "Author: Antmicro" (at -0.95 -4.169 180) (layer "B.Fab") hide
        (effects (font (size 0.7 0.7) (thickness 0.15)) (justify left bottom mirror))
    )
    (fp_rect (start -0.925 0.47) (end 0.925 -0.47)
      (stroke (width 0.05) (type default)) (fill none) (layer "B.CrtYd"))
    (fp_rect (start -0.5 0.25) (end 0.5 -0.25)
      (stroke (width 0.15) (type solid)) (fill none) (layer "B.Fab"))
    (pad "1" smd roundrect (at -0.48 0) (size 0.59 0.64) (layers "B.Cu" "B.Paste" "B.Mask") (roundrect_rratio 0.25)
      (net 2 "VCC3V3") (pintype "passive"))
    (pad "2" smd roundrect (at 0.48 0) (size 0.59 0.64) (layers "B.Cu" "B.Paste" "B.Mask") (roundrect_rratio 0.25)
      (net 173 "I3C[3]_SDA_3V3") (pintype "passive"))
  )

  (footprint "antmicro-footprints:R_0402_1005Metric" (layer "B.Cu")
    (at 90.649 148.0742)
    (descr "Resistor SMD 0402")
    (tags "resistor SMD 0402")
    (property "Author" "Antmicro")
    (property "License" "Apache-2.0")
    (property "MPN" "CR0402-FX-3573GLF")
    (property "Manufacturer" "Bourns")
    (property "Public" "False")
    (property "Sheetfile" "interfaces.kicad_sch")
    (property "Sheetname" "Interfaces")
    (property "Tolerance" "1%")
    (property "Val" "357k")
    (property "ki_description" "SMD Chip Resistor")
    (property "ki_keywords" "0402, SMT, RESISTOR, PASSIVE")
    (attr smd)
    (fp_text reference "R56" (at -2.2 -0.03) (layer "B.SilkS")
        (effects (font (size 0.7 0.7) (thickness 0.127)) (justify mirror))
    )
    (fp_text value "R_357k_0402" (at 0 -1.17) (layer "B.Fab")
        (effects (font (size 1 1) (thickness 0.15)) (justify mirror))
    )
    (fp_text user "License: Apache-2.0" (at -0.95 -5.169 180) (layer "B.Fab") hide
        (effects (font (size 0.7 0.7) (thickness 0.15)) (justify left bottom mirror))
    )
    (fp_text user "${REFERENCE}" (at 0 0) (layer "B.Fab")
        (effects (font (size 0.25 0.25) (thickness 0.04)) (justify mirror))
    )
    (fp_text user "Author: Antmicro" (at -0.95 -4.169 180) (layer "B.Fab") hide
        (effects (font (size 0.7 0.7) (thickness 0.15)) (justify left bottom mirror))
    )
    (fp_rect (start -0.925 0.47) (end 0.925 -0.47)
      (stroke (width 0.05) (type default)) (fill none) (layer "B.CrtYd"))
    (fp_rect (start -0.5 0.25) (end 0.5 -0.25)
      (stroke (width 0.15) (type solid)) (fill none) (layer "B.Fab"))
    (pad "1" smd roundrect (at -0.48 0) (size 0.59 0.64) (layers "B.Cu" "B.Paste" "B.Mask") (roundrect_rratio 0.25)
      (net 2 "VCC3V3") (pintype "passive"))
    (pad "2" smd roundrect (at 0.48 0) (size 0.59 0.64) (layers "B.Cu" "B.Paste" "B.Mask") (roundrect_rratio 0.25)
      (net 174 "I3C[3]_SCL_3V3") (pintype "passive"))
  )

  (footprint "antmicro-footprints:C_0402_1005Metric" (layer "B.Cu")
    (at 85.8 94.6 180)
    (descr "Capacitor SMD 0402")
    (tags "capacitor SMD 0402")
    (property "Author" "Antmicro")
    (property "Dielectric" "X5R")
    (property "License" "Apache-2.0")
    (property "MPN" "GRM155R61H104KE14D")
    (property "Manufacturer" "Murata")
    (property "Public" "False")
    (property "Sheetfile" "interfaces.kicad_sch")
    (property "Sheetname" "Interfaces")
    (property "Val" "100n")
    (property "Voltage" "50V")
    (property "ki_description" "SMD Multilayer Ceramic Capacitor, 0.1 µF, 50 V, 0402 [1005 Metric], ± 10%, X5R, GRM Series")
    (property "ki_keywords" "0402, SMT, CAPACITOR, PASSIVE, CERAMIC, MLCC")
    (attr smd)
    (fp_text reference "C242" (at 0.066667 9.47) (layer "B.SilkS")
        (effects (font (size 0.7 0.7) (thickness 0.127)) (justify mirror))
    )
    (fp_text value "C_100n_0402" (at 0 -1.17) (layer "B.Fab")
        (effects (font (size 1 1) (thickness 0.15)) (justify mirror))
    )
    (fp_text user "License: Apache-2.0" (at -0.939 -5.799) (layer "B.Fab") hide
        (effects (font (size 0.7 0.7) (thickness 0.15)) (justify left bottom mirror))
    )
    (fp_text user "${REFERENCE}" (at 0 0) (layer "B.Fab")
        (effects (font (size 0.25 0.25) (thickness 0.04)) (justify mirror))
    )
    (fp_text user "Author: Antmicro" (at -0.939 -3.399) (layer "B.Fab") hide
        (effects (font (size 0.7 0.7) (thickness 0.15)) (justify left bottom mirror))
    )
    (fp_rect (start -0.925 0.47) (end 0.925 -0.47)
      (stroke (width 0.05) (type default)) (fill none) (layer "B.CrtYd"))
    (fp_line (start -0.494 -0.248) (end -0.494 0.25)
      (stroke (width 0.15) (type solid)) (layer "B.Fab"))
    (fp_line (start -0.494 0.25) (end 0.504 0.25)
      (stroke (width 0.15) (type solid)) (layer "B.Fab"))
    (fp_line (start 0.504 -0.248) (end -0.494 -0.248)
      (stroke (width 0.15) (type solid)) (layer "B.Fab"))
    (fp_line (start 0.504 0.25) (end 0.504 -0.248)
      (stroke (width 0.15) (type solid)) (layer "B.Fab"))
    (pad "1" smd roundrect (at -0.48 0 180) (size 0.59 0.64) (layers "B.Cu" "B.Paste" "B.Mask") (roundrect_rratio 0.25)
      (net 1 "GND") (pintype "passive"))
    (pad "2" smd roundrect (at 0.48 0 180) (size 0.59 0.64) (layers "B.Cu" "B.Paste" "B.Mask") (roundrect_rratio 0.25)
      (net 2 "VCC3V3") (pintype "passive"))
  )

  (footprint "antmicro-footprints:C_0402_1005Metric" (layer "B.Cu")
    (at 85.8 96.6 180)
    (descr "Capacitor SMD 0402")
    (tags "capacitor SMD 0402")
    (property "Author" "Antmicro")
    (property "Dielectric" "X5R")
    (property "License" "Apache-2.0")
    (property "MPN" "GRM155R61H104KE14D")
    (property "Manufacturer" "Murata")
    (property "Public" "False")
    (property "Sheetfile" "interfaces.kicad_sch")
    (property "Sheetname" "Interfaces")
    (property "Val" "100n")
    (property "Voltage" "50V")
    (property "ki_description" "SMD Multilayer Ceramic Capacitor, 0.1 µF, 50 V, 0402 [1005 Metric], ± 10%, X5R, GRM Series")
    (property "ki_keywords" "0402, SMT, CAPACITOR, PASSIVE, CERAMIC, MLCC")
    (attr smd)
    (fp_text reference "C243" (at 0.066667 9.3775) (layer "B.SilkS")
        (effects (font (size 0.7 0.7) (thickness 0.127)) (justify mirror))
    )
    (fp_text value "C_100n_0402" (at 0 -1.17) (layer "B.Fab")
        (effects (font (size 1 1) (thickness 0.15)) (justify mirror))
    )
    (fp_text user "License: Apache-2.0" (at -0.939 -5.799) (layer "B.Fab") hide
        (effects (font (size 0.7 0.7) (thickness 0.15)) (justify left bottom mirror))
    )
    (fp_text user "Author: Antmicro" (at -0.939 -3.399) (layer "B.Fab") hide
        (effects (font (size 0.7 0.7) (thickness 0.15)) (justify left bottom mirror))
    )
    (fp_text user "${REFERENCE}" (at 0 0) (layer "B.Fab")
        (effects (font (size 0.25 0.25) (thickness 0.04)) (justify mirror))
    )
    (fp_rect (start -0.925 0.47) (end 0.925 -0.47)
      (stroke (width 0.05) (type default)) (fill none) (layer "B.CrtYd"))
    (fp_line (start -0.494 -0.248) (end -0.494 0.25)
      (stroke (width 0.15) (type solid)) (layer "B.Fab"))
    (fp_line (start -0.494 0.25) (end 0.504 0.25)
      (stroke (width 0.15) (type solid)) (layer "B.Fab"))
    (fp_line (start 0.504 -0.248) (end -0.494 -0.248)
      (stroke (width 0.15) (type solid)) (layer "B.Fab"))
    (fp_line (start 0.504 0.25) (end 0.504 -0.248)
      (stroke (width 0.15) (type solid)) (layer "B.Fab"))
    (pad "1" smd roundrect (at -0.48 0 180) (size 0.59 0.64) (layers "B.Cu" "B.Paste" "B.Mask") (roundrect_rratio 0.25)
      (net 1 "GND") (pintype "passive"))
    (pad "2" smd roundrect (at 0.48 0 180) (size 0.59 0.64) (layers "B.Cu" "B.Paste" "B.Mask") (roundrect_rratio 0.25)
      (net 2 "VCC3V3") (pintype "passive"))
  )

  (footprint "antmicro-footprints:C_0402_1005Metric" (layer "B.Cu")
    (at 85.8 98.6 180)
    (descr "Capacitor SMD 0402")
    (tags "capacitor SMD 0402")
    (property "Author" "Antmicro")
    (property "Dielectric" "X5R")
    (property "License" "Apache-2.0")
    (property "MPN" "GRM155R61H104KE14D")
    (property "Manufacturer" "Murata")
    (property "Public" "False")
    (property "Sheetfile" "interfaces.kicad_sch")
    (property "Sheetname" "Interfaces")
    (property "Val" "100n")
    (property "Voltage" "50V")
    (property "ki_description" "SMD Multilayer Ceramic Capacitor, 0.1 µF, 50 V, 0402 [1005 Metric], ± 10%, X5R, GRM Series")
    (property "ki_keywords" "0402, SMT, CAPACITOR, PASSIVE, CERAMIC, MLCC")
    (attr smd)
    (fp_text reference "C244" (at 0.066667 9.285) (layer "B.SilkS")
        (effects (font (size 0.7 0.7) (thickness 0.127)) (justify mirror))
    )
    (fp_text value "C_100n_0402" (at 0 -1.17) (layer "B.Fab")
        (effects (font (size 1 1) (thickness 0.15)) (justify mirror))
    )
    (fp_text user "${REFERENCE}" (at 0 0) (layer "B.Fab")
        (effects (font (size 0.25 0.25) (thickness 0.04)) (justify mirror))
    )
    (fp_text user "License: Apache-2.0" (at -0.939 -5.799) (layer "B.Fab") hide
        (effects (font (size 0.7 0.7) (thickness 0.15)) (justify left bottom mirror))
    )
    (fp_text user "Author: Antmicro" (at -0.939 -3.399) (layer "B.Fab") hide
        (effects (font (size 0.7 0.7) (thickness 0.15)) (justify left bottom mirror))
    )
    (fp_rect (start -0.925 0.47) (end 0.925 -0.47)
      (stroke (width 0.05) (type default)) (fill none) (layer "B.CrtYd"))
    (fp_line (start -0.494 -0.248) (end -0.494 0.25)
      (stroke (width 0.15) (type solid)) (layer "B.Fab"))
    (fp_line (start -0.494 0.25) (end 0.504 0.25)
      (stroke (width 0.15) (type solid)) (layer "B.Fab"))
    (fp_line (start 0.504 -0.248) (end -0.494 -0.248)
      (stroke (width 0.15) (type solid)) (layer "B.Fab"))
    (fp_line (start 0.504 0.25) (end 0.504 -0.248)
      (stroke (width 0.15) (type solid)) (layer "B.Fab"))
    (pad "1" smd roundrect (at -0.48 0 180) (size 0.59 0.64) (layers "B.Cu" "B.Paste" "B.Mask") (roundrect_rratio 0.25)
      (net 1 "GND") (pintype "passive"))
    (pad "2" smd roundrect (at 0.48 0 180) (size 0.59 0.64) (layers "B.Cu" "B.Paste" "B.Mask") (roundrect_rratio 0.25)
      (net 2 "VCC3V3") (pintype "passive"))
  )

  (footprint "antmicro-footprints:C_0402_1005Metric" (layer "B.Cu")
    (at 85.8 99.6 180)
    (descr "Capacitor SMD 0402")
    (tags "capacitor SMD 0402")
    (property "Author" "Antmicro")
    (property "Dielectric" "X5R")
    (property "License" "Apache-2.0")
    (property "MPN" "GRM155R61H104KE14D")
    (property "Manufacturer" "Murata")
    (property "Public" "False")
    (property "Sheetfile" "interfaces.kicad_sch")
    (property "Sheetname" "Interfaces")
    (property "Val" "100n")
    (property "Voltage" "50V")
    (property "ki_description" "SMD Multilayer Ceramic Capacitor, 0.1 µF, 50 V, 0402 [1005 Metric], ± 10%, X5R, GRM Series")
    (property "ki_keywords" "0402, SMT, CAPACITOR, PASSIVE, CERAMIC, MLCC")
    (attr smd)
    (fp_text reference "C245" (at 0.066667 9.23875) (layer "B.SilkS")
        (effects (font (size 0.7 0.7) (thickness 0.127)) (justify mirror))
    )
    (fp_text value "C_100n_0402" (at 0 -1.17) (layer "B.Fab")
        (effects (font (size 1 1) (thickness 0.15)) (justify mirror))
    )
    (fp_text user "Author: Antmicro" (at -0.939 -3.399) (layer "B.Fab") hide
        (effects (font (size 0.7 0.7) (thickness 0.15)) (justify left bottom mirror))
    )
    (fp_text user "License: Apache-2.0" (at -0.939 -5.799) (layer "B.Fab") hide
        (effects (font (size 0.7 0.7) (thickness 0.15)) (justify left bottom mirror))
    )
    (fp_text user "${REFERENCE}" (at 0 0) (layer "B.Fab")
        (effects (font (size 0.25 0.25) (thickness 0.04)) (justify mirror))
    )
    (fp_rect (start -0.925 0.47) (end 0.925 -0.47)
      (stroke (width 0.05) (type default)) (fill none) (layer "B.CrtYd"))
    (fp_line (start -0.494 -0.248) (end -0.494 0.25)
      (stroke (width 0.15) (type solid)) (layer "B.Fab"))
    (fp_line (start -0.494 0.25) (end 0.504 0.25)
      (stroke (width 0.15) (type solid)) (layer "B.Fab"))
    (fp_line (start 0.504 -0.248) (end -0.494 -0.248)
      (stroke (width 0.15) (type solid)) (layer "B.Fab"))
    (fp_line (start 0.504 0.25) (end 0.504 -0.248)
      (stroke (width 0.15) (type solid)) (layer "B.Fab"))
    (pad "1" smd roundrect (at -0.48 0 180) (size 0.59 0.64) (layers "B.Cu" "B.Paste" "B.Mask") (roundrect_rratio 0.25)
      (net 1 "GND") (pintype "passive"))
    (pad "2" smd roundrect (at 0.48 0 180) (size 0.59 0.64) (layers "B.Cu" "B.Paste" "B.Mask") (roundrect_rratio 0.25)
      (net 2 "VCC3V3") (pintype "passive"))
  )

  (footprint "antmicro-footprints:C_0402_1005Metric" (layer "B.Cu")
    (at 85.8 100.6 180)
    (descr "Capacitor SMD 0402")
    (tags "capacitor SMD 0402")
    (property "Author" "Antmicro")
    (property "Dielectric" "X5R")
    (property "License" "Apache-2.0")
    (property "MPN" "GRM155R61H104KE14D")
    (property "Manufacturer" "Murata")
    (property "Public" "False")
    (property "Sheetfile" "interfaces.kicad_sch")
    (property "Sheetname" "Interfaces")
    (property "Val" "100n")
    (property "Voltage" "50V")
    (property "ki_description" "SMD Multilayer Ceramic Capacitor, 0.1 µF, 50 V, 0402 [1005 Metric], ± 10%, X5R, GRM Series")
    (property "ki_keywords" "0402, SMT, CAPACITOR, PASSIVE, CERAMIC, MLCC")
    (attr smd)
    (fp_text reference "C246" (at 0.066667 9.1925) (layer "B.SilkS")
        (effects (font (size 0.7 0.7) (thickness 0.127)) (justify mirror))
    )
    (fp_text value "C_100n_0402" (at 0 -1.17) (layer "B.Fab")
        (effects (font (size 1 1) (thickness 0.15)) (justify mirror))
    )
    (fp_text user "${REFERENCE}" (at 0 0) (layer "B.Fab")
        (effects (font (size 0.25 0.25) (thickness 0.04)) (justify mirror))
    )
    (fp_text user "License: Apache-2.0" (at -0.939 -5.799) (layer "B.Fab") hide
        (effects (font (size 0.7 0.7) (thickness 0.15)) (justify left bottom mirror))
    )
    (fp_text user "Author: Antmicro" (at -0.939 -3.399) (layer "B.Fab") hide
        (effects (font (size 0.7 0.7) (thickness 0.15)) (justify left bottom mirror))
    )
    (fp_rect (start -0.925 0.47) (end 0.925 -0.47)
      (stroke (width 0.05) (type default)) (fill none) (layer "B.CrtYd"))
    (fp_line (start -0.494 -0.248) (end -0.494 0.25)
      (stroke (width 0.15) (type solid)) (layer "B.Fab"))
    (fp_line (start -0.494 0.25) (end 0.504 0.25)
      (stroke (width 0.15) (type solid)) (layer "B.Fab"))
    (fp_line (start 0.504 -0.248) (end -0.494 -0.248)
      (stroke (width 0.15) (type solid)) (layer "B.Fab"))
    (fp_line (start 0.504 0.25) (end 0.504 -0.248)
      (stroke (width 0.15) (type solid)) (layer "B.Fab"))
    (pad "1" smd roundrect (at -0.48 0 180) (size 0.59 0.64) (layers "B.Cu" "B.Paste" "B.Mask") (roundrect_rratio 0.25)
      (net 1 "GND") (pintype "passive"))
    (pad "2" smd roundrect (at 0.48 0 180) (size 0.59 0.64) (layers "B.Cu" "B.Paste" "B.Mask") (roundrect_rratio 0.25)
      (net 2 "VCC3V3") (pintype "passive"))
  )

  (footprint "antmicro-footprints:C_0402_1005Metric" (layer "B.Cu")
    (at 85.8 101.6 180)
    (descr "Capacitor SMD 0402")
    (tags "capacitor SMD 0402")
    (property "Author" "Antmicro")
    (property "Dielectric" "X5R")
    (property "License" "Apache-2.0")
    (property "MPN" "GRM155R61H104KE14D")
    (property "Manufacturer" "Murata")
    (property "Public" "False")
    (property "Sheetfile" "interfaces.kicad_sch")
    (property "Sheetname" "Interfaces")
    (property "Val" "100n")
    (property "Voltage" "50V")
    (property "ki_description" "SMD Multilayer Ceramic Capacitor, 0.1 µF, 50 V, 0402 [1005 Metric], ± 10%, X5R, GRM Series")
    (property "ki_keywords" "0402, SMT, CAPACITOR, PASSIVE, CERAMIC, MLCC")
    (attr smd)
    (fp_text reference "C247" (at 0.066667 9.14625) (layer "B.SilkS")
        (effects (font (size 0.7 0.7) (thickness 0.127)) (justify mirror))
    )
    (fp_text value "C_100n_0402" (at 0 -1.17) (layer "B.Fab")
        (effects (font (size 1 1) (thickness 0.15)) (justify mirror))
    )
    (fp_text user "Author: Antmicro" (at -0.939 -3.399) (layer "B.Fab") hide
        (effects (font (size 0.7 0.7) (thickness 0.15)) (justify left bottom mirror))
    )
    (fp_text user "${REFERENCE}" (at 0 0) (layer "B.Fab")
        (effects (font (size 0.25 0.25) (thickness 0.04)) (justify mirror))
    )
    (fp_text user "License: Apache-2.0" (at -0.939 -5.799) (layer "B.Fab") hide
        (effects (font (size 0.7 0.7) (thickness 0.15)) (justify left bottom mirror))
    )
    (fp_rect (start -0.925 0.47) (end 0.925 -0.47)
      (stroke (width 0.05) (type default)) (fill none) (layer "B.CrtYd"))
    (fp_line (start -0.494 -0.248) (end -0.494 0.25)
      (stroke (width 0.15) (type solid)) (layer "B.Fab"))
    (fp_line (start -0.494 0.25) (end 0.504 0.25)
      (stroke (width 0.15) (type solid)) (layer "B.Fab"))
    (fp_line (start 0.504 -0.248) (end -0.494 -0.248)
      (stroke (width 0.15) (type solid)) (layer "B.Fab"))
    (fp_line (start 0.504 0.25) (end 0.504 -0.248)
      (stroke (width 0.15) (type solid)) (layer "B.Fab"))
    (pad "1" smd roundrect (at -0.48 0 180) (size 0.59 0.64) (layers "B.Cu" "B.Paste" "B.Mask") (roundrect_rratio 0.25)
      (net 1 "GND") (pintype "passive"))
    (pad "2" smd roundrect (at 0.48 0 180) (size 0.59 0.64) (layers "B.Cu" "B.Paste" "B.Mask") (roundrect_rratio 0.25)
      (net 2 "VCC3V3") (pintype "passive"))
  )

  (footprint "antmicro-footprints:R_0402_1005Metric" (layer "B.Cu")
    (at 94.575 95.05 180)
    (descr "Resistor SMD 0402")
    (tags "resistor SMD 0402")
    (property "Author" "Antmicro")
    (property "License" "Apache-2.0")
    (property "MPN" "CR0402-FX-4702GLF")
    (property "Manufacturer" "Bourns")
    (property "Public" "False")
    (property "Sheetfile" "interfaces.kicad_sch")
    (property "Sheetname" "Interfaces")
    (property "Tolerance" "1%")
    (property "Val" "47k")
    (property "ki_description" "SMD Chip Resistor, 47 kohm, ± 1%, 62.5 mW, 0402 [1005 Metric], Thick Film, General Purpose")
    (property "ki_keywords" "0402, SMT, RESISTOR, PASSIVE")
    (attr smd)
    (fp_text reference "R67" (at 0.025 -7.55) (layer "B.SilkS")
        (effects (font (size 0.7 0.7) (thickness 0.127)) (justify mirror))
    )
    (fp_text value "R_47k_0402" (at 0 -1.17) (layer "B.Fab")
        (effects (font (size 1 1) (thickness 0.15)) (justify mirror))
    )
    (fp_text user "License: Apache-2.0" (at -0.95 -5.169) (layer "B.Fab") hide
        (effects (font (size 0.7 0.7) (thickness 0.15)) (justify left bottom mirror))
    )
    (fp_text user "Author: Antmicro" (at -0.95 -4.169) (layer "B.Fab") hide
        (effects (font (size 0.7 0.7) (thickness 0.15)) (justify left bottom mirror))
    )
    (fp_text user "${REFERENCE}" (at 0 0) (layer "B.Fab")
        (effects (font (size 0.25 0.25) (thickness 0.04)) (justify mirror))
    )
    (fp_rect (start -0.925 0.47) (end 0.925 -0.47)
      (stroke (width 0.05) (type default)) (fill none) (layer "B.CrtYd"))
    (fp_rect (start -0.5 0.25) (end 0.5 -0.25)
      (stroke (width 0.15) (type solid)) (fill none) (layer "B.Fab"))
    (pad "1" smd roundrect (at -0.48 0 180) (size 0.59 0.64) (layers "B.Cu" "B.Paste" "B.Mask") (roundrect_rratio 0.25)
      (net 2 "VCC3V3") (pintype "passive"))
    (pad "2" smd roundrect (at 0.48 0 180) (size 0.59 0.64) (layers "B.Cu" "B.Paste" "B.Mask") (roundrect_rratio 0.25)
      (net 285 "MMC_DAT6") (pintype "passive"))
  )

  (footprint "antmicro-footprints:R_0402_1005Metric" (layer "B.Cu")
    (at 94.55 101.6 180)
    (descr "Resistor SMD 0402")
    (tags "resistor SMD 0402")
    (property "Author" "Antmicro")
    (property "License" "Apache-2.0")
    (property "MPN" "CR0402-FX-4702GLF")
    (property "Manufacturer" "Bourns")
    (property "Public" "False")
    (property "Sheetfile" "interfaces.kicad_sch")
    (property "Sheetname" "Interfaces")
    (property "Tolerance" "1%")
    (property "Val" "47k")
    (property "ki_description" "SMD Chip Resistor, 47 kohm, ± 1%, 62.5 mW, 0402 [1005 Metric], Thick Film, General Purpose")
    (property "ki_keywords" "0402, SMT, RESISTOR, PASSIVE")
    (attr smd)
    (fp_text reference "R62" (at 0 -6.8) (layer "B.SilkS")
        (effects (font (size 0.7 0.7) (thickness 0.127)) (justify mirror))
    )
    (fp_text value "R_47k_0402" (at 0 -1.17) (layer "B.Fab")
        (effects (font (size 1 1) (thickness 0.15)) (justify mirror))
    )
    (fp_text user "${REFERENCE}" (at 0 0) (layer "B.Fab")
        (effects (font (size 0.25 0.25) (thickness 0.04)) (justify mirror))
    )
    (fp_text user "Author: Antmicro" (at -0.95 -4.169) (layer "B.Fab") hide
        (effects (font (size 0.7 0.7) (thickness 0.15)) (justify left bottom mirror))
    )
    (fp_text user "License: Apache-2.0" (at -0.95 -5.169) (layer "B.Fab") hide
        (effects (font (size 0.7 0.7) (thickness 0.15)) (justify left bottom mirror))
    )
    (fp_rect (start -0.925 0.47) (end 0.925 -0.47)
      (stroke (width 0.05) (type default)) (fill none) (layer "B.CrtYd"))
    (fp_rect (start -0.5 0.25) (end 0.5 -0.25)
      (stroke (width 0.15) (type solid)) (fill none) (layer "B.Fab"))
    (pad "1" smd roundrect (at -0.48 0 180) (size 0.59 0.64) (layers "B.Cu" "B.Paste" "B.Mask") (roundrect_rratio 0.25)
      (net 2 "VCC3V3") (pintype "passive"))
    (pad "2" smd roundrect (at 0.48 0 180) (size 0.59 0.64) (layers "B.Cu" "B.Paste" "B.Mask") (roundrect_rratio 0.25)
      (net 280 "MMC_DAT1") (pintype "passive"))
  )

  (footprint "antmicro-footprints:SOT-23-3" (layer "B.Cu")
    (at 67.25 89.1 180)
    (property "Author" "Antmicro")
    (property "License" "Apache-2.0")
    (property "MPN" "2N7002")
    (property "Manufacturer" "ON Semiconductor")
    (property "Sheetfile" "power-supply.kicad_sch")
    (property "Sheetname" "Power supply")
    (property "ki_description" "Power MOSFET, N Channel, 60 V, 115 mA, 1.2 ohm, SOT-23, Surface Mount")
    (property "ki_keywords" "SMT, TRANSISTOR, SEMICONDUCTOR, NMOS")
    (attr smd)
    (fp_text reference "Q16" (at -1.8 1.85 180) (layer "B.SilkS")
        (effects (font (size 0.7 0.7) (thickness 0.127)) (justify mirror))
    )
    (fp_text value "2N7002" (at 0.025 -3.25 180) (layer "B.Fab")
        (effects (font (size 1 1) (thickness 0.15)) (justify mirror))
    )
    (fp_text user "Author: Antmicro" (at -1.837 -5.3) (layer "B.Fab") hide
        (effects (font (size 0.7 0.7) (thickness 0.15)) (justify left bottom mirror))
    )
    (fp_text user "${REFERENCE}" (at -0.125 -0.15 180) (layer "B.Fab")
        (effects (font (size 0.25 0.25) (thickness 0.05)) (justify mirror))
    )
    (fp_text user "License: Apache-2.0" (at -1.8 -6.8) (layer "B.Fab") hide
        (effects (font (size 0.7 0.7) (thickness 0.15)) (justify left bottom mirror))
    )
    (fp_line (start -1.45 1.35) (end -0.85 1.35)
      (stroke (width 0.15) (type solid)) (layer "B.SilkS"))
    (fp_line (start -0.85 1.35) (end -0.7 1.5)
      (stroke (width 0.15) (type solid)) (layer "B.SilkS"))
    (fp_line (start -0.7 -1.5) (end -0.7 -1.35)
      (stroke (width 0.15) (type solid)) (layer "B.SilkS"))
    (fp_line (start 0.7 -1.5) (end -0.7 -1.5)
      (stroke (width 0.15) (type solid)) (layer "B.SilkS"))
    (fp_line (start 0.7 -0.4) (end 0.7 -1.5)
      (stroke (width 0.15) (type solid)) (layer "B.SilkS"))
    (fp_line (start 0.7 0.4) (end 0.7 1.5)
      (stroke (width 0.15) (type solid)) (layer "B.SilkS"))
    (fp_line (start 0.7 1.5) (end -0.7 1.5)
      (stroke (width 0.15) (type solid)) (layer "B.SilkS"))
    (fp_line (start -1.75 -1.4) (end -1.75 -0.5)
      (stroke (width 0.05) (type solid)) (layer "B.CrtYd"))
    (fp_line (start -1.75 -0.5) (end -0.85 -0.5)
      (stroke (width 0.05) (type solid)) (layer "B.CrtYd"))
    (fp_line (start -1.75 0.5) (end -1.75 1.4)
      (stroke (width 0.05) (type solid)) (layer "B.CrtYd"))
    (fp_line (start -0.9 1.4) (end -1.75 1.4)
      (stroke (width 0.05) (type solid)) (layer "B.CrtYd"))
    (fp_line (start -0.9 1.6) (end -0.9 1.4)
      (stroke (width 0.05) (type solid)) (layer "B.CrtYd"))
    (fp_line (start -0.9 1.6) (end 0.825 1.6)
      (stroke (width 0.05) (type solid)) (layer "B.CrtYd"))
    (fp_line (start -0.85 -1.65) (end -0.85 -1.4)
      (stroke (width 0.05) (type solid)) (layer "B.CrtYd"))
    (fp_line (start -0.85 -1.4) (end -1.75 -1.4)
      (stroke (width 0.05) (type solid)) (layer "B.CrtYd"))
    (fp_line (start -0.85 -0.5) (end -0.85 0.5)
      (stroke (width 0.05) (type solid)) (layer "B.CrtYd"))
    (fp_line (start -0.85 0.5) (end -1.75 0.5)
      (stroke (width 0.05) (type solid)) (layer "B.CrtYd"))
    (fp_line (start 0.825 0.45) (end 1.75 0.45)
      (stroke (width 0.05) (type solid)) (layer "B.CrtYd"))
    (fp_line (start 0.825 1.6) (end 0.825 0.45)
      (stroke (width 0.05) (type solid)) (layer "B.CrtYd"))
    (fp_line (start 0.85 -1.65) (end -0.85 -1.65)
      (stroke (width 0.05) (type solid)) (layer "B.CrtYd"))
    (fp_line (start 0.85 -0.45) (end 0.85 -1.65)
      (stroke (width 0.05) (type solid)) (layer "B.CrtYd"))
    (fp_line (start 1.75 -0.45) (end 0.85 -0.45)
      (stroke (width 0.05) (type solid)) (layer "B.CrtYd"))
    (fp_line (start 1.75 0.45) (end 1.75 -0.45)
      (stroke (width 0.05) (type solid)) (layer "B.CrtYd"))
    (fp_line (start -0.712 -1.519) (end 0.688 -1.519)
      (stroke (width 0.15) (type solid)) (layer "B.Fab"))
    (fp_line (start -0.712 1.325) (end -0.712 -1.523)
      (stroke (width 0.15) (type solid)) (layer "B.Fab"))
    (fp_line (start -0.437 1.526) (end -0.712 1.325)
      (stroke (width 0.15) (type solid)) (layer "B.Fab"))
    (fp_line (start -0.437 1.526) (end 0.688 1.526)
      (stroke (width 0.15) (type solid)) (layer "B.Fab"))
    (fp_line (start 0.688 -1.519) (end 0.688 1.52)
      (stroke (width 0.15) (type solid)) (layer "B.Fab"))
    (pad "1" smd roundrect (at -1.1 0.951 180) (size 1 0.6) (layers "B.Cu" "B.Paste" "B.Mask") (roundrect_rratio 0.15)
      (net 224 "/Power supply/1V35_PG") (pinfunction "G") (pintype "passive"))
    (pad "2" smd roundrect (at -1.1 -0.949 180) (size 1 0.6) (layers "B.Cu" "B.Paste" "B.Mask") (roundrect_rratio 0.15)
      (net 1 "GND") (pinfunction "S") (pintype "passive"))
    (pad "3" smd roundrect (at 1.1 0.0005 180) (size 1 0.6) (layers "B.Cu" "B.Paste" "B.Mask") (roundrect_rratio 0.15)
      (net 400 "Net-(Q16-D)") (pinfunction "D") (pintype "passive"))
  )

  (footprint "antmicro-footprints:C_0402_1005Metric" (layer "B.Cu")
    (at 101.75 113.8 90)
    (descr "Capacitor SMD 0402")
    (tags "capacitor SMD 0402")
    (property "Author" "Antmicro")
    (property "Dielectric" "")
    (property "License" "Apache-2.0")
    (property "MPN" "C1005X5R1E474M050BB")
    (property "Manufacturer" "TDK")
    (property "Public" "False")
    (property "Sheetfile" "fpga-banks.kicad_sch")
    (property "Sheetname" "FPGA banks")
    (property "Val" "470n")
    (property "Voltage" "")
    (property "ki_description" "SMD Multilayer Ceramic Capacitor, 0.47 µF, 25 V, 0402 [1005 Metric], ± 20%, X5R, C")
    (property "ki_keywords" "0402, SMT, CAPACITOR, PASSIVE, CERAMIC, MLCC")
    (attr smd)
    (fp_text reference "C205" (at 2.45 0 90) (layer "B.SilkS")
        (effects (font (size 0.7 0.7) (thickness 0.127)) (justify mirror))
    )
    (fp_text value "C_470n_0402" (at 0 -1.17 90) (layer "B.Fab")
        (effects (font (size 1 1) (thickness 0.15)) (justify mirror))
    )
    (fp_text user "License: Apache-2.0" (at -0.939 -5.799 270) (layer "B.Fab") hide
        (effects (font (size 0.7 0.7) (thickness 0.15)) (justify left bottom mirror))
    )
    (fp_text user "${REFERENCE}" (at 0 0 90) (layer "B.Fab")
        (effects (font (size 0.25 0.25) (thickness 0.04)) (justify mirror))
    )
    (fp_text user "Author: Antmicro" (at -0.939 -3.399 270) (layer "B.Fab") hide
        (effects (font (size 0.7 0.7) (thickness 0.15)) (justify left bottom mirror))
    )
    (fp_rect (start -0.925 0.47) (end 0.925 -0.47)
      (stroke (width 0.05) (type default)) (fill none) (layer "B.CrtYd"))
    (fp_line (start -0.494 -0.248) (end -0.494 0.25)
      (stroke (width 0.15) (type solid)) (layer "B.Fab"))
    (fp_line (start -0.494 0.25) (end 0.504 0.25)
      (stroke (width 0.15) (type solid)) (layer "B.Fab"))
    (fp_line (start 0.504 -0.248) (end -0.494 -0.248)
      (stroke (width 0.15) (type solid)) (layer "B.Fab"))
    (fp_line (start 0.504 0.25) (end 0.504 -0.248)
      (stroke (width 0.15) (type solid)) (layer "B.Fab"))
    (pad "1" smd roundrect (at -0.48 0 90) (size 0.59 0.64) (layers "B.Cu" "B.Paste" "B.Mask") (roundrect_rratio 0.25)
      (net 2 "VCC3V3") (pintype "passive"))
    (pad "2" smd roundrect (at 0.48 0 90) (size 0.59 0.64) (layers "B.Cu" "B.Paste" "B.Mask") (roundrect_rratio 0.25)
      (net 1 "GND") (pintype "passive"))
  )

  (footprint "antmicro-footprints:C_0402_1005Metric" (layer "B.Cu")
    (at 114.3 83.45 180)
    (descr "Capacitor SMD 0402")
    (tags "capacitor SMD 0402")
    (property "Author" "Antmicro")
    (property "Dielectric" "X5R")
    (property "License" "Apache-2.0")
    (property "MPN" "GRM155R61H104KE14D")
    (property "Manufacturer" "Murata")
    (property "Public" "False")
    (property "Sheetfile" "ethernet.kicad_sch")
    (property "Sheetname" "Ethernet")
    (property "Val" "100n")
    (property "Voltage" "50V")
    (property "ki_description" "SMD Multilayer Ceramic Capacitor, 0.1 µF, 50 V, 0402 [1005 Metric], ± 10%, X5R, GRM Series")
    (property "ki_keywords" "0402, SMT, CAPACITOR, PASSIVE, CERAMIC, MLCC")
    (attr smd)
    (fp_text reference "C27" (at -0.09 -1.045) (layer "B.SilkS")
        (effects (font (size 0.7 0.7) (thickness 0.127)) (justify mirror))
    )
    (fp_text value "C_100n_0402" (at 0 -1.17) (layer "B.Fab")
        (effects (font (size 1 1) (thickness 0.15)) (justify mirror))
    )
    (fp_text user "License: Apache-2.0" (at -0.939 -5.799) (layer "B.Fab") hide
        (effects (font (size 0.7 0.7) (thickness 0.15)) (justify left bottom mirror))
    )
    (fp_text user "${REFERENCE}" (at 0 0) (layer "B.Fab")
        (effects (font (size 0.25 0.25) (thickness 0.04)) (justify mirror))
    )
    (fp_text user "Author: Antmicro" (at -0.939 -3.399) (layer "B.Fab") hide
        (effects (font (size 0.7 0.7) (thickness 0.15)) (justify left bottom mirror))
    )
    (fp_rect (start -0.925 0.47) (end 0.925 -0.47)
      (stroke (width 0.05) (type default)) (fill none) (layer "B.CrtYd"))
    (fp_line (start -0.494 -0.248) (end -0.494 0.25)
      (stroke (width 0.15) (type solid)) (layer "B.Fab"))
    (fp_line (start -0.494 0.25) (end 0.504 0.25)
      (stroke (width 0.15) (type solid)) (layer "B.Fab"))
    (fp_line (start 0.504 -0.248) (end -0.494 -0.248)
      (stroke (width 0.15) (type solid)) (layer "B.Fab"))
    (fp_line (start 0.504 0.25) (end 0.504 -0.248)
      (stroke (width 0.15) (type solid)) (layer "B.Fab"))
    (pad "1" smd roundrect (at -0.48 0 180) (size 0.59 0.64) (layers "B.Cu" "B.Paste" "B.Mask") (roundrect_rratio 0.25)
      (net 1 "GND") (pintype "passive"))
    (pad "2" smd roundrect (at 0.48 0 180) (size 0.59 0.64) (layers "B.Cu" "B.Paste" "B.Mask") (roundrect_rratio 0.25)
      (net 7 "Net-(J1-TRCT1)") (pintype "passive"))
  )

  (footprint "antmicro-footprints:C_0402_1005Metric" (layer "B.Cu")
    (at 114.3 82.45 180)
    (descr "Capacitor SMD 0402")
    (tags "capacitor SMD 0402")
    (property "Author" "Antmicro")
    (property "Dielectric" "X5R")
    (property "License" "Apache-2.0")
    (property "MPN" "GRM155R61H104KE14D")
    (property "Manufacturer" "Murata")
    (property "Public" "False")
    (property "Sheetfile" "ethernet.kicad_sch")
    (property "Sheetname" "Ethernet")
    (property "Val" "100n")
    (property "Voltage" "50V")
    (property "ki_description" "SMD Multilayer Ceramic Capacitor, 0.1 µF, 50 V, 0402 [1005 Metric], ± 10%, X5R, GRM Series")
    (property "ki_keywords" "0402, SMT, CAPACITOR, PASSIVE, CERAMIC, MLCC")
    (attr smd)
    (fp_text reference "C28" (at -0.42 0.945) (layer "B.SilkS")
        (effects (font (size 0.7 0.7) (thickness 0.127)) (justify mirror))
    )
    (fp_text value "C_100n_0402" (at 0 -1.17) (layer "B.Fab")
        (effects (font (size 1 1) (thickness 0.15)) (justify mirror))
    )
    (fp_text user "${REFERENCE}" (at 0 0 90) (layer "B.Fab")
        (effects (font (size 0.25 0.25) (thickness 0.04)) (justify mirror))
    )
    (fp_text user "License: Apache-2.0" (at -0.939 -5.799) (layer "B.Fab") hide
        (effects (font (size 0.7 0.7) (thickness 0.15)) (justify left bottom mirror))
    )
    (fp_text user "Author: Antmicro" (at -0.939 -3.399) (layer "B.Fab") hide
        (effects (font (size 0.7 0.7) (thickness 0.15)) (justify left bottom mirror))
    )
    (fp_rect (start -0.925 0.47) (end 0.925 -0.47)
      (stroke (width 0.05) (type default)) (fill none) (layer "B.CrtYd"))
    (fp_line (start -0.494 -0.248) (end -0.494 0.25)
      (stroke (width 0.15) (type solid)) (layer "B.Fab"))
    (fp_line (start -0.494 0.25) (end 0.504 0.25)
      (stroke (width 0.15) (type solid)) (layer "B.Fab"))
    (fp_line (start 0.504 -0.248) (end -0.494 -0.248)
      (stroke (width 0.15) (type solid)) (layer "B.Fab"))
    (fp_line (start 0.504 0.25) (end 0.504 -0.248)
      (stroke (width 0.15) (type solid)) (layer "B.Fab"))
    (pad "1" smd roundrect (at -0.48 0 180) (size 0.59 0.64) (layers "B.Cu" "B.Paste" "B.Mask") (roundrect_rratio 0.25)
      (net 1 "GND") (pintype "passive"))
    (pad "2" smd roundrect (at 0.48 0 180) (size 0.59 0.64) (layers "B.Cu" "B.Paste" "B.Mask") (roundrect_rratio 0.25)
      (net 8 "Net-(J1-TRCT2)") (pintype "passive"))
  )

  (footprint "antmicro-footprints:R_0402_1005Metric" (layer "B.Cu")
    (at 97.55 89.75)
    (descr "Resistor SMD 0402")
    (tags "resistor SMD 0402")
    (property "Author" "Antmicro")
    (property "License" "Apache-2.0")
    (property "MPN" "CR0402-FX-1022GLF")
    (property "Manufacturer" "Bourns")
    (property "Public" "False")
    (property "Sheetfile" "ethernet.kicad_sch")
    (property "Sheetname" "Ethernet")
    (property "Tolerance" "1%")
    (property "Val" "10k2")
    (property "ki_description" "SMD Chip Resistor")
    (property "ki_keywords" "0402, SMT, RESISTOR, PASSIVE")
    (attr smd)
    (fp_text reference "R12" (at 1.06 -1.015) (layer "B.SilkS")
        (effects (font (size 0.7 0.7) (thickness 0.127)) (justify mirror))
    )
    (fp_text value "R_10k2_0402" (at 0 -1.17) (layer "B.Fab")
        (effects (font (size 1 1) (thickness 0.15)) (justify mirror))
    )
    (fp_text user "License: Apache-2.0" (at -0.95 -5.169 180) (layer "B.Fab") hide
        (effects (font (size 0.7 0.7) (thickness 0.15)) (justify left bottom mirror))
    )
    (fp_text user "${REFERENCE}" (at 0 0) (layer "B.Fab")
        (effects (font (size 0.25 0.25) (thickness 0.04)) (justify mirror))
    )
    (fp_text user "Author: Antmicro" (at -0.95 -4.169 180) (layer "B.Fab") hide
        (effects (font (size 0.7 0.7) (thickness 0.15)) (justify left bottom mirror))
    )
    (fp_rect (start -0.925 0.47) (end 0.925 -0.47)
      (stroke (width 0.05) (type default)) (fill none) (layer "B.CrtYd"))
    (fp_rect (start -0.5 0.25) (end 0.5 -0.25)
      (stroke (width 0.15) (type solid)) (fill none) (layer "B.Fab"))
    (pad "1" smd roundrect (at -0.48 0) (size 0.59 0.64) (layers "B.Cu" "B.Paste" "B.Mask") (roundrect_rratio 0.25)
      (net 165 "/Ethernet/ETH_LED2") (pintype "passive"))
    (pad "2" smd roundrect (at 0.48 0) (size 0.59 0.64) (layers "B.Cu" "B.Paste" "B.Mask") (roundrect_rratio 0.25)
      (net 2 "VCC3V3") (pintype "passive"))
  )

  (footprint "antmicro-footprints:R_0402_1005Metric" (layer "B.Cu")
    (at 96.05 88 -90)
    (descr "Resistor SMD 0402")
    (tags "resistor SMD 0402")
    (property "Author" "Antmicro")
    (property "License" "Apache-2.0")
    (property "MPN" "CR0402-FX-1001GLF")
    (property "Manufacturer" "Bourns")
    (property "Public" "False")
    (property "Sheetfile" "ethernet.kicad_sch")
    (property "Sheetname" "Ethernet")
    (property "Tolerance" "1%")
    (property "Val" "1k")
    (property "ki_description" "SMD Chip Resistor, 1 kohm, ± 1%, 63 mW, 0402 [1005 Metric], Thick Film, General Purpose")
    (property "ki_keywords" "0402, SMT, RESISTOR, PASSIVE")
    (attr smd)
    (fp_text reference "R16" (at 0 1.17 90) (layer "B.SilkS")
        (effects (font (size 0.7 0.7) (thickness 0.127)) (justify mirror))
    )
    (fp_text value "R_1k_0402" (at 0 -1.17 90) (layer "B.Fab")
        (effects (font (size 1 1) (thickness 0.15)) (justify mirror))
    )
    (fp_text user "License: Apache-2.0" (at -0.95 -5.169 90) (layer "B.Fab") hide
        (effects (font (size 0.7 0.7) (thickness 0.15)) (justify left bottom mirror))
    )
    (fp_text user "Author: Antmicro" (at -0.95 -4.169 90) (layer "B.Fab") hide
        (effects (font (size 0.7 0.7) (thickness 0.15)) (justify left bottom mirror))
    )
    (fp_text user "${REFERENCE}" (at 0 0 90) (layer "B.Fab")
        (effects (font (size 0.25 0.25) (thickness 0.04)) (justify mirror))
    )
    (fp_rect (start -0.925 0.47) (end 0.925 -0.47)
      (stroke (width 0.05) (type default)) (fill none) (layer "B.CrtYd"))
    (fp_rect (start -0.5 0.25) (end 0.5 -0.25)
      (stroke (width 0.15) (type solid)) (fill none) (layer "B.Fab"))
    (pad "1" smd roundrect (at -0.48 0 270) (size 0.59 0.64) (layers "B.Cu" "B.Paste" "B.Mask") (roundrect_rratio 0.25)
      (net 680 "Net-(J1-Pad13)") (pintype "passive"))
    (pad "2" smd roundrect (at 0.48 0 270) (size 0.59 0.64) (layers "B.Cu" "B.Paste" "B.Mask") (roundrect_rratio 0.25)
      (net 164 "/Ethernet/ETH_LED1") (pintype "passive"))
  )

  (footprint "antmicro-footprints:C_0402_1005Metric" (layer "B.Cu")
    (at 83.31 97.95 -90)
    (descr "Capacitor SMD 0402")
    (tags "capacitor SMD 0402")
    (property "Author" "Antmicro")
    (property "Dielectric" "X5R")
    (property "License" "Apache-2.0")
    (property "MPN" "GRM155R61H104KE14D")
    (property "Manufacturer" "Murata")
    (property "Public" "False")
    (property "Sheetfile" "interfaces.kicad_sch")
    (property "Sheetname" "Interfaces")
    (property "Val" "100n")
    (property "Voltage" "50V")
    (property "ki_description" "SMD Multilayer Ceramic Capacitor, 0.1 µF, 50 V, 0402 [1005 Metric], ± 10%, X5R, GRM Series")
    (property "ki_keywords" "0402, SMT, CAPACITOR, PASSIVE, CERAMIC, MLCC")
    (attr smd)
    (fp_text reference "C54" (at -0.05 -1.21 90) (layer "B.SilkS")
        (effects (font (size 0.7 0.7) (thickness 0.127)) (justify mirror))
    )
    (fp_text value "C_100n_0402" (at 0 -1.17 90) (layer "B.Fab")
        (effects (font (size 1 1) (thickness 0.15)) (justify mirror))
    )
    (fp_text user "License: Apache-2.0" (at -0.939 -5.799 90) (layer "B.Fab") hide
        (effects (font (size 0.7 0.7) (thickness 0.15)) (justify left bottom mirror))
    )
    (fp_text user "${REFERENCE}" (at 0 0 90) (layer "B.Fab")
        (effects (font (size 0.25 0.25) (thickness 0.04)) (justify mirror))
    )
    (fp_text user "Author: Antmicro" (at -0.939 -3.399 90) (layer "B.Fab") hide
        (effects (font (size 0.7 0.7) (thickness 0.15)) (justify left bottom mirror))
    )
    (fp_rect (start -0.925 0.47) (end 0.925 -0.47)
      (stroke (width 0.05) (type default)) (fill none) (layer "B.CrtYd"))
    (fp_line (start -0.494 -0.248) (end -0.494 0.25)
      (stroke (width 0.15) (type solid)) (layer "B.Fab"))
    (fp_line (start -0.494 0.25) (end 0.504 0.25)
      (stroke (width 0.15) (type solid)) (layer "B.Fab"))
    (fp_line (start 0.504 -0.248) (end -0.494 -0.248)
      (stroke (width 0.15) (type solid)) (layer "B.Fab"))
    (fp_line (start 0.504 0.25) (end 0.504 -0.248)
      (stroke (width 0.15) (type solid)) (layer "B.Fab"))
    (pad "1" smd roundrect (at -0.48 0 270) (size 0.59 0.64) (layers "B.Cu" "B.Paste" "B.Mask") (roundrect_rratio 0.25)
      (net 1 "GND") (pintype "passive"))
    (pad "2" smd roundrect (at 0.48 0 270) (size 0.59 0.64) (layers "B.Cu" "B.Paste" "B.Mask") (roundrect_rratio 0.25)
      (net 219 "Net-(U6-VDDIM)") (pintype "passive"))
  )

  (footprint "antmicro-footprints:C_0402_1005Metric" (layer "B.Cu")
    (at 128.6 124.6 90)
    (descr "Capacitor SMD 0402")
    (tags "capacitor SMD 0402")
    (property "Author" "Antmicro")
    (property "Dielectric" "X5R")
    (property "License" "Apache-2.0")
    (property "MPN" "GRM155R61H104KE14D")
    (property "Manufacturer" "Murata")
    (property "Public" "False")
    (property "Sheetfile" "interfaces.kicad_sch")
    (property "Sheetname" "Interfaces")
    (property "Val" "100n")
    (property "Voltage" "50V")
    (property "ki_description" "SMD Multilayer Ceramic Capacitor, 0.1 µF, 50 V, 0402 [1005 Metric], ± 10%, X5R, GRM Series")
    (property "ki_keywords" "0402, SMT, CAPACITOR, PASSIVE, CERAMIC, MLCC")
    (attr smd)
    (fp_text reference "C60" (at 0.025 1.01 90) (layer "B.SilkS")
        (effects (font (size 0.7 0.7) (thickness 0.127)) (justify mirror))
    )
    (fp_text value "C_100n_0402" (at 0 -1.17 90) (layer "B.Fab")
        (effects (font (size 1 1) (thickness 0.15)) (justify mirror))
    )
    (fp_text user "License: Apache-2.0" (at -0.939 -5.799 270) (layer "B.Fab") hide
        (effects (font (size 0.7 0.7) (thickness 0.15)) (justify left bottom mirror))
    )
    (fp_text user "${REFERENCE}" (at 0 0 90) (layer "B.Fab")
        (effects (font (size 0.25 0.25) (thickness 0.04)) (justify mirror))
    )
    (fp_text user "Author: Antmicro" (at -0.939 -3.399 270) (layer "B.Fab") hide
        (effects (font (size 0.7 0.7) (thickness 0.15)) (justify left bottom mirror))
    )
    (fp_rect (start -0.925 0.47) (end 0.925 -0.47)
      (stroke (width 0.05) (type default)) (fill none) (layer "B.CrtYd"))
    (fp_line (start -0.494 -0.248) (end -0.494 0.25)
      (stroke (width 0.15) (type solid)) (layer "B.Fab"))
    (fp_line (start -0.494 0.25) (end 0.504 0.25)
      (stroke (width 0.15) (type solid)) (layer "B.Fab"))
    (fp_line (start 0.504 -0.248) (end -0.494 -0.248)
      (stroke (width 0.15) (type solid)) (layer "B.Fab"))
    (fp_line (start 0.504 0.25) (end 0.504 -0.248)
      (stroke (width 0.15) (type solid)) (layer "B.Fab"))
    (pad "1" smd roundrect (at -0.48 0 90) (size 0.59 0.64) (layers "B.Cu" "B.Paste" "B.Mask") (roundrect_rratio 0.25)
      (net 2 "VCC3V3") (pintype "passive"))
    (pad "2" smd roundrect (at 0.48 0 90) (size 0.59 0.64) (layers "B.Cu" "B.Paste" "B.Mask") (roundrect_rratio 0.25)
      (net 1 "GND") (pintype "passive"))
  )

  (footprint "antmicro-footprints:R_0402_1005Metric" (layer "B.Cu")
    (at 127.425 124.625 -90)
    (descr "Resistor SMD 0402")
    (tags "resistor SMD 0402")
    (property "Author" "Antmicro")
    (property "License" "Apache-2.0")
    (property "MPN" "CR0402-FX-1001GLF")
    (property "Manufacturer" "Bourns")
    (property "Public" "False")
    (property "Sheetfile" "interfaces.kicad_sch")
    (property "Sheetname" "Interfaces")
    (property "Tolerance" "1%")
    (property "Val" "1k")
    (property "ki_description" "SMD Chip Resistor, 1 kohm, ± 1%, 63 mW, 0402 [1005 Metric], Thick Film, General Purpose")
    (property "ki_keywords" "0402, SMT, RESISTOR, PASSIVE")
    (attr smd)
    (fp_text reference "R74" (at -2.225 0 -90) (layer "B.SilkS")
        (effects (font (size 0.7 0.7) (thickness 0.127)) (justify mirror))
    )
    (fp_text value "R_1k_0402" (at 0 -1.17 -90) (layer "B.Fab")
        (effects (font (size 1 1) (thickness 0.15)) (justify mirror))
    )
    (fp_text user "${REFERENCE}" (at 0 0 -90) (layer "B.Fab")
        (effects (font (size 0.25 0.25) (thickness 0.04)) (justify mirror))
    )
    (fp_text user "License: Apache-2.0" (at -0.95 -5.169 90) (layer "B.Fab") hide
        (effects (font (size 0.7 0.7) (thickness 0.15)) (justify left bottom mirror))
    )
    (fp_text user "Author: Antmicro" (at -0.95 -4.169 90) (layer "B.Fab") hide
        (effects (font (size 0.7 0.7) (thickness 0.15)) (justify left bottom mirror))
    )
    (fp_rect (start -0.925 0.47) (end 0.925 -0.47)
      (stroke (width 0.05) (type default)) (fill none) (layer "B.CrtYd"))
    (fp_rect (start -0.5 0.25) (end 0.5 -0.25)
      (stroke (width 0.15) (type solid)) (fill none) (layer "B.Fab"))
    (pad "1" smd roundrect (at -0.48 0 270) (size 0.59 0.64) (layers "B.Cu" "B.Paste" "B.Mask") (roundrect_rratio 0.25)
      (net 11 "VCC5V0") (pintype "passive"))
    (pad "2" smd roundrect (at 0.48 0 270) (size 0.59 0.64) (layers "B.Cu" "B.Paste" "B.Mask") (roundrect_rratio 0.25)
      (net 404 "Net-(U8-VBUS)") (pintype "passive"))
  )

  (footprint "antmicro-footprints:C_0402_1005Metric" (layer "B.Cu")
    (at 126.625 130.7 180)
    (descr "Capacitor SMD 0402")
    (tags "capacitor SMD 0402")
    (property "Author" "Antmicro")
    (property "Dielectric" "X5R")
    (property "License" "Apache-2.0")
    (property "MPN" "GRM155R61H104KE14D")
    (property "Manufacturer" "Murata")
    (property "Public" "False")
    (property "Sheetfile" "interfaces.kicad_sch")
    (property "Sheetname" "Interfaces")
    (property "Val" "100n")
    (property "Voltage" "50V")
    (property "ki_description" "SMD Multilayer Ceramic Capacitor, 0.1 µF, 50 V, 0402 [1005 Metric], ± 10%, X5R, GRM Series")
    (property "ki_keywords" "0402, SMT, CAPACITOR, PASSIVE, CERAMIC, MLCC")
    (attr smd)
    (fp_text reference "C73" (at -0.105 -1.035) (layer "B.SilkS")
        (effects (font (size 0.7 0.7) (thickness 0.127)) (justify mirror))
    )
    (fp_text value "C_100n_0402" (at 0 -1.17) (layer "B.Fab")
        (effects (font (size 1 1) (thickness 0.15)) (justify mirror))
    )
    (fp_text user "Author: Antmicro" (at -0.939 -3.399) (layer "B.Fab") hide
        (effects (font (size 0.7 0.7) (thickness 0.15)) (justify left bottom mirror))
    )
    (fp_text user "${REFERENCE}" (at 0 0) (layer "B.Fab")
        (effects (font (size 0.25 0.25) (thickness 0.04)) (justify mirror))
    )
    (fp_text user "License: Apache-2.0" (at -0.939 -5.799) (layer "B.Fab") hide
        (effects (font (size 0.7 0.7) (thickness 0.15)) (justify left bottom mirror))
    )
    (fp_rect (start -0.925 0.47) (end 0.925 -0.47)
      (stroke (width 0.05) (type default)) (fill none) (layer "B.CrtYd"))
    (fp_line (start -0.494 -0.248) (end -0.494 0.25)
      (stroke (width 0.15) (type solid)) (layer "B.Fab"))
    (fp_line (start -0.494 0.25) (end 0.504 0.25)
      (stroke (width 0.15) (type solid)) (layer "B.Fab"))
    (fp_line (start 0.504 -0.248) (end -0.494 -0.248)
      (stroke (width 0.15) (type solid)) (layer "B.Fab"))
    (fp_line (start 0.504 0.25) (end 0.504 -0.248)
      (stroke (width 0.15) (type solid)) (layer "B.Fab"))
    (pad "1" smd roundrect (at -0.48 0 180) (size 0.59 0.64) (layers "B.Cu" "B.Paste" "B.Mask") (roundrect_rratio 0.25)
      (net 1 "GND") (pintype "passive"))
    (pad "2" smd roundrect (at 0.48 0 180) (size 0.59 0.64) (layers "B.Cu" "B.Paste" "B.Mask") (roundrect_rratio 0.25)
      (net 221 "Net-(U8-VDDA1.8)") (pintype "passive"))
  )

  (footprint "antmicro-footprints:C_0402_1005Metric" (layer "B.Cu")
    (at 122.525 130.7)
    (descr "Capacitor SMD 0402")
    (tags "capacitor SMD 0402")
    (property "Author" "Antmicro")
    (property "Dielectric" "")
    (property "License" "Apache-2.0")
    (property "MPN" "GRM155R61A475MEAAD")
    (property "Manufacturer" "Murata")
    (property "Public" "False")
    (property "Sheetfile" "interfaces.kicad_sch")
    (property "Sheetname" "Interfaces")
    (property "Val" "4u7")
    (property "Voltage" "")
    (property "ki_description" "SMD Multilayer Ceramic Capacitor, 4.7 µF, 10 V, 0402 [1005 Metric], ± 20%, X5R, GRM Series")
    (property "ki_keywords" "0402, SMT, CAPACITOR, PASSIVE")
    (attr smd)
    (fp_text reference "C75" (at 0.035 1.415) (layer "B.SilkS")
        (effects (font (size 0.7 0.7) (thickness 0.127)) (justify mirror))
    )
    (fp_text value "C_4u7_0402" (at 0 -1.17) (layer "B.Fab")
        (effects (font (size 1 1) (thickness 0.15)) (justify mirror))
    )
    (fp_text user "Author: Antmicro" (at -0.939 -3.399 180) (layer "B.Fab") hide
        (effects (font (size 0.7 0.7) (thickness 0.15)) (justify left bottom mirror))
    )
    (fp_text user "${REFERENCE}" (at 0 0) (layer "B.Fab")
        (effects (font (size 0.25 0.25) (thickness 0.04)) (justify mirror))
    )
    (fp_text user "License: Apache-2.0" (at -0.939 -5.799 180) (layer "B.Fab") hide
        (effects (font (size 0.7 0.7) (thickness 0.15)) (justify left bottom mirror))
    )
    (fp_rect (start -0.925 0.47) (end 0.925 -0.47)
      (stroke (width 0.05) (type default)) (fill none) (layer "B.CrtYd"))
    (fp_line (start -0.494 -0.248) (end -0.494 0.25)
      (stroke (width 0.15) (type solid)) (layer "B.Fab"))
    (fp_line (start -0.494 0.25) (end 0.504 0.25)
      (stroke (width 0.15) (type solid)) (layer "B.Fab"))
    (fp_line (start 0.504 -0.248) (end -0.494 -0.248)
      (stroke (width 0.15) (type solid)) (layer "B.Fab"))
    (fp_line (start 0.504 0.25) (end 0.504 -0.248)
      (stroke (width 0.15) (type solid)) (layer "B.Fab"))
    (pad "1" smd roundrect (at -0.48 0) (size 0.59 0.64) (layers "B.Cu" "B.Paste" "B.Mask") (roundrect_rratio 0.25)
      (net 1 "GND") (pintype "passive"))
    (pad "2" smd roundrect (at 0.48 0) (size 0.59 0.64) (layers "B.Cu" "B.Paste" "B.Mask") (roundrect_rratio 0.25)
      (net 227 "Net-(C71-Pad1)") (pintype "passive"))
  )

  (footprint "antmicro-footprints:C_0402_1005Metric" (layer "B.Cu")
    (at 124.675 130.7)
    (descr "Capacitor SMD 0402")
    (tags "capacitor SMD 0402")
    (property "Author" "Antmicro")
    (property "Dielectric" "")
    (property "License" "Apache-2.0")
    (property "MPN" "GRM155R61A475MEAAD")
    (property "Manufacturer" "Murata")
    (property "Public" "False")
    (property "Sheetfile" "interfaces.kicad_sch")
    (property "Sheetname" "Interfaces")
    (property "Val" "4u7")
    (property "Voltage" "")
    (property "ki_description" "SMD Multilayer Ceramic Capacitor, 4.7 µF, 10 V, 0402 [1005 Metric], ± 20%, X5R, GRM Series")
    (property "ki_keywords" "0402, SMT, CAPACITOR, PASSIVE")
    (attr smd)
    (fp_text reference "C66" (at 0.035 1.025) (layer "B.SilkS")
        (effects (font (size 0.7 0.7) (thickness 0.127)) (justify mirror))
    )
    (fp_text value "C_4u7_0402" (at 0 -1.17) (layer "B.Fab")
        (effects (font (size 1 1) (thickness 0.15)) (justify mirror))
    )
    (fp_text user "License: Apache-2.0" (at -0.939 -5.799 180) (layer "B.Fab") hide
        (effects (font (size 0.7 0.7) (thickness 0.15)) (justify left bottom mirror))
    )
    (fp_text user "${REFERENCE}" (at 0 0) (layer "B.Fab")
        (effects (font (size 0.25 0.25) (thickness 0.04)) (justify mirror))
    )
    (fp_text user "Author: Antmicro" (at -0.939 -3.399 180) (layer "B.Fab") hide
        (effects (font (size 0.7 0.7) (thickness 0.15)) (justify left bottom mirror))
    )
    (fp_rect (start -0.925 0.47) (end 0.925 -0.47)
      (stroke (width 0.05) (type default)) (fill none) (layer "B.CrtYd"))
    (fp_line (start -0.494 -0.248) (end -0.494 0.25)
      (stroke (width 0.15) (type solid)) (layer "B.Fab"))
    (fp_line (start -0.494 0.25) (end 0.504 0.25)
      (stroke (width 0.15) (type solid)) (layer "B.Fab"))
    (fp_line (start 0.504 -0.248) (end -0.494 -0.248)
      (stroke (width 0.15) (type solid)) (layer "B.Fab"))
    (fp_line (start 0.504 0.25) (end 0.504 -0.248)
      (stroke (width 0.15) (type solid)) (layer "B.Fab"))
    (pad "1" smd roundrect (at -0.48 0) (size 0.59 0.64) (layers "B.Cu" "B.Paste" "B.Mask") (roundrect_rratio 0.25)
      (net 1 "GND") (pintype "passive"))
    (pad "2" smd roundrect (at 0.48 0) (size 0.59 0.64) (layers "B.Cu" "B.Paste" "B.Mask") (roundrect_rratio 0.25)
      (net 221 "Net-(U8-VDDA1.8)") (pintype "passive"))
  )

  (footprint "antmicro-footprints:C_0402_1005Metric" (layer "B.Cu")
    (at 122.515 128.17 180)
    (descr "Capacitor SMD 0402")
    (tags "capacitor SMD 0402")
    (property "Author" "Antmicro")
    (property "Dielectric" "X5R")
    (property "License" "Apache-2.0")
    (property "MPN" "GRM155R61H104KE14D")
    (property "Manufacturer" "Murata")
    (property "Public" "False")
    (property "Sheetfile" "interfaces.kicad_sch")
    (property "Sheetname" "Interfaces")
    (property "Val" "100n")
    (property "Voltage" "50V")
    (property "ki_description" "SMD Multilayer Ceramic Capacitor, 0.1 µF, 50 V, 0402 [1005 Metric], ± 10%, X5R, GRM Series")
    (property "ki_keywords" "0402, SMT, CAPACITOR, PASSIVE, CERAMIC, MLCC")
    (attr smd)
    (fp_text reference "C63" (at 2.01 0.03) (layer "B.SilkS")
        (effects (font (size 0.7 0.7) (thickness 0.127)) (justify mirror))
    )
    (fp_text value "C_100n_0402" (at 0 -1.17) (layer "B.Fab")
        (effects (font (size 1 1) (thickness 0.15)) (justify mirror))
    )
    (fp_text user "${REFERENCE}" (at 0 0) (layer "B.Fab")
        (effects (font (size 0.25 0.25) (thickness 0.04)) (justify mirror))
    )
    (fp_text user "Author: Antmicro" (at -0.939 -3.399) (layer "B.Fab") hide
        (effects (font (size 0.7 0.7) (thickness 0.15)) (justify left bottom mirror))
    )
    (fp_text user "License: Apache-2.0" (at -0.939 -5.799) (layer "B.Fab") hide
        (effects (font (size 0.7 0.7) (thickness 0.15)) (justify left bottom mirror))
    )
    (fp_rect (start -0.925 0.47) (end 0.925 -0.47)
      (stroke (width 0.05) (type default)) (fill none) (layer "B.CrtYd"))
    (fp_line (start -0.494 -0.248) (end -0.494 0.25)
      (stroke (width 0.15) (type solid)) (layer "B.Fab"))
    (fp_line (start -0.494 0.25) (end 0.504 0.25)
      (stroke (width 0.15) (type solid)) (layer "B.Fab"))
    (fp_line (start 0.504 -0.248) (end -0.494 -0.248)
      (stroke (width 0.15) (type solid)) (layer "B.Fab"))
    (fp_line (start 0.504 0.25) (end 0.504 -0.248)
      (stroke (width 0.15) (type solid)) (layer "B.Fab"))
    (pad "1" smd roundrect (at -0.48 0 180) (size 0.59 0.64) (layers "B.Cu" "B.Paste" "B.Mask") (roundrect_rratio 0.25)
      (net 2 "VCC3V3") (pintype "passive"))
    (pad "2" smd roundrect (at 0.48 0 180) (size 0.59 0.64) (layers "B.Cu" "B.Paste" "B.Mask") (roundrect_rratio 0.25)
      (net 1 "GND") (pintype "passive"))
  )

  (footprint "antmicro-footprints:C_0402_1005Metric" (layer "B.Cu")
    (at 122.45 122.45 180)
    (descr "Capacitor SMD 0402")
    (tags "capacitor SMD 0402")
    (property "Author" "Antmicro")
    (property "Dielectric" "X5R")
    (property "License" "Apache-2.0")
    (property "MPN" "GRM155R61H104KE14D")
    (property "Manufacturer" "Murata")
    (property "Public" "False")
    (property "Sheetfile" "interfaces.kicad_sch")
    (property "Sheetname" "Interfaces")
    (property "Val" "100n")
    (property "Voltage" "50V")
    (property "ki_description" "SMD Multilayer Ceramic Capacitor, 0.1 µF, 50 V, 0402 [1005 Metric], ± 10%, X5R, GRM Series")
    (property "ki_keywords" "0402, SMT, CAPACITOR, PASSIVE, CERAMIC, MLCC")
    (attr smd)
    (fp_text reference "C61" (at 1.97 -0.025) (layer "B.SilkS")
        (effects (font (size 0.7 0.7) (thickness 0.127)) (justify mirror))
    )
    (fp_text value "C_100n_0402" (at 0 -1.17) (layer "B.Fab")
        (effects (font (size 1 1) (thickness 0.15)) (justify mirror))
    )
    (fp_text user "Author: Antmicro" (at -0.939 -3.399) (layer "B.Fab") hide
        (effects (font (size 0.7 0.7) (thickness 0.15)) (justify left bottom mirror))
    )
    (fp_text user "${REFERENCE}" (at 0 0) (layer "B.Fab")
        (effects (font (size 0.25 0.25) (thickness 0.04)) (justify mirror))
    )
    (fp_text user "License: Apache-2.0" (at -0.939 -5.799) (layer "B.Fab") hide
        (effects (font (size 0.7 0.7) (thickness 0.15)) (justify left bottom mirror))
    )
    (fp_rect (start -0.925 0.47) (end 0.925 -0.47)
      (stroke (width 0.05) (type default)) (fill none) (layer "B.CrtYd"))
    (fp_line (start -0.494 -0.248) (end -0.494 0.25)
      (stroke (width 0.15) (type solid)) (layer "B.Fab"))
    (fp_line (start -0.494 0.25) (end 0.504 0.25)
      (stroke (width 0.15) (type solid)) (layer "B.Fab"))
    (fp_line (start 0.504 -0.248) (end -0.494 -0.248)
      (stroke (width 0.15) (type solid)) (layer "B.Fab"))
    (fp_line (start 0.504 0.25) (end 0.504 -0.248)
      (stroke (width 0.15) (type solid)) (layer "B.Fab"))
    (pad "1" smd roundrect (at -0.48 0 180) (size 0.59 0.64) (layers "B.Cu" "B.Paste" "B.Mask") (roundrect_rratio 0.25)
      (net 2 "VCC3V3") (pintype "passive"))
    (pad "2" smd roundrect (at 0.48 0 180) (size 0.59 0.64) (layers "B.Cu" "B.Paste" "B.Mask") (roundrect_rratio 0.25)
      (net 1 "GND") (pintype "passive"))
  )

  (footprint "antmicro-footprints:C_0402_1005Metric" (layer "B.Cu")
    (at 127.2 129.7)
    (descr "Capacitor SMD 0402")
    (tags "capacitor SMD 0402")
    (property "Author" "Antmicro")
    (property "Dielectric" "X5R")
    (property "License" "Apache-2.0")
    (property "MPN" "GRM155R61H104KE14D")
    (property "Manufacturer" "Murata")
    (property "Public" "False")
    (property "Sheetfile" "interfaces.kicad_sch")
    (property "Sheetname" "Interfaces")
    (property "Val" "100n")
    (property "Voltage" "50V")
    (property "ki_description" "SMD Multilayer Ceramic Capacitor, 0.1 µF, 50 V, 0402 [1005 Metric], ± 10%, X5R, GRM Series")
    (property "ki_keywords" "0402, SMT, CAPACITOR, PASSIVE, CERAMIC, MLCC")
    (attr smd)
    (fp_text reference "C65" (at -0.02 -0.965) (layer "B.SilkS")
        (effects (font (size 0.7 0.7) (thickness 0.127)) (justify mirror))
    )
    (fp_text value "C_100n_0402" (at 0 -1.17) (layer "B.Fab")
        (effects (font (size 1 1) (thickness 0.15)) (justify mirror))
    )
    (fp_text user "Author: Antmicro" (at -0.939 -3.399 180) (layer "B.Fab") hide
        (effects (font (size 0.7 0.7) (thickness 0.15)) (justify left bottom mirror))
    )
    (fp_text user "License: Apache-2.0" (at -0.939 -5.799 180) (layer "B.Fab") hide
        (effects (font (size 0.7 0.7) (thickness 0.15)) (justify left bottom mirror))
    )
    (fp_text user "${REFERENCE}" (at 0 0) (layer "B.Fab")
        (effects (font (size 0.25 0.25) (thickness 0.04)) (justify mirror))
    )
    (fp_rect (start -0.925 0.47) (end 0.925 -0.47)
      (stroke (width 0.05) (type default)) (fill none) (layer "B.CrtYd"))
    (fp_line (start -0.494 -0.248) (end -0.494 0.25)
      (stroke (width 0.15) (type solid)) (layer "B.Fab"))
    (fp_line (start -0.494 0.25) (end 0.504 0.25)
      (stroke (width 0.15) (type solid)) (layer "B.Fab"))
    (fp_line (start 0.504 -0.248) (end -0.494 -0.248)
      (stroke (width 0.15) (type solid)) (layer "B.Fab"))
    (fp_line (start 0.504 0.25) (end 0.504 -0.248)
      (stroke (width 0.15) (type solid)) (layer "B.Fab"))
    (pad "1" smd roundrect (at -0.48 0) (size 0.59 0.64) (layers "B.Cu" "B.Paste" "B.Mask") (roundrect_rratio 0.25)
      (net 2 "VCC3V3") (pintype "passive"))
    (pad "2" smd roundrect (at 0.48 0) (size 0.59 0.64) (layers "B.Cu" "B.Paste" "B.Mask") (roundrect_rratio 0.25)
      (net 1 "GND") (pintype "passive"))
  )

  (footprint "antmicro-footprints:C_0402_1005Metric" (layer "B.Cu")
    (at 123.2 124.15 180)
    (descr "Capacitor SMD 0402")
    (tags "capacitor SMD 0402")
    (property "Author" "Antmicro")
    (property "Dielectric" "X5R")
    (property "License" "Apache-2.0")
    (property "MPN" "GRM155R61H104KE14D")
    (property "Manufacturer" "Murata")
    (property "Public" "False")
    (property "Sheetfile" "interfaces.kicad_sch")
    (property "Sheetname" "Interfaces")
    (property "Val" "100n")
    (property "Voltage" "50V")
    (property "ki_description" "SMD Multilayer Ceramic Capacitor, 0.1 µF, 50 V, 0402 [1005 Metric], ± 10%, X5R, GRM Series")
    (property "ki_keywords" "0402, SMT, CAPACITOR, PASSIVE, CERAMIC, MLCC")
    (attr smd)
    (fp_text reference "C71" (at 0.02 -1.035) (layer "B.SilkS")
        (effects (font (size 0.7 0.7) (thickness 0.127)) (justify mirror))
    )
    (fp_text value "C_100n_0402" (at 0 -1.17) (layer "B.Fab")
        (effects (font (size 1 1) (thickness 0.15)) (justify mirror))
    )
    (fp_text user "Author: Antmicro" (at -0.939 -3.399) (layer "B.Fab") hide
        (effects (font (size 0.7 0.7) (thickness 0.15)) (justify left bottom mirror))
    )
    (fp_text user "${REFERENCE}" (at 0 0) (layer "B.Fab")
        (effects (font (size 0.25 0.25) (thickness 0.04)) (justify mirror))
    )
    (fp_text user "License: Apache-2.0" (at -0.939 -5.799) (layer "B.Fab") hide
        (effects (font (size 0.7 0.7) (thickness 0.15)) (justify left bottom mirror))
    )
    (fp_rect (start -0.925 0.47) (end 0.925 -0.47)
      (stroke (width 0.05) (type default)) (fill none) (layer "B.CrtYd"))
    (fp_line (start -0.494 -0.248) (end -0.494 0.25)
      (stroke (width 0.15) (type solid)) (layer "B.Fab"))
    (fp_line (start -0.494 0.25) (end 0.504 0.25)
      (stroke (width 0.15) (type solid)) (layer "B.Fab"))
    (fp_line (start 0.504 -0.248) (end -0.494 -0.248)
      (stroke (width 0.15) (type solid)) (layer "B.Fab"))
    (fp_line (start 0.504 0.25) (end 0.504 -0.248)
      (stroke (width 0.15) (type solid)) (layer "B.Fab"))
    (pad "1" smd roundrect (at -0.48 0 180) (size 0.59 0.64) (layers "B.Cu" "B.Paste" "B.Mask") (roundrect_rratio 0.25)
      (net 227 "Net-(C71-Pad1)") (pintype "passive"))
    (pad "2" smd roundrect (at 0.48 0 180) (size 0.59 0.64) (layers "B.Cu" "B.Paste" "B.Mask") (roundrect_rratio 0.25)
      (net 1 "GND") (pintype "passive"))
  )

  (footprint "antmicro-footprints:C_0402_1005Metric" (layer "B.Cu")
    (at 122.515 129.2)
    (descr "Capacitor SMD 0402")
    (tags "capacitor SMD 0402")
    (property "Author" "Antmicro")
    (property "Dielectric" "")
    (property "License" "Apache-2.0")
    (property "MPN" "GRM155R61A475MEAAD")
    (property "Manufacturer" "Murata")
    (property "Public" "False")
    (property "Sheetfile" "interfaces.kicad_sch")
    (property "Sheetname" "Interfaces")
    (property "Val" "4u7")
    (property "Voltage" "")
    (property "ki_description" "SMD Multilayer Ceramic Capacitor, 4.7 µF, 10 V, 0402 [1005 Metric], ± 20%, X5R, GRM Series")
    (property "ki_keywords" "0402, SMT, CAPACITOR, PASSIVE")
    (attr smd)
    (fp_text reference "C68" (at -2.01 0) (layer "B.SilkS")
        (effects (font (size 0.7 0.7) (thickness 0.127)) (justify mirror))
    )
    (fp_text value "C_4u7_0402" (at 0 -1.17) (layer "B.Fab")
        (effects (font (size 1 1) (thickness 0.15)) (justify mirror))
    )
    (fp_text user "Author: Antmicro" (at -0.939 -3.399 180) (layer "B.Fab") hide
        (effects (font (size 0.7 0.7) (thickness 0.15)) (justify left bottom mirror))
    )
    (fp_text user "${REFERENCE}" (at 0 0) (layer "B.Fab")
        (effects (font (size 0.25 0.25) (thickness 0.04)) (justify mirror))
    )
    (fp_text user "License: Apache-2.0" (at -0.939 -5.799 180) (layer "B.Fab") hide
        (effects (font (size 0.7 0.7) (thickness 0.15)) (justify left bottom mirror))
    )
    (fp_rect (start -0.925 0.47) (end 0.925 -0.47)
      (stroke (width 0.05) (type default)) (fill none) (layer "B.CrtYd"))
    (fp_line (start -0.494 -0.248) (end -0.494 0.25)
      (stroke (width 0.15) (type solid)) (layer "B.Fab"))
    (fp_line (start -0.494 0.25) (end 0.504 0.25)
      (stroke (width 0.15) (type solid)) (layer "B.Fab"))
    (fp_line (start 0.504 -0.248) (end -0.494 -0.248)
      (stroke (width 0.15) (type solid)) (layer "B.Fab"))
    (fp_line (start 0.504 0.25) (end 0.504 -0.248)
      (stroke (width 0.15) (type solid)) (layer "B.Fab"))
    (pad "1" smd roundrect (at -0.48 0) (size 0.59 0.64) (layers "B.Cu" "B.Paste" "B.Mask") (roundrect_rratio 0.25)
      (net 1 "GND") (pintype "passive"))
    (pad "2" smd roundrect (at 0.48 0) (size 0.59 0.64) (layers "B.Cu" "B.Paste" "B.Mask") (roundrect_rratio 0.25)
      (net 2 "VCC3V3") (pintype "passive"))
  )

  (footprint "antmicro-footprints:C_0402_1005Metric" (layer "B.Cu")
    (at 122.95 112.45 180)
    (descr "Capacitor SMD 0402")
    (tags "capacitor SMD 0402")
    (property "Author" "Antmicro")
    (property "Dielectric" "X5R")
    (property "License" "Apache-2.0")
    (property "MPN" "GRM155R61H104KE14D")
    (property "Manufacturer" "Murata")
    (property "Public" "False")
    (property "Sheetfile" "interfaces.kicad_sch")
    (property "Sheetname" "Interfaces")
    (property "Val" "100n")
    (property "Voltage" "50V")
    (property "ki_description" "SMD Multilayer Ceramic Capacitor, 0.1 µF, 50 V, 0402 [1005 Metric], ± 10%, X5R, GRM Series")
    (property "ki_keywords" "0402, SMT, CAPACITOR, PASSIVE, CERAMIC, MLCC")
    (attr smd)
    (fp_text reference "C62" (at -0.1 -1.2) (layer "B.SilkS")
        (effects (font (size 0.7 0.7) (thickness 0.127)) (justify mirror))
    )
    (fp_text value "C_100n_0402" (at 0 -1.17) (layer "B.Fab")
        (effects (font (size 1 1) (thickness 0.15)) (justify mirror))
    )
    (fp_text user "License: Apache-2.0" (at -0.939 -5.799) (layer "B.Fab") hide
        (effects (font (size 0.7 0.7) (thickness 0.15)) (justify left bottom mirror))
    )
    (fp_text user "Author: Antmicro" (at -0.939 -3.399) (layer "B.Fab") hide
        (effects (font (size 0.7 0.7) (thickness 0.15)) (justify left bottom mirror))
    )
    (fp_text user "${REFERENCE}" (at 0 0) (layer "B.Fab")
        (effects (font (size 0.25 0.25) (thickness 0.04)) (justify mirror))
    )
    (fp_rect (start -0.925 0.47) (end 0.925 -0.47)
      (stroke (width 0.05) (type default)) (fill none) (layer "B.CrtYd"))
    (fp_line (start -0.494 -0.248) (end -0.494 0.25)
      (stroke (width 0.15) (type solid)) (layer "B.Fab"))
    (fp_line (start -0.494 0.25) (end 0.504 0.25)
      (stroke (width 0.15) (type solid)) (layer "B.Fab"))
    (fp_line (start 0.504 -0.248) (end -0.494 -0.248)
      (stroke (width 0.15) (type solid)) (layer "B.Fab"))
    (fp_line (start 0.504 0.25) (end 0.504 -0.248)
      (stroke (width 0.15) (type solid)) (layer "B.Fab"))
    (pad "1" smd roundrect (at -0.48 0 180) (size 0.59 0.64) (layers "B.Cu" "B.Paste" "B.Mask") (roundrect_rratio 0.25)
      (net 2 "VCC3V3") (pintype "passive"))
    (pad "2" smd roundrect (at 0.48 0 180) (size 0.59 0.64) (layers "B.Cu" "B.Paste" "B.Mask") (roundrect_rratio 0.25)
      (net 1 "GND") (pintype "passive"))
  )

  (footprint "antmicro-footprints:R_0402_1005Metric" (layer "B.Cu")
    (at 83.05 87.55 180)
    (descr "Resistor SMD 0402")
    (tags "resistor SMD 0402")
    (property "Author" "Antmicro")
    (property "License" "Apache-2.0")
    (property "MPN" "CR0402-FX-1002GLF")
    (property "Manufacturer" "Bourns")
    (property "Public" "False")
    (property "Sheetfile" "power-supply.kicad_sch")
    (property "Sheetname" "Power supply")
    (property "Tolerance" "1%")
    (property "Val" "10k")
    (property "ki_description" "SMD Chip Resistor, 10 kohm, ± 1%, 62.5 mW, 0402 [1005 Metric], Thick Film, General Purpose")
    (property "ki_keywords" "0402, SMT, RESISTOR, PASSIVE")
    (attr smd)
    (fp_text reference "R103" (at 0 1.17 180) (layer "B.SilkS")
        (effects (font (size 0.7 0.7) (thickness 0.127)) (justify mirror))
    )
    (fp_text value "R_10k_0402" (at 0 -1.17 180) (layer "B.Fab")
        (effects (font (size 1 1) (thickness 0.15)) (justify mirror))
    )
    (fp_text user "License: Apache-2.0" (at -0.95 -5.169) (layer "B.Fab") hide
        (effects (font (size 0.7 0.7) (thickness 0.15)) (justify left bottom mirror))
    )
    (fp_text user "${REFERENCE}" (at 0 0 180) (layer "B.Fab")
        (effects (font (size 0.25 0.25) (thickness 0.04)) (justify mirror))
    )
    (fp_text user "Author: Antmicro" (at -0.95 -4.169) (layer "B.Fab") hide
        (effects (font (size 0.7 0.7) (thickness 0.15)) (justify left bottom mirror))
    )
    (fp_rect (start -0.925 0.47) (end 0.925 -0.47)
      (stroke (width 0.05) (type default)) (fill none) (layer "B.CrtYd"))
    (fp_rect (start -0.5 0.25) (end 0.5 -0.25)
      (stroke (width 0.15) (type solid)) (fill none) (layer "B.Fab"))
    (pad "1" smd roundrect (at -0.48 0 180) (size 0.59 0.64) (layers "B.Cu" "B.Paste" "B.Mask") (roundrect_rratio 0.25)
      (net 11 "VCC5V0") (pintype "passive"))
    (pad "2" smd roundrect (at 0.48 0 180) (size 0.59 0.64) (layers "B.Cu" "B.Paste" "B.Mask") (roundrect_rratio 0.25)
      (net 222 "/Power supply/3V3_PG") (pintype "passive"))
  )

  (footprint "antmicro-footprints:C_0402_1005Metric" (layer "B.Cu")
    (at 88.865 116.92 -90)
    (descr "Capacitor SMD 0402")
    (tags "capacitor SMD 0402")
    (property "Author" "Antmicro")
    (property "Dielectric" "")
    (property "License" "Apache-2.0")
    (property "MPN" "C1005X5R1E474M050BB")
    (property "Manufacturer" "TDK")
    (property "Public" "False")
    (property "Sheetfile" "ddr3.kicad_sch")
    (property "Sheetname" "DDR3")
    (property "Val" "470n")
    (property "Voltage" "")
    (property "ki_description" "SMD Multilayer Ceramic Capacitor, 0.47 µF, 25 V, 0402 [1005 Metric], ± 20%, X5R, C")
    (property "ki_keywords" "0402, SMT, CAPACITOR, PASSIVE, CERAMIC, MLCC")
    (attr smd)
    (fp_text reference "C90" (at 0 1.17 90) (layer "B.SilkS")
        (effects (font (size 0.7 0.7) (thickness 0.127)) (justify mirror))
    )
    (fp_text value "C_470n_0402" (at 0 -1.17 90) (layer "B.Fab")
        (effects (font (size 1 1) (thickness 0.15)) (justify mirror))
    )
    (fp_text user "License: Apache-2.0" (at -0.939 -5.799 90) (layer "B.Fab") hide
        (effects (font (size 0.7 0.7) (thickness 0.15)) (justify left bottom mirror))
    )
    (fp_text user "Author: Antmicro" (at -0.939 -3.399 90) (layer "B.Fab") hide
        (effects (font (size 0.7 0.7) (thickness 0.15)) (justify left bottom mirror))
    )
    (fp_text user "${REFERENCE}" (at 0 0 90) (layer "B.Fab")
        (effects (font (size 0.25 0.25) (thickness 0.04)) (justify mirror))
    )
    (fp_rect (start -0.925 0.47) (end 0.925 -0.47)
      (stroke (width 0.05) (type default)) (fill none) (layer "B.CrtYd"))
    (fp_line (start -0.494 -0.248) (end -0.494 0.25)
      (stroke (width 0.15) (type solid)) (layer "B.Fab"))
    (fp_line (start -0.494 0.25) (end 0.504 0.25)
      (stroke (width 0.15) (type solid)) (layer "B.Fab"))
    (fp_line (start 0.504 -0.248) (end -0.494 -0.248)
      (stroke (width 0.15) (type solid)) (layer "B.Fab"))
    (fp_line (start 0.504 0.25) (end 0.504 -0.248)
      (stroke (width 0.15) (type solid)) (layer "B.Fab"))
    (pad "1" smd roundrect (at -0.48 0 270) (size 0.59 0.64) (layers "B.Cu" "B.Paste" "B.Mask") (roundrect_rratio 0.25)
      (net 1 "GND") (pintype "passive"))
    (pad "2" smd roundrect (at 0.48 0 270) (size 0.59 0.64) (layers "B.Cu" "B.Paste" "B.Mask") (roundrect_rratio 0.25)
      (net 3 "VCC1V35") (pintype "passive"))
  )

  (footprint "antmicro-footprints:C_0402_1005Metric" (layer "B.Cu")
    (at 79.05 124.7 90)
    (descr "Capacitor SMD 0402")
    (tags "capacitor SMD 0402")
    (property "Author" "Antmicro")
    (property "Dielectric" "")
    (property "License" "Apache-2.0")
    (property "MPN" "C1005X5R1E474M050BB")
    (property "Manufacturer" "TDK")
    (property "Public" "False")
    (property "Sheetfile" "ddr3.kicad_sch")
    (property "Sheetname" "DDR3")
    (property "Val" "470n")
    (property "Voltage" "")
    (property "ki_description" "SMD Multilayer Ceramic Capacitor, 0.47 µF, 25 V, 0402 [1005 Metric], ± 20%, X5R, C")
    (property "ki_keywords" "0402, SMT, CAPACITOR, PASSIVE, CERAMIC, MLCC")
    (attr smd)
    (fp_text reference "C87" (at 0.035 -2.58 90) (layer "B.SilkS")
        (effects (font (size 0.7 0.7) (thickness 0.127)) (justify mirror))
    )
    (fp_text value "C_470n_0402" (at 0 -1.17 90) (layer "B.Fab")
        (effects (font (size 1 1) (thickness 0.15)) (justify mirror))
    )
    (fp_text user "License: Apache-2.0" (at -0.939 -5.799 270) (layer "B.Fab") hide
        (effects (font (size 0.7 0.7) (thickness 0.15)) (justify left bottom mirror))
    )
    (fp_text user "${REFERENCE}" (at 0 0 90) (layer "B.Fab")
        (effects (font (size 0.25 0.25) (thickness 0.04)) (justify mirror))
    )
    (fp_text user "Author: Antmicro" (at -0.939 -3.399 270) (layer "B.Fab") hide
        (effects (font (size 0.7 0.7) (thickness 0.15)) (justify left bottom mirror))
    )
    (fp_rect (start -0.925 0.47) (end 0.925 -0.47)
      (stroke (width 0.05) (type default)) (fill none) (layer "B.CrtYd"))
    (fp_line (start -0.494 -0.248) (end -0.494 0.25)
      (stroke (width 0.15) (type solid)) (layer "B.Fab"))
    (fp_line (start -0.494 0.25) (end 0.504 0.25)
      (stroke (width 0.15) (type solid)) (layer "B.Fab"))
    (fp_line (start 0.504 -0.248) (end -0.494 -0.248)
      (stroke (width 0.15) (type solid)) (layer "B.Fab"))
    (fp_line (start 0.504 0.25) (end 0.504 -0.248)
      (stroke (width 0.15) (type solid)) (layer "B.Fab"))
    (pad "1" smd roundrect (at -0.48 0 90) (size 0.59 0.64) (layers "B.Cu" "B.Paste" "B.Mask") (roundrect_rratio 0.25)
      (net 1 "GND") (pintype "passive"))
    (pad "2" smd roundrect (at 0.48 0 90) (size 0.59 0.64) (layers "B.Cu" "B.Paste" "B.Mask") (roundrect_rratio 0.25)
      (net 3 "VCC1V35") (pintype "passive"))
  )

  (footprint "antmicro-footprints:SOT-23-3" (layer "B.Cu")
    (at 71.2 85.05)
    (property "Author" "Antmicro")
    (property "License" "Apache-2.0")
    (property "MPN" "2N7002")
    (property "Manufacturer" "ON Semiconductor")
    (property "Sheetfile" "power-supply.kicad_sch")
    (property "Sheetname" "Power supply")
    (property "ki_description" "Power MOSFET, N Channel, 60 V, 115 mA, 1.2 ohm, SOT-23, Surface Mount")
    (property "ki_keywords" "SMT, TRANSISTOR, SEMICONDUCTOR, NMOS")
    (attr smd)
    (fp_text reference "Q10" (at 0 -2.45 180) (layer "B.SilkS")
        (effects (font (size 0.7 0.7) (thickness 0.127)) (justify mirror))
    )
    (fp_text value "2N7002" (at 0.025 -3.25) (layer "B.Fab")
        (effects (font (size 1 1) (thickness 0.15)) (justify mirror))
    )
    (fp_text user "Author: Antmicro" (at -1.837 -5.3 180) (layer "B.Fab") hide
        (effects (font (size 0.7 0.7) (thickness 0.15)) (justify left bottom mirror))
    )
    (fp_text user "${REFERENCE}" (at -0.125 -0.15) (layer "B.Fab")
        (effects (font (size 0.25 0.25) (thickness 0.05)) (justify mirror))
    )
    (fp_text user "License: Apache-2.0" (at -1.8 -6.8 180) (layer "B.Fab") hide
        (effects (font (size 0.7 0.7) (thickness 0.15)) (justify left bottom mirror))
    )
    (fp_line (start -1.45 1.35) (end -0.85 1.35)
      (stroke (width 0.15) (type solid)) (layer "B.SilkS"))
    (fp_line (start -0.85 1.35) (end -0.7 1.5)
      (stroke (width 0.15) (type solid)) (layer "B.SilkS"))
    (fp_line (start -0.7 -1.5) (end -0.7 -1.35)
      (stroke (width 0.15) (type solid)) (layer "B.SilkS"))
    (fp_line (start 0.7 -1.5) (end -0.7 -1.5)
      (stroke (width 0.15) (type solid)) (layer "B.SilkS"))
    (fp_line (start 0.7 -0.4) (end 0.7 -1.5)
      (stroke (width 0.15) (type solid)) (layer "B.SilkS"))
    (fp_line (start 0.7 0.4) (end 0.7 1.5)
      (stroke (width 0.15) (type solid)) (layer "B.SilkS"))
    (fp_line (start 0.7 1.5) (end -0.7 1.5)
      (stroke (width 0.15) (type solid)) (layer "B.SilkS"))
    (fp_line (start -1.75 -1.4) (end -1.75 -0.5)
      (stroke (width 0.05) (type solid)) (layer "B.CrtYd"))
    (fp_line (start -1.75 -0.5) (end -0.85 -0.5)
      (stroke (width 0.05) (type solid)) (layer "B.CrtYd"))
    (fp_line (start -1.75 0.5) (end -1.75 1.4)
      (stroke (width 0.05) (type solid)) (layer "B.CrtYd"))
    (fp_line (start -0.9 1.4) (end -1.75 1.4)
      (stroke (width 0.05) (type solid)) (layer "B.CrtYd"))
    (fp_line (start -0.9 1.6) (end -0.9 1.4)
      (stroke (width 0.05) (type solid)) (layer "B.CrtYd"))
    (fp_line (start -0.9 1.6) (end 0.825 1.6)
      (stroke (width 0.05) (type solid)) (layer "B.CrtYd"))
    (fp_line (start -0.85 -1.65) (end -0.85 -1.4)
      (stroke (width 0.05) (type solid)) (layer "B.CrtYd"))
    (fp_line (start -0.85 -1.4) (end -1.75 -1.4)
      (stroke (width 0.05) (type solid)) (layer "B.CrtYd"))
    (fp_line (start -0.85 -0.5) (end -0.85 0.5)
      (stroke (width 0.05) (type solid)) (layer "B.CrtYd"))
    (fp_line (start -0.85 0.5) (end -1.75 0.5)
      (stroke (width 0.05) (type solid)) (layer "B.CrtYd"))
    (fp_line (start 0.825 0.45) (end 1.75 0.45)
      (stroke (width 0.05) (type solid)) (layer "B.CrtYd"))
    (fp_line (start 0.825 1.6) (end 0.825 0.45)
      (stroke (width 0.05) (type solid)) (layer "B.CrtYd"))
    (fp_line (start 0.85 -1.65) (end -0.85 -1.65)
      (stroke (width 0.05) (type solid)) (layer "B.CrtYd"))
    (fp_line (start 0.85 -0.45) (end 0.85 -1.65)
      (stroke (width 0.05) (type solid)) (layer "B.CrtYd"))
    (fp_line (start 1.75 -0.45) (end 0.85 -0.45)
      (stroke (width 0.05) (type solid)) (layer "B.CrtYd"))
    (fp_line (start 1.75 0.45) (end 1.75 -0.45)
      (stroke (width 0.05) (type solid)) (layer "B.CrtYd"))
    (fp_line (start -0.712 -1.519) (end 0.688 -1.519)
      (stroke (width 0.15) (type solid)) (layer "B.Fab"))
    (fp_line (start -0.712 1.325) (end -0.712 -1.523)
      (stroke (width 0.15) (type solid)) (layer "B.Fab"))
    (fp_line (start -0.437 1.526) (end -0.712 1.325)
      (stroke (width 0.15) (type solid)) (layer "B.Fab"))
    (fp_line (start -0.437 1.526) (end 0.688 1.526)
      (stroke (width 0.15) (type solid)) (layer "B.Fab"))
    (fp_line (start 0.688 -1.519) (end 0.688 1.52)
      (stroke (width 0.15) (type solid)) (layer "B.Fab"))
    (pad "1" smd roundrect (at -1.1 0.951) (size 1 0.6) (layers "B.Cu" "B.Paste" "B.Mask") (roundrect_rratio 0.15)
      (net 235 "/Power supply/1V2_PG") (pinfunction "G") (pintype "passive"))
    (pad "2" smd roundrect (at -1.1 -0.949) (size 1 0.6) (layers "B.Cu" "B.Paste" "B.Mask") (roundrect_rratio 0.15)
      (net 1 "GND") (pinfunction "S") (pintype "passive"))
    (pad "3" smd roundrect (at 1.1 0.0005) (size 1 0.6) (layers "B.Cu" "B.Paste" "B.Mask") (roundrect_rratio 0.15)
      (net 394 "Net-(Q10-D)") (pinfunction "D") (pintype "passive"))
  )

  (footprint "antmicro-footprints:C_0402_1005Metric" (layer "B.Cu")
    (at 82.65 120.5 180)
    (descr "Capacitor SMD 0402")
    (tags "capacitor SMD 0402")
    (property "Author" "Antmicro")
    (property "Dielectric" "X5R")
    (property "License" "Apache-2.0")
    (property "MPN" "GRM155R61H104KE14D")
    (property "Manufacturer" "Murata")
    (property "Public" "False")
    (property "Sheetfile" "ddr3.kicad_sch")
    (property "Sheetname" "DDR3")
    (property "Val" "100n")
    (property "Voltage" "50V")
    (property "ki_description" "SMD Multilayer Ceramic Capacitor, 0.1 µF, 50 V, 0402 [1005 Metric], ± 10%, X5R, GRM Series")
    (property "ki_keywords" "0402, SMT, CAPACITOR, PASSIVE, CERAMIC, MLCC")
    (attr smd)
    (fp_text reference "C93" (at 0 1.17) (layer "B.SilkS")
        (effects (font (size 0.7 0.7) (thickness 0.127)) (justify mirror))
    )
    (fp_text value "C_100n_0402" (at 0 -1.17) (layer "B.Fab")
        (effects (font (size 1 1) (thickness 0.15)) (justify mirror))
    )
    (fp_text user "License: Apache-2.0" (at -0.939 -5.799) (layer "B.Fab") hide
        (effects (font (size 0.7 0.7) (thickness 0.15)) (justify left bottom mirror))
    )
    (fp_text user "${REFERENCE}" (at 0 0) (layer "B.Fab")
        (effects (font (size 0.25 0.25) (thickness 0.04)) (justify mirror))
    )
    (fp_text user "Author: Antmicro" (at -0.939 -3.399) (layer "B.Fab") hide
        (effects (font (size 0.7 0.7) (thickness 0.15)) (justify left bottom mirror))
    )
    (fp_rect (start -0.925 0.47) (end 0.925 -0.47)
      (stroke (width 0.05) (type default)) (fill none) (layer "B.CrtYd"))
    (fp_line (start -0.494 -0.248) (end -0.494 0.25)
      (stroke (width 0.15) (type solid)) (layer "B.Fab"))
    (fp_line (start -0.494 0.25) (end 0.504 0.25)
      (stroke (width 0.15) (type solid)) (layer "B.Fab"))
    (fp_line (start 0.504 -0.248) (end -0.494 -0.248)
      (stroke (width 0.15) (type solid)) (layer "B.Fab"))
    (fp_line (start 0.504 0.25) (end 0.504 -0.248)
      (stroke (width 0.15) (type solid)) (layer "B.Fab"))
    (pad "1" smd roundrect (at -0.48 0 180) (size 0.59 0.64) (layers "B.Cu" "B.Paste" "B.Mask") (roundrect_rratio 0.25)
      (net 1 "GND") (pintype "passive"))
    (pad "2" smd roundrect (at 0.48 0 180) (size 0.59 0.64) (layers "B.Cu" "B.Paste" "B.Mask") (roundrect_rratio 0.25)
      (net 217 "DDR3_VREF") (pintype "passive"))
  )

  (footprint "antmicro-footprints:C_0402_1005Metric" (layer "B.Cu")
    (at 91.7 122.15 180)
    (descr "Capacitor SMD 0402")
    (tags "capacitor SMD 0402")
    (property "Author" "Antmicro")
    (property "Dielectric" "X5R")
    (property "License" "Apache-2.0")
    (property "MPN" "GRM155R61H104KE14D")
    (property "Manufacturer" "Murata")
    (property "Public" "False")
    (property "Sheetfile" "fpga-banks.kicad_sch")
    (property "Sheetname" "FPGA banks")
    (property "Val" "100n")
    (property "Voltage" "50V")
    (property "ki_description" "SMD Multilayer Ceramic Capacitor, 0.1 µF, 50 V, 0402 [1005 Metric], ± 10%, X5R, GRM Series")
    (property "ki_keywords" "0402, SMT, CAPACITOR, PASSIVE, CERAMIC, MLCC")
    (attr smd)
    (fp_text reference "C216" (at 0.02 0.885 180) (layer "B.SilkS")
        (effects (font (size 0.7 0.7) (thickness 0.127)) (justify mirror))
    )
    (fp_text value "C_100n_0402" (at 0 -1.17 180) (layer "B.Fab")
        (effects (font (size 1 1) (thickness 0.15)) (justify mirror))
    )
    (fp_text user "${REFERENCE}" (at 0 0 180) (layer "B.Fab")
        (effects (font (size 0.25 0.25) (thickness 0.04)) (justify mirror))
    )
    (fp_text user "Author: Antmicro" (at -0.939 -3.399) (layer "B.Fab") hide
        (effects (font (size 0.7 0.7) (thickness 0.15)) (justify left bottom mirror))
    )
    (fp_text user "License: Apache-2.0" (at -0.939 -5.799) (layer "B.Fab") hide
        (effects (font (size 0.7 0.7) (thickness 0.15)) (justify left bottom mirror))
    )
    (fp_rect (start -0.925 0.47) (end 0.925 -0.47)
      (stroke (width 0.05) (type default)) (fill none) (layer "B.CrtYd"))
    (fp_line (start -0.494 -0.248) (end -0.494 0.25)
      (stroke (width 0.15) (type solid)) (layer "B.Fab"))
    (fp_line (start -0.494 0.25) (end 0.504 0.25)
      (stroke (width 0.15) (type solid)) (layer "B.Fab"))
    (fp_line (start 0.504 -0.248) (end -0.494 -0.248)
      (stroke (width 0.15) (type solid)) (layer "B.Fab"))
    (fp_line (start 0.504 0.25) (end 0.504 -0.248)
      (stroke (width 0.15) (type solid)) (layer "B.Fab"))
    (pad "1" smd roundrect (at -0.48 0 180) (size 0.59 0.64) (layers "B.Cu" "B.Paste" "B.Mask") (roundrect_rratio 0.25)
      (net 1 "GND") (pintype "passive"))
    (pad "2" smd roundrect (at 0.48 0 180) (size 0.59 0.64) (layers "B.Cu" "B.Paste" "B.Mask") (roundrect_rratio 0.25)
      (net 217 "DDR3_VREF") (pintype "passive"))
  )

  (footprint "antmicro-footprints:C_0402_1005Metric" (layer "B.Cu")
    (at 93.6 122.95)
    (descr "Capacitor SMD 0402")
    (tags "capacitor SMD 0402")
    (property "Author" "Antmicro")
    (property "Dielectric" "X5R")
    (property "License" "Apache-2.0")
    (property "MPN" "GRM155R61H104KE14D")
    (property "Manufacturer" "Murata")
    (property "Public" "False")
    (property "Sheetfile" "fpga-banks.kicad_sch")
    (property "Sheetname" "FPGA banks")
    (property "Val" "100n")
    (property "Voltage" "50V")
    (property "ki_description" "SMD Multilayer Ceramic Capacitor, 0.1 µF, 50 V, 0402 [1005 Metric], ± 10%, X5R, GRM Series")
    (property "ki_keywords" "0402, SMT, CAPACITOR, PASSIVE, CERAMIC, MLCC")
    (attr smd)
    (fp_text reference "C217" (at -1.35 0.95) (layer "B.SilkS")
        (effects (font (size 0.7 0.7) (thickness 0.127)) (justify mirror))
    )
    (fp_text value "C_100n_0402" (at 0 -1.17) (layer "B.Fab")
        (effects (font (size 1 1) (thickness 0.15)) (justify mirror))
    )
    (fp_text user "Author: Antmicro" (at -0.939 -3.399 180) (layer "B.Fab") hide
        (effects (font (size 0.7 0.7) (thickness 0.15)) (justify left bottom mirror))
    )
    (fp_text user "License: Apache-2.0" (at -0.939 -5.799 180) (layer "B.Fab") hide
        (effects (font (size 0.7 0.7) (thickness 0.15)) (justify left bottom mirror))
    )
    (fp_text user "${REFERENCE}" (at 0 0) (layer "B.Fab")
        (effects (font (size 0.25 0.25) (thickness 0.04)) (justify mirror))
    )
    (fp_rect (start -0.925 0.47) (end 0.925 -0.47)
      (stroke (width 0.05) (type default)) (fill none) (layer "B.CrtYd"))
    (fp_line (start -0.494 -0.248) (end -0.494 0.25)
      (stroke (width 0.15) (type solid)) (layer "B.Fab"))
    (fp_line (start -0.494 0.25) (end 0.504 0.25)
      (stroke (width 0.15) (type solid)) (layer "B.Fab"))
    (fp_line (start 0.504 -0.248) (end -0.494 -0.248)
      (stroke (width 0.15) (type solid)) (layer "B.Fab"))
    (fp_line (start 0.504 0.25) (end 0.504 -0.248)
      (stroke (width 0.15) (type solid)) (layer "B.Fab"))
    (pad "1" smd roundrect (at -0.48 0) (size 0.59 0.64) (layers "B.Cu" "B.Paste" "B.Mask") (roundrect_rratio 0.25)
      (net 1 "GND") (pintype "passive"))
    (pad "2" smd roundrect (at 0.48 0) (size 0.59 0.64) (layers "B.Cu" "B.Paste" "B.Mask") (roundrect_rratio 0.25)
      (net 217 "DDR3_VREF") (pintype "passive"))
  )

  (footprint "antmicro-footprints:R_0402_1005Metric" (layer "B.Cu")
    (at 94.575 96.075 180)
    (descr "Resistor SMD 0402")
    (tags "resistor SMD 0402")
    (property "Author" "Antmicro")
    (property "License" "Apache-2.0")
    (property "MPN" "CR0402-FX-4702GLF")
    (property "Manufacturer" "Bourns")
    (property "Public" "False")
    (property "Sheetfile" "interfaces.kicad_sch")
    (property "Sheetname" "Interfaces")
    (property "Tolerance" "1%")
    (property "Val" "47k")
    (property "ki_description" "SMD Chip Resistor, 47 kohm, ± 1%, 62.5 mW, 0402 [1005 Metric], Thick Film, General Purpose")
    (property "ki_keywords" "0402, SMT, RESISTOR, PASSIVE")
    (attr smd)
    (fp_text reference "R65" (at 0.025 -7.425) (layer "B.SilkS")
        (effects (font (size 0.7 0.7) (thickness 0.127)) (justify mirror))
    )
    (fp_text value "R_47k_0402" (at 0 -1.17) (layer "B.Fab")
        (effects (font (size 1 1) (thickness 0.15)) (justify mirror))
    )
    (fp_text user "Author: Antmicro" (at -0.95 -4.169) (layer "B.Fab") hide
        (effects (font (size 0.7 0.7) (thickness 0.15)) (justify left bottom mirror))
    )
    (fp_text user "${REFERENCE}" (at 0 0) (layer "B.Fab")
        (effects (font (size 0.25 0.25) (thickness 0.04)) (justify mirror))
    )
    (fp_text user "License: Apache-2.0" (at -0.95 -5.169) (layer "B.Fab") hide
        (effects (font (size 0.7 0.7) (thickness 0.15)) (justify left bottom mirror))
    )
    (fp_rect (start -0.925 0.47) (end 0.925 -0.47)
      (stroke (width 0.05) (type default)) (fill none) (layer "B.CrtYd"))
    (fp_rect (start -0.5 0.25) (end 0.5 -0.25)
      (stroke (width 0.15) (type solid)) (fill none) (layer "B.Fab"))
    (pad "1" smd roundrect (at -0.48 0 180) (size 0.59 0.64) (layers "B.Cu" "B.Paste" "B.Mask") (roundrect_rratio 0.25)
      (net 2 "VCC3V3") (pintype "passive"))
    (pad "2" smd roundrect (at 0.48 0 180) (size 0.59 0.64) (layers "B.Cu" "B.Paste" "B.Mask") (roundrect_rratio 0.25)
      (net 283 "MMC_DAT4") (pintype "passive"))
  )

  (footprint "antmicro-footprints:R_0402_1005Metric" (layer "B.Cu")
    (at 77.65 93.75 90)
    (descr "Resistor SMD 0402")
    (tags "resistor SMD 0402")
    (property "Author" "Antmicro")
    (property "License" "Apache-2.0")
    (property "MPN" "CR0402-FX-1002GLF")
    (property "Manufacturer" "Bourns")
    (property "Public" "False")
    (property "Sheetfile" "power-supply.kicad_sch")
    (property "Sheetname" "Power supply")
    (property "Tolerance" "1%")
    (property "Val" "10k")
    (property "ki_description" "SMD Chip Resistor, 10 kohm, ± 1%, 62.5 mW, 0402 [1005 Metric], Thick Film, General Purpose")
    (property "ki_keywords" "0402, SMT, RESISTOR, PASSIVE")
    (attr smd)
    (fp_text reference "R102" (at 0.05 1.05 270) (layer "B.SilkS")
        (effects (font (size 0.7 0.7) (thickness 0.127)) (justify mirror))
    )
    (fp_text value "R_10k_0402" (at 0 -1.17 270) (layer "B.Fab")
        (effects (font (size 1 1) (thickness 0.15)) (justify mirror))
    )
    (fp_text user "Author: Antmicro" (at -0.95 -4.169 270) (layer "B.Fab") hide
        (effects (font (size 0.7 0.7) (thickness 0.15)) (justify left bottom mirror))
    )
    (fp_text user "${REFERENCE}" (at 0 0 270) (layer "B.Fab")
        (effects (font (size 0.25 0.25) (thickness 0.04)) (justify mirror))
    )
    (fp_text user "License: Apache-2.0" (at -0.95 -5.169 270) (layer "B.Fab") hide
        (effects (font (size 0.7 0.7) (thickness 0.15)) (justify left bottom mirror))
    )
    (fp_rect (start -0.925 0.47) (end 0.925 -0.47)
      (stroke (width 0.05) (type default)) (fill none) (layer "B.CrtYd"))
    (fp_rect (start -0.5 0.25) (end 0.5 -0.25)
      (stroke (width 0.15) (type solid)) (fill none) (layer "B.Fab"))
    (pad "1" smd roundrect (at -0.48 0 90) (size 0.59 0.64) (layers "B.Cu" "B.Paste" "B.Mask") (roundrect_rratio 0.25)
      (net 2 "VCC3V3") (pintype "passive"))
    (pad "2" smd roundrect (at 0.48 0 90) (size 0.59 0.64) (layers "B.Cu" "B.Paste" "B.Mask") (roundrect_rratio 0.25)
      (net 385 "1V0_PG") (pintype "passive"))
  )

  (footprint "antmicro-footprints:R_0402_1005Metric" (layer "B.Cu")
    (at 94.55 99.15 180)
    (descr "Resistor SMD 0402")
    (tags "resistor SMD 0402")
    (property "Author" "Antmicro")
    (property "License" "Apache-2.0")
    (property "MPN" "CR0402-FX-4702GLF")
    (property "Manufacturer" "Bourns")
    (property "Public" "False")
    (property "Sheetfile" "interfaces.kicad_sch")
    (property "Sheetname" "Interfaces")
    (property "Tolerance" "1%")
    (property "Val" "47k")
    (property "ki_description" "SMD Chip Resistor, 47 kohm, ± 1%, 62.5 mW, 0402 [1005 Metric], Thick Film, General Purpose")
    (property "ki_keywords" "0402, SMT, RESISTOR, PASSIVE")
    (attr smd)
    (fp_text reference "R59" (at 0 -7.202) (layer "B.SilkS")
        (effects (font (size 0.7 0.7) (thickness 0.127)) (justify mirror))
    )
    (fp_text value "R_47k_0402" (at 0 -1.17) (layer "B.Fab")
        (effects (font (size 1 1) (thickness 0.15)) (justify mirror))
    )
    (fp_text user "Author: Antmicro" (at -0.95 -4.169) (layer "B.Fab") hide
        (effects (font (size 0.7 0.7) (thickness 0.15)) (justify left bottom mirror))
    )
    (fp_text user "License: Apache-2.0" (at -0.95 -5.169) (layer "B.Fab") hide
        (effects (font (size 0.7 0.7) (thickness 0.15)) (justify left bottom mirror))
    )
    (fp_text user "${REFERENCE}" (at 0 0) (layer "B.Fab")
        (effects (font (size 0.25 0.25) (thickness 0.04)) (justify mirror))
    )
    (fp_rect (start -0.925 0.47) (end 0.925 -0.47)
      (stroke (width 0.05) (type default)) (fill none) (layer "B.CrtYd"))
    (fp_rect (start -0.5 0.25) (end 0.5 -0.25)
      (stroke (width 0.15) (type solid)) (fill none) (layer "B.Fab"))
    (pad "1" smd roundrect (at -0.48 0 180) (size 0.59 0.64) (layers "B.Cu" "B.Paste" "B.Mask") (roundrect_rratio 0.25)
      (net 2 "VCC3V3") (pintype "passive"))
    (pad "2" smd roundrect (at 0.48 0 180) (size 0.59 0.64) (layers "B.Cu" "B.Paste" "B.Mask") (roundrect_rratio 0.25)
      (net 377 "MMC_RSTN") (pintype "passive"))
  )

  (footprint "antmicro-footprints:C_0402_1005Metric" (layer "B.Cu")
    (at 140.8 83.64 90)
    (descr "Capacitor SMD 0402")
    (tags "capacitor SMD 0402")
    (property "Author" "Antmicro")
    (property "Dielectric" "X5R")
    (property "License" "Apache-2.0")
    (property "MPN" "GRM155R61H104KE14D")
    (property "Manufacturer" "Murata")
    (property "Public" "False")
    (property "Sheetfile" "interfaces.kicad_sch")
    (property "Sheetname" "Interfaces")
    (property "Val" "100n")
    (property "Voltage" "50V")
    (property "ki_description" "SMD Multilayer Ceramic Capacitor, 0.1 µF, 50 V, 0402 [1005 Metric], ± 10%, X5R, GRM Series")
    (property "ki_keywords" "0402, SMT, CAPACITOR, PASSIVE, CERAMIC, MLCC")
    (attr smd)
    (fp_text reference "C98" (at -0.035 1.42 90) (layer "B.SilkS")
        (effects (font (size 0.7 0.7) (thickness 0.15)) (justify mirror))
    )
    (fp_text value "C_100n_0402" (at 0 -1.17 90) (layer "B.Fab")
        (effects (font (size 1 1) (thickness 0.15)) (justify mirror))
    )
    (fp_text user "${REFERENCE}" (at 0 0 90) (layer "B.Fab")
        (effects (font (size 0.25 0.25) (thickness 0.04)) (justify mirror))
    )
    (fp_text user "License: Apache-2.0" (at -0.939 -5.799 270) (layer "B.Fab") hide
        (effects (font (size 0.7 0.7) (thickness 0.15)) (justify left bottom mirror))
    )
    (fp_text user "Author: Antmicro" (at -0.939 -3.399 270) (layer "B.Fab") hide
        (effects (font (size 0.7 0.7) (thickness 0.15)) (justify left bottom mirror))
    )
    (fp_rect (start -0.925 0.47) (end 0.925 -0.47)
      (stroke (width 0.05) (type default)) (fill none) (layer "B.CrtYd"))
    (fp_line (start -0.494 -0.248) (end -0.494 0.25)
      (stroke (width 0.15) (type solid)) (layer "B.Fab"))
    (fp_line (start -0.494 0.25) (end 0.504 0.25)
      (stroke (width 0.15) (type solid)) (layer "B.Fab"))
    (fp_line (start 0.504 -0.248) (end -0.494 -0.248)
      (stroke (width 0.15) (type solid)) (layer "B.Fab"))
    (fp_line (start 0.504 0.25) (end 0.504 -0.248)
      (stroke (width 0.15) (type solid)) (layer "B.Fab"))
    (pad "1" smd roundrect (at -0.48 0 90) (size 0.59 0.64) (layers "B.Cu" "B.Paste" "B.Mask") (roundrect_rratio 0.25)
      (net 1 "GND") (pintype "passive"))
    (pad "2" smd roundrect (at 0.48 0 90) (size 0.59 0.64) (layers "B.Cu" "B.Paste" "B.Mask") (roundrect_rratio 0.25)
      (net 415 "VBUS") (pintype "passive"))
  )

  (footprint "antmicro-footprints:C_0402_1005Metric" (layer "B.Cu")
    (at 138.65 83.675 90)
    (descr "Capacitor SMD 0402")
    (tags "capacitor SMD 0402")
    (property "Author" "Antmicro")
    (property "Dielectric" "")
    (property "License" "Apache-2.0")
    (property "MPN" "GRM155R61A475MEAAD")
    (property "Manufacturer" "Murata")
    (property "Public" "False")
    (property "Sheetfile" "interfaces.kicad_sch")
    (property "Sheetname" "Interfaces")
    (property "Val" "4u7")
    (property "Voltage" "")
    (property "ki_description" "SMD Multilayer Ceramic Capacitor, 4.7 µF, 10 V, 0402 [1005 Metric], ± 20%, X5R, GRM Series")
    (property "ki_keywords" "0402, SMT, CAPACITOR, PASSIVE")
    (attr smd)
    (fp_text reference "C99" (at 2 0.07 90) (layer "B.SilkS")
        (effects (font (size 0.7 0.7) (thickness 0.15)) (justify mirror))
    )
    (fp_text value "C_4u7_0402" (at 0 -1.17 90) (layer "B.Fab")
        (effects (font (size 1 1) (thickness 0.15)) (justify mirror))
    )
    (fp_text user "License: Apache-2.0" (at -0.939 -5.799 270) (layer "B.Fab") hide
        (effects (font (size 0.7 0.7) (thickness 0.15)) (justify left bottom mirror))
    )
    (fp_text user "${REFERENCE}" (at 0 0 90) (layer "B.Fab")
        (effects (font (size 0.25 0.25) (thickness 0.04)) (justify mirror))
    )
    (fp_text user "Author: Antmicro" (at -0.939 -3.399 270) (layer "B.Fab") hide
        (effects (font (size 0.7 0.7) (thickness 0.15)) (justify left bottom mirror))
    )
    (fp_rect (start -0.925 0.47) (end 0.925 -0.47)
      (stroke (width 0.05) (type default)) (fill none) (layer "B.CrtYd"))
    (fp_line (start -0.494 -0.248) (end -0.494 0.25)
      (stroke (width 0.15) (type solid)) (layer "B.Fab"))
    (fp_line (start -0.494 0.25) (end 0.504 0.25)
      (stroke (width 0.15) (type solid)) (layer "B.Fab"))
    (fp_line (start 0.504 -0.248) (end -0.494 -0.248)
      (stroke (width 0.15) (type solid)) (layer "B.Fab"))
    (fp_line (start 0.504 0.25) (end 0.504 -0.248)
      (stroke (width 0.15) (type solid)) (layer "B.Fab"))
    (pad "1" smd roundrect (at -0.48 0 90) (size 0.59 0.64) (layers "B.Cu" "B.Paste" "B.Mask") (roundrect_rratio 0.25)
      (net 1 "GND") (pintype "passive"))
    (pad "2" smd roundrect (at 0.48 0 90) (size 0.59 0.64) (layers "B.Cu" "B.Paste" "B.Mask") (roundrect_rratio 0.25)
      (net 415 "VBUS") (pintype "passive"))
  )

  (footprint "antmicro-footprints:FB_0402_1005Metric" (layer "B.Cu")
    (at 136.4 83.675 -90)
    (descr "Ferrite Bead SMD 0402")
    (tags "ferrite bead SMD 0402")
    (property "Author" "Antmicro")
    (property "Current" "")
    (property "License" "Apache-2.0")
    (property "MPN" "BLM15AG601SN1D")
    (property "Manufacturer" "Murata")
    (property "Public" "False")
    (property "Sheetfile" "interfaces.kicad_sch")
    (property "Sheetname" "Interfaces")
    (property "Val" "600Z/0.3A")
    (property "ki_description" "Ferrite Bead, 0402 [1005 Metric], 600 ohm, 300 mA, BLM15AG_SN, 0.6 ohm, ± 25%, General use")
    (property "ki_keywords" "0402, SMT, FERRITE BEAD, PASSIVE")
    (attr smd)
    (fp_text reference "FB9" (at -2.918333 -0.06 90) (layer "B.SilkS")
        (effects (font (size 0.7 0.7) (thickness 0.15)) (justify mirror))
    )
    (fp_text value "FB_600Z_0.3A_Murata-BLM15AG_0402" (at 0 -1.17 90) (layer "B.Fab")
        (effects (font (size 1 1) (thickness 0.15)) (justify mirror))
    )
    (fp_text user "License: Apache-2.0" (at -0.95 -5.169 90) (layer "B.Fab") hide
        (effects (font (size 0.7 0.7) (thickness 0.15)) (justify left bottom mirror))
    )
    (fp_text user "${REFERENCE}" (at 0 0 90) (layer "B.Fab")
        (effects (font (size 0.25 0.25) (thickness 0.04)) (justify mirror))
    )
    (fp_text user "Author: Antmicro" (at -0.95 -4.169 90) (layer "B.Fab") hide
        (effects (font (size 0.7 0.7) (thickness 0.15)) (justify left bottom mirror))
    )
    (fp_rect (start -0.925 0.47) (end 0.925 -0.47)
      (stroke (width 0.05) (type default)) (fill none) (layer "B.CrtYd"))
    (fp_rect (start -0.5 0.25) (end 0.5 -0.25)
      (stroke (width 0.15) (type solid)) (fill none) (layer "B.Fab"))
    (pad "1" smd roundrect (at -0.48 0 270) (size 0.59 0.64) (layers "B.Cu" "B.Paste" "B.Mask") (roundrect_rratio 0.25)
      (net 2 "VCC3V3") (pintype "passive"))
    (pad "2" smd roundrect (at 0.48 0 270) (size 0.59 0.64) (layers "B.Cu" "B.Paste" "B.Mask") (roundrect_rratio 0.25)
      (net 306 "Net-(U14-V_{PLL})") (pintype "passive"))
  )

  (footprint "antmicro-footprints:R_0402_1005Metric" (layer "B.Cu")
    (at 137.1 86.325 -90)
    (descr "Resistor SMD 0402")
    (tags "resistor SMD 0402")
    (property "Author" "Antmicro")
    (property "License" "Apache-2.0")
    (property "MPN" "CR0402-FX-1202GLF")
    (property "Manufacturer" "Bourns")
    (property "Public" "False")
    (property "Sheetfile" "interfaces.kicad_sch")
    (property "Sheetname" "Interfaces")
    (property "Tolerance" "1%")
    (property "Val" "12k")
    (property "ki_description" "SMD Chip Resistor, 12 kohm, ± 1%, 62.5 mW, 0402 [1005 Metric], Thick Film, General Purpose")
    (property "ki_keywords" "0402, SMT, RESISTOR, PASSIVE")
    (attr smd)
    (fp_text reference "R149" (at 3.1 0.05 90) (layer "B.SilkS")
        (effects (font (size 0.7 0.7) (thickness 0.15)) (justify mirror))
    )
    (fp_text value "R_12k_0402" (at -0.005 -1.25 90) (layer "B.Fab")
        (effects (font (size 1 1) (thickness 0.15)) (justify mirror))
    )
    (fp_text user "${REFERENCE}" (at 0 0 90) (layer "B.Fab")
        (effects (font (size 0.25 0.25) (thickness 0.04)) (justify mirror))
    )
    (fp_text user "Author: Antmicro" (at -0.95 -4.169 90) (layer "B.Fab") hide
        (effects (font (size 0.7 0.7) (thickness 0.15)) (justify left bottom mirror))
    )
    (fp_text user "License: Apache-2.0" (at -0.95 -5.169 90) (layer "B.Fab") hide
        (effects (font (size 0.7 0.7) (thickness 0.15)) (justify left bottom mirror))
    )
    (fp_rect (start -0.925 0.47) (end 0.925 -0.47)
      (stroke (width 0.05) (type default)) (fill none) (layer "B.CrtYd"))
    (fp_rect (start -0.5 0.25) (end 0.5 -0.25)
      (stroke (width 0.15) (type solid)) (fill none) (layer "B.Fab"))
    (pad "1" smd roundrect (at -0.48 0 270) (size 0.59 0.64) (layers "B.Cu" "B.Paste" "B.Mask") (roundrect_rratio 0.25)
      (net 433 "Net-(U14-REF)") (pintype "passive"))
    (pad "2" smd roundrect (at 0.48 0 270) (size 0.59 0.64) (layers "B.Cu" "B.Paste" "B.Mask") (roundrect_rratio 0.25)
      (net 1 "GND") (pintype "passive"))
  )

  (footprint "antmicro-footprints:R_0402_1005Metric" (layer "B.Cu")
    (at 133.1 86.325 90)
    (descr "Resistor SMD 0402")
    (tags "resistor SMD 0402")
    (property "Author" "Antmicro")
    (property "License" "Apache-2.0")
    (property "MPN" "CR0402-FX-1001GLF")
    (property "Manufacturer" "Bourns")
    (property "Public" "False")
    (property "Sheetfile" "interfaces.kicad_sch")
    (property "Sheetname" "Interfaces")
    (property "Tolerance" "1%")
    (property "Val" "1k")
    (property "ki_description" "SMD Chip Resistor, 1 kohm, ± 1%, 63 mW, 0402 [1005 Metric], Thick Film, General Purpose")
    (property "ki_keywords" "0402, SMT, RESISTOR, PASSIVE")
    (attr smd)
    (fp_text reference "R148" (at -2.39 0.01 90) (layer "B.SilkS")
        (effects (font (size 0.7 0.7) (thickness 0.15)) (justify mirror))
    )
    (fp_text value "R_1k_0402" (at 0 -1.17 90) (layer "B.Fab")
        (effects (font (size 1 1) (thickness 0.15)) (justify mirror))
    )
    (fp_text user "${REFERENCE}" (at 0 0 90) (layer "B.Fab")
        (effects (font (size 0.25 0.25) (thickness 0.04)) (justify mirror))
    )
    (fp_text user "License: Apache-2.0" (at -0.95 -5.169 270) (layer "B.Fab") hide
        (effects (font (size 0.7 0.7) (thickness 0.15)) (justify left bottom mirror))
    )
    (fp_text user "Author: Antmicro" (at -0.95 -4.169 270) (layer "B.Fab") hide
        (effects (font (size 0.7 0.7) (thickness 0.15)) (justify left bottom mirror))
    )
    (fp_rect (start -0.925 0.47) (end 0.925 -0.47)
      (stroke (width 0.05) (type default)) (fill none) (layer "B.CrtYd"))
    (fp_rect (start -0.5 0.25) (end 0.5 -0.25)
      (stroke (width 0.15) (type solid)) (fill none) (layer "B.Fab"))
    (pad "1" smd roundrect (at -0.48 0 90) (size 0.59 0.64) (layers "B.Cu" "B.Paste" "B.Mask") (roundrect_rratio 0.25)
      (net 2 "VCC3V3") (pintype "passive"))
    (pad "2" smd roundrect (at 0.48 0 90) (size 0.59 0.64) (layers "B.Cu" "B.Paste" "B.Mask") (roundrect_rratio 0.25)
      (net 432 "Net-(U14-~{RESET})") (pintype "passive"))
  )

  (footprint "antmicro-footprints:R_0402_1005Metric" (layer "B.Cu")
    (at 134.1 86.325 -90)
    (descr "Resistor SMD 0402")
    (tags "resistor SMD 0402")
    (property "Author" "Antmicro")
    (property "DNP" "DNP")
    (property "License" "Apache-2.0")
    (property "MPN" "CR0402-FX-1002GLF")
    (property "Manufacturer" "Bourns")
    (property "Public" "False")
    (property "Sheetfile" "interfaces.kicad_sch")
    (property "Sheetname" "Interfaces")
    (property "Tolerance" "1%")
    (property "Val" "10k")
    (property "dnp" "")
    (property "exclude_from_bom" "")
    (property "ki_description" "SMD Chip Resistor, 10 kohm, ± 1%, 62.5 mW, 0402 [1005 Metric], Thick Film, General Purpose")
    (property "ki_keywords" "0402, SMT, RESISTOR, PASSIVE")
    (attr smd exclude_from_pos_files exclude_from_bom)
    (fp_text reference "R147" (at 2.4 0.1 90) (layer "B.SilkS")
        (effects (font (size 0.7 0.7) (thickness 0.15)) (justify mirror))
    )
    (fp_text value "R_10k_0402" (at 0 -1.17 90) (layer "B.Fab")
        (effects (font (size 1 1) (thickness 0.15)) (justify mirror))
    )
    (fp_text user "${REFERENCE}" (at 0 0 90) (layer "B.Fab")
        (effects (font (size 0.25 0.25) (thickness 0.04)) (justify mirror))
    )
    (fp_text user "License: Apache-2.0" (at -0.95 -5.169 90) (layer "B.Fab") hide
        (effects (font (size 0.7 0.7) (thickness 0.15)) (justify left bottom mirror))
    )
    (fp_text user "Author: Antmicro" (at -0.95 -4.169 90) (layer "B.Fab") hide
        (effects (font (size 0.7 0.7) (thickness 0.15)) (justify left bottom mirror))
    )
    (fp_rect (start -0.925 0.47) (end 0.925 -0.47)
      (stroke (width 0.05) (type default)) (fill none) (layer "B.CrtYd"))
    (fp_rect (start -0.5 0.25) (end 0.5 -0.25)
      (stroke (width 0.15) (type solid)) (fill none) (layer "B.Fab"))
    (pad "1" smd roundrect (at -0.48 0 270) (size 0.59 0.64) (layers "B.Cu" "B.Paste" "B.Mask") (roundrect_rratio 0.25)
      (net 432 "Net-(U14-~{RESET})") (pintype "passive"))
    (pad "2" smd roundrect (at 0.48 0 270) (size 0.59 0.64) (layers "B.Cu" "B.Paste" "B.Mask") (roundrect_rratio 0.25)
      (net 1 "GND") (pintype "passive"))
  )

  (footprint "antmicro-footprints:FB_0402_1005Metric" (layer "B.Cu")
    (at 137.5 83.675 -90)
    (descr "Ferrite Bead SMD 0402")
    (tags "ferrite bead SMD 0402")
    (property "Author" "Antmicro")
    (property "Current" "")
    (property "License" "Apache-2.0")
    (property "MPN" "BLM15AG601SN1D")
    (property "Manufacturer" "Murata")
    (property "Public" "False")
    (property "Sheetfile" "interfaces.kicad_sch")
    (property "Sheetname" "Interfaces")
    (property "Val" "600Z/0.3A")
    (property "ki_description" "Ferrite Bead, 0402 [1005 Metric], 600 ohm, 300 mA, BLM15AG_SN, 0.6 ohm, ± 25%, General use")
    (property "ki_keywords" "0402, SMT, FERRITE BEAD, PASSIVE")
    (attr smd)
    (fp_text reference "FB10" (at -2.585 -0.06 90) (layer "B.SilkS")
        (effects (font (size 0.7 0.7) (thickness 0.15)) (justify mirror))
    )
    (fp_text value "FB_600Z_0.3A_Murata-BLM15AG_0402" (at 0 -1.17 90) (layer "B.Fab")
        (effects (font (size 1 1) (thickness 0.15)) (justify mirror))
    )
    (fp_text user "Author: Antmicro" (at -0.95 -4.169 90) (layer "B.Fab") hide
        (effects (font (size 0.7 0.7) (thickness 0.15)) (justify left bottom mirror))
    )
    (fp_text user "${REFERENCE}" (at 0 0 90) (layer "B.Fab")
        (effects (font (size 0.25 0.25) (thickness 0.04)) (justify mirror))
    )
    (fp_text user "License: Apache-2.0" (at -0.95 -5.169 90) (layer "B.Fab") hide
        (effects (font (size 0.7 0.7) (thickness 0.15)) (justify left bottom mirror))
    )
    (fp_rect (start -0.925 0.47) (end 0.925 -0.47)
      (stroke (width 0.05) (type default)) (fill none) (layer "B.CrtYd"))
    (fp_rect (start -0.5 0.25) (end 0.5 -0.25)
      (stroke (width 0.15) (type solid)) (fill none) (layer "B.Fab"))
    (pad "1" smd roundrect (at -0.48 0 270) (size 0.59 0.64) (layers "B.Cu" "B.Paste" "B.Mask") (roundrect_rratio 0.25)
      (net 2 "VCC3V3") (pintype "passive"))
    (pad "2" smd roundrect (at 0.48 0 270) (size 0.59 0.64) (layers "B.Cu" "B.Paste" "B.Mask") (roundrect_rratio 0.25)
      (net 307 "Net-(U14-V_{PHY})") (pintype "passive"))
  )

  (footprint "antmicro-footprints:R_0402_1005Metric" (layer "B.Cu")
    (at 134.85 83.675 -90)
    (descr "Resistor SMD 0402")
    (tags "resistor SMD 0402")
    (property "Author" "Antmicro")
    (property "DNP" "DNP")
    (property "License" "Apache-2.0")
    (property "MPN" "CR0402-FX-4701GLF")
    (property "Manufacturer" "Bourns")
    (property "Public" "False")
    (property "Sheetfile" "interfaces.kicad_sch")
    (property "Sheetname" "Interfaces")
    (property "Tolerance" "1%")
    (property "Val" "4k7")
    (property "dnp" "")
    (property "exclude_from_bom" "")
    (property "ki_description" "SMD Chip Resistor, 4.7 kohm, ± 1%, 62.5 mW, 0402 [1005 Metric], Thick Film, General Purpose")
    (property "ki_keywords" "0402, SMT, RESISTOR, PASSIVE")
    (attr smd exclude_from_pos_files exclude_from_bom)
    (fp_text reference "R146" (at -2.551667 -0.11 90) (layer "B.SilkS")
        (effects (font (size 0.7 0.7) (thickness 0.15)) (justify mirror))
    )
    (fp_text value "R_4k7_0402" (at 0 -1.17 90) (layer "B.Fab")
        (effects (font (size 1 1) (thickness 0.15)) (justify mirror))
    )
    (fp_text user "License: Apache-2.0" (at -0.95 -5.169 90) (layer "B.Fab") hide
        (effects (font (size 0.7 0.7) (thickness 0.15)) (justify left bottom mirror))
    )
    (fp_text user "${REFERENCE}" (at 0 0 90) (layer "B.Fab")
        (effects (font (size 0.25 0.25) (thickness 0.04)) (justify mirror))
    )
    (fp_text user "Author: Antmicro" (at -0.95 -4.169 90) (layer "B.Fab") hide
        (effects (font (size 0.7 0.7) (thickness 0.15)) (justify left bottom mirror))
    )
    (fp_rect (start -0.925 0.47) (end 0.925 -0.47)
      (stroke (width 0.05) (type default)) (fill none) (layer "B.CrtYd"))
    (fp_rect (start -0.5 0.25) (end 0.5 -0.25)
      (stroke (width 0.15) (type solid)) (fill none) (layer "B.Fab"))
    (pad "1" smd roundrect (at -0.48 0 270) (size 0.59 0.64) (layers "B.Cu" "B.Paste" "B.Mask") (roundrect_rratio 0.25)
      (net 415 "VBUS") (pintype "passive"))
    (pad "2" smd roundrect (at 0.48 0 270) (size 0.59 0.64) (layers "B.Cu" "B.Paste" "B.Mask") (roundrect_rratio 0.25)
      (net 432 "Net-(U14-~{RESET})") (pintype "passive"))
  )

  (footprint "antmicro-footprints:C_0603_1608Metric" (layer "B.Cu")
    (at 140.1 93.775)
    (descr "Capacitor SMD 0603")
    (tags "capacitor 0603")
    (property "Author" "Antmicro")
    (property "Dielectric" "")
    (property "License" "Apache-2.0")
    (property "MPN" "C0603C335M9PACTU")
    (property "Manufacturer" "KEMET")
    (property "Public" "False")
    (property "Sheetfile" "interfaces.kicad_sch")
    (property "Sheetname" "Interfaces")
    (property "Val" "3u3")
    (property "Voltage" "")
    (property "ki_description" "SMD Multilayer Ceramic Capacitor, 3.3 µF, 6.3 V, 0603 [1608 Metric], ± 20%, X5R, C Series KEMET")
    (property "ki_keywords" "0603, SMT, CAPACITOR, PASSIVE, CERAMIC, MLCC")
    (attr smd)
    (fp_text reference "C257" (at 3.11 0.07) (layer "B.SilkS")
        (effects (font (size 0.7 0.7) (thickness 0.15)) (justify mirror))
    )
    (fp_text value "C_3u3_0603" (at 0 -1.9) (layer "B.Fab")
        (effects (font (size 1 1) (thickness 0.15)) (justify mirror))
    )
    (fp_text user "Author: Antmicro" (at -1.682 -4.894 180) (layer "B.Fab") hide
        (effects (font (size 0.7 0.7) (thickness 0.15)) (justify left bottom mirror))
    )
    (fp_text user "${REFERENCE}" (at -1.682 -3.895 180) (layer "B.Fab") hide
        (effects (font (size 0.7 0.7) (thickness 0.15)) (justify left bottom mirror))
    )
    (fp_text user "License: Apache-2.0" (at -1.682 -5.895 180) (layer "B.Fab") hide
        (effects (font (size 0.7 0.7) (thickness 0.15)) (justify left bottom mirror))
    )
    (fp_line (start -0.15 -0.4) (end 0.15 -0.4)
      (stroke (width 0.15) (type solid)) (layer "B.SilkS"))
    (fp_line (start -0.15 0.4) (end 0.15 0.4)
      (stroke (width 0.15) (type solid)) (layer "B.SilkS"))
    (fp_rect (start -1.25 0.65) (end 1.25 -0.65)
      (stroke (width 0.05) (type solid)) (fill none) (layer "B.CrtYd"))
    (fp_rect (start -0.8 0.4) (end 0.8 -0.4)
      (stroke (width 0.15) (type solid)) (fill none) (layer "B.Fab"))
    (pad "1" smd roundrect (at -0.7 0) (size 0.8 1) (layers "B.Cu" "B.Paste" "B.Mask") (roundrect_rratio 0.2)
      (net 1 "GND") (pintype "passive"))
    (pad "2" smd roundrect (at 0.7 0) (size 0.8 1) (layers "B.Cu" "B.Paste" "B.Mask") (roundrect_rratio 0.2)
      (net 657 "VREGOUT") (pintype "passive"))
  )

  (footprint "antmicro-footprints:R_0402_1005Metric" (layer "B.Cu")
    (at 139.75 83.64 -90)
    (descr "Resistor SMD 0402")
    (tags "resistor SMD 0402")
    (property "Author" "Antmicro")
    (property "License" "Apache-2.0")
    (property "MPN" "CR0402-FX-4701GLF")
    (property "Manufacturer" "Bourns")
    (property "Public" "False")
    (property "Sheetfile" "interfaces.kicad_sch")
    (property "Sheetname" "Interfaces")
    (property "Tolerance" "1%")
    (property "Val" "4k7")
    (property "ki_description" "SMD Chip Resistor, 4.7 kohm, ± 1%, 62.5 mW, 0402 [1005 Metric], Thick Film, General Purpose")
    (property "ki_keywords" "0402, SMT, RESISTOR, PASSIVE")
    (attr smd)
    (fp_text reference "R150" (at -2.516667 -0.01 90) (layer "B.SilkS")
        (effects (font (size 0.7 0.7) (thickness 0.15)) (justify mirror))
    )
    (fp_text value "R_4k7_0402" (at 0 -1.17 90) (layer "B.Fab")
        (effects (font (size 1 1) (thickness 0.15)) (justify mirror))
    )
    (fp_text user "${REFERENCE}" (at 0 0 90) (layer "B.Fab")
        (effects (font (size 0.25 0.25) (thickness 0.04)) (justify mirror))
    )
    (fp_text user "License: Apache-2.0" (at -0.95 -5.169 90) (layer "B.Fab") hide
        (effects (font (size 0.7 0.7) (thickness 0.15)) (justify left bottom mirror))
    )
    (fp_text user "Author: Antmicro" (at -0.95 -4.169 90) (layer "B.Fab") hide
        (effects (font (size 0.7 0.7) (thickness 0.15)) (justify left bottom mirror))
    )
    (fp_rect (start -0.925 0.47) (end 0.925 -0.47)
      (stroke (width 0.05) (type default)) (fill none) (layer "B.CrtYd"))
    (fp_rect (start -0.5 0.25) (end 0.5 -0.25)
      (stroke (width 0.15) (type solid)) (fill none) (layer "B.Fab"))
    (pad "1" smd roundrect (at -0.48 0 270) (size 0.59 0.64) (layers "B.Cu" "B.Paste" "B.Mask") (roundrect_rratio 0.25)
      (net 415 "VBUS") (pintype "passive"))
    (pad "2" smd roundrect (at 0.48 0 270) (size 0.59 0.64) (layers "B.Cu" "B.Paste" "B.Mask") (roundrect_rratio 0.25)
      (net 434 "Net-(U14-DDBUS7)") (pintype "passive"))
  )

  (footprint "antmicro-footprints:R_0402_1005Metric" (layer "B.Cu")
    (at 140.45 88.375 180)
    (descr "Resistor SMD 0402")
    (tags "resistor SMD 0402")
    (property "Author" "Antmicro")
    (property "License" "Apache-2.0")
    (property "MPN" "CR0402-FX-1002GLF")
    (property "Manufacturer" "Bourns")
    (property "Public" "False")
    (property "Sheetfile" "interfaces.kicad_sch")
    (property "Sheetname" "Interfaces")
    (property "Tolerance" "1%")
    (property "Val" "10k")
    (property "ki_description" "SMD Chip Resistor, 10 kohm, ± 1%, 62.5 mW, 0402 [1005 Metric], Thick Film, General Purpose")
    (property "ki_keywords" "0402, SMT, RESISTOR, PASSIVE")
    (attr smd)
    (fp_text reference "R151" (at -2.24 -0.58 180) (layer "B.SilkS")
        (effects (font (size 0.7 0.7) (thickness 0.15)) (justify mirror))
    )
    (fp_text value "R_10k_0402" (at 0 -1.17 180) (layer "B.Fab")
        (effects (font (size 1 1) (thickness 0.15)) (justify mirror))
    )
    (fp_text user "${REFERENCE}" (at 0 0 180) (layer "B.Fab")
        (effects (font (size 0.25 0.25) (thickness 0.04)) (justify mirror))
    )
    (fp_text user "License: Apache-2.0" (at -0.95 -5.169) (layer "B.Fab") hide
        (effects (font (size 0.7 0.7) (thickness 0.15)) (justify left bottom mirror))
    )
    (fp_text user "Author: Antmicro" (at -0.95 -4.169) (layer "B.Fab") hide
        (effects (font (size 0.7 0.7) (thickness 0.15)) (justify left bottom mirror))
    )
    (fp_rect (start -0.925 0.47) (end 0.925 -0.47)
      (stroke (width 0.05) (type default)) (fill none) (layer "B.CrtYd"))
    (fp_rect (start -0.5 0.25) (end 0.5 -0.25)
      (stroke (width 0.15) (type solid)) (fill none) (layer "B.Fab"))
    (pad "1" smd roundrect (at -0.48 0 180) (size 0.59 0.64) (layers "B.Cu" "B.Paste" "B.Mask") (roundrect_rratio 0.25)
      (net 434 "Net-(U14-DDBUS7)") (pintype "passive"))
    (pad "2" smd roundrect (at 0.48 0 180) (size 0.59 0.64) (layers "B.Cu" "B.Paste" "B.Mask") (roundrect_rratio 0.25)
      (net 1 "GND") (pintype "passive"))
  )

  (footprint "antmicro-footprints:C_0402_1005Metric" (layer "B.Cu")
    (at 134.9 93.925 180)
    (descr "Capacitor SMD 0402")
    (tags "capacitor SMD 0402")
    (property "Author" "Antmicro")
    (property "Dielectric" "X5R")
    (property "License" "Apache-2.0")
    (property "MPN" "GRM155R61H104KE14D")
    (property "Manufacturer" "Murata")
    (property "Public" "False")
    (property "Sheetfile" "interfaces.kicad_sch")
    (property "Sheetname" "Interfaces")
    (property "Val" "100n")
    (property "Voltage" "50V")
    (property "ki_description" "SMD Multilayer Ceramic Capacitor, 0.1 µF, 50 V, 0402 [1005 Metric], ± 10%, X5R, GRM Series")
    (property "ki_keywords" "0402, SMT, CAPACITOR, PASSIVE, CERAMIC, MLCC")
    (attr smd)
    (fp_text reference "C255" (at 0.29 1.02) (layer "B.SilkS")
        (effects (font (size 0.7 0.7) (thickness 0.15)) (justify mirror))
    )
    (fp_text value "C_100n_0402" (at 0 -1.17) (layer "B.Fab")
        (effects (font (size 1 1) (thickness 0.15)) (justify mirror))
    )
    (fp_text user "Author: Antmicro" (at -0.939 -3.399) (layer "B.Fab") hide
        (effects (font (size 0.7 0.7) (thickness 0.15)) (justify left bottom mirror))
    )
    (fp_text user "${REFERENCE}" (at 0 0 90) (layer "B.Fab")
        (effects (font (size 0.25 0.25) (thickness 0.04)) (justify mirror))
    )
    (fp_text user "License: Apache-2.0" (at -0.939 -5.799) (layer "B.Fab") hide
        (effects (font (size 0.7 0.7) (thickness 0.15)) (justify left bottom mirror))
    )
    (fp_rect (start -0.925 0.47) (end 0.925 -0.47)
      (stroke (width 0.05) (type default)) (fill none) (layer "B.CrtYd"))
    (fp_line (start -0.494 -0.248) (end -0.494 0.25)
      (stroke (width 0.15) (type solid)) (layer "B.Fab"))
    (fp_line (start -0.494 0.25) (end 0.504 0.25)
      (stroke (width 0.15) (type solid)) (layer "B.Fab"))
    (fp_line (start 0.504 -0.248) (end -0.494 -0.248)
      (stroke (width 0.15) (type solid)) (layer "B.Fab"))
    (fp_line (start 0.504 0.25) (end 0.504 -0.248)
      (stroke (width 0.15) (type solid)) (layer "B.Fab"))
    (pad "1" smd roundrect (at -0.48 0 180) (size 0.59 0.64) (layers "B.Cu" "B.Paste" "B.Mask") (roundrect_rratio 0.25)
      (net 1 "GND") (pintype "passive"))
    (pad "2" smd roundrect (at 0.48 0 180) (size 0.59 0.64) (layers "B.Cu" "B.Paste" "B.Mask") (roundrect_rratio 0.25)
      (net 657 "VREGOUT") (pintype "passive"))
  )

  (footprint "antmicro-footprints:C_0402_1005Metric" (layer "B.Cu")
    (at 137.5 93.875 180)
    (descr "Capacitor SMD 0402")
    (tags "capacitor SMD 0402")
    (property "Author" "Antmicro")
    (property "Dielectric" "X5R")
    (property "License" "Apache-2.0")
    (property "MPN" "GRM155R61H104KE14D")
    (property "Manufacturer" "Murata")
    (property "Public" "False")
    (property "Sheetfile" "interfaces.kicad_sch")
    (property "Sheetname" "Interfaces")
    (property "Val" "100n")
    (property "Voltage" "50V")
    (property "ki_description" "SMD Multilayer Ceramic Capacitor, 0.1 µF, 50 V, 0402 [1005 Metric], ± 10%, X5R, GRM Series")
    (property "ki_keywords" "0402, SMT, CAPACITOR, PASSIVE, CERAMIC, MLCC")
    (attr smd)
    (fp_text reference "C254" (at 0.12 0.92) (layer "B.SilkS")
        (effects (font (size 0.7 0.7) (thickness 0.15)) (justify mirror))
    )
    (fp_text value "C_100n_0402" (at 0 -1.17) (layer "B.Fab")
        (effects (font (size 1 1) (thickness 0.15)) (justify mirror))
    )
    (fp_text user "License: Apache-2.0" (at -0.939 -5.799) (layer "B.Fab") hide
        (effects (font (size 0.7 0.7) (thickness 0.15)) (justify left bottom mirror))
    )
    (fp_text user "Author: Antmicro" (at -0.939 -3.399) (layer "B.Fab") hide
        (effects (font (size 0.7 0.7) (thickness 0.15)) (justify left bottom mirror))
    )
    (fp_text user "${REFERENCE}" (at 0 0) (layer "B.Fab")
        (effects (font (size 0.25 0.25) (thickness 0.04)) (justify mirror))
    )
    (fp_rect (start -0.925 0.47) (end 0.925 -0.47)
      (stroke (width 0.05) (type default)) (fill none) (layer "B.CrtYd"))
    (fp_line (start -0.494 -0.248) (end -0.494 0.25)
      (stroke (width 0.15) (type solid)) (layer "B.Fab"))
    (fp_line (start -0.494 0.25) (end 0.504 0.25)
      (stroke (width 0.15) (type solid)) (layer "B.Fab"))
    (fp_line (start 0.504 -0.248) (end -0.494 -0.248)
      (stroke (width 0.15) (type solid)) (layer "B.Fab"))
    (fp_line (start 0.504 0.25) (end 0.504 -0.248)
      (stroke (width 0.15) (type solid)) (layer "B.Fab"))
    (pad "1" smd roundrect (at -0.48 0 180) (size 0.59 0.64) (layers "B.Cu" "B.Paste" "B.Mask") (roundrect_rratio 0.25)
      (net 1 "GND") (pintype "passive"))
    (pad "2" smd roundrect (at 0.48 0 180) (size 0.59 0.64) (layers "B.Cu" "B.Paste" "B.Mask") (roundrect_rratio 0.25)
      (net 2 "VCC3V3") (pintype "passive"))
  )

  (footprint "antmicro-footprints:C_0402_1005Metric" (layer "B.Cu")
    (at 140.1 86.325 90)
    (descr "Capacitor SMD 0402")
    (tags "capacitor SMD 0402")
    (property "Author" "Antmicro")
    (property "Dielectric" "X5R")
    (property "License" "Apache-2.0")
    (property "MPN" "GRM155R61H104KE14D")
    (property "Manufacturer" "Murata")
    (property "Public" "False")
    (property "Sheetfile" "interfaces.kicad_sch")
    (property "Sheetname" "Interfaces")
    (property "Val" "100n")
    (property "Voltage" "50V")
    (property "ki_description" "SMD Multilayer Ceramic Capacitor, 0.1 µF, 50 V, 0402 [1005 Metric], ± 10%, X5R, GRM Series")
    (property "ki_keywords" "0402, SMT, CAPACITOR, PASSIVE, CERAMIC, MLCC")
    (attr smd)
    (fp_text reference "C259" (at 0.03 1.5 90) (layer "B.SilkS")
        (effects (font (size 0.7 0.7) (thickness 0.15)) (justify mirror))
    )
    (fp_text value "C_100n_0402" (at 0 -1.17 90) (layer "B.Fab")
        (effects (font (size 1 1) (thickness 0.15)) (justify mirror))
    )
    (fp_text user "${REFERENCE}" (at 0 0 90) (layer "B.Fab")
        (effects (font (size 0.25 0.25) (thickness 0.04)) (justify mirror))
    )
    (fp_text user "Author: Antmicro" (at -0.939 -3.399 270) (layer "B.Fab") hide
        (effects (font (size 0.7 0.7) (thickness 0.15)) (justify left bottom mirror))
    )
    (fp_text user "License: Apache-2.0" (at -0.939 -5.799 270) (layer "B.Fab") hide
        (effects (font (size 0.7 0.7) (thickness 0.15)) (justify left bottom mirror))
    )
    (fp_rect (start -0.925 0.47) (end 0.925 -0.47)
      (stroke (width 0.05) (type default)) (fill none) (layer "B.CrtYd"))
    (fp_line (start -0.494 -0.248) (end -0.494 0.25)
      (stroke (width 0.15) (type solid)) (layer "B.Fab"))
    (fp_line (start -0.494 0.25) (end 0.504 0.25)
      (stroke (width 0.15) (type solid)) (layer "B.Fab"))
    (fp_line (start 0.504 -0.248) (end -0.494 -0.248)
      (stroke (width 0.15) (type solid)) (layer "B.Fab"))
    (fp_line (start 0.504 0.25) (end 0.504 -0.248)
      (stroke (width 0.15) (type solid)) (layer "B.Fab"))
    (pad "1" smd roundrect (at -0.48 0 90) (size 0.59 0.64) (layers "B.Cu" "B.Paste" "B.Mask") (roundrect_rratio 0.25)
      (net 1 "GND") (pintype "passive"))
    (pad "2" smd roundrect (at 0.48 0 90) (size 0.59 0.64) (layers "B.Cu" "B.Paste" "B.Mask") (roundrect_rratio 0.25)
      (net 657 "VREGOUT") (pintype "passive"))
  )

  (footprint "antmicro-footprints:C_0402_1005Metric" (layer "B.Cu")
    (at 131.9 88.525 90)
    (descr "Capacitor SMD 0402")
    (tags "capacitor SMD 0402")
    (property "Author" "Antmicro")
    (property "Dielectric" "X5R")
    (property "License" "Apache-2.0")
    (property "MPN" "GRM155R61H104KE14D")
    (property "Manufacturer" "Murata")
    (property "Public" "False")
    (property "Sheetfile" "interfaces.kicad_sch")
    (property "Sheetname" "Interfaces")
    (property "Val" "100n")
    (property "Voltage" "50V")
    (property "ki_description" "SMD Multilayer Ceramic Capacitor, 0.1 µF, 50 V, 0402 [1005 Metric], ± 10%, X5R, GRM Series")
    (property "ki_keywords" "0402, SMT, CAPACITOR, PASSIVE, CERAMIC, MLCC")
    (attr smd)
    (fp_text reference "C253" (at -0.06 -1.06 90) (layer "B.SilkS")
        (effects (font (size 0.7 0.7) (thickness 0.15)) (justify mirror))
    )
    (fp_text value "C_100n_0402" (at 0 -1.17 90) (layer "B.Fab")
        (effects (font (size 1 1) (thickness 0.15)) (justify mirror))
    )
    (fp_text user "${REFERENCE}" (at 0 0 90) (layer "B.Fab")
        (effects (font (size 0.25 0.25) (thickness 0.04)) (justify mirror))
    )
    (fp_text user "License: Apache-2.0" (at -0.939 -5.799 270) (layer "B.Fab") hide
        (effects (font (size 0.7 0.7) (thickness 0.15)) (justify left bottom mirror))
    )
    (fp_text user "Author: Antmicro" (at -0.939 -3.399 270) (layer "B.Fab") hide
        (effects (font (size 0.7 0.7) (thickness 0.15)) (justify left bottom mirror))
    )
    (fp_rect (start -0.925 0.47) (end 0.925 -0.47)
      (stroke (width 0.05) (type default)) (fill none) (layer "B.CrtYd"))
    (fp_line (start -0.494 -0.248) (end -0.494 0.25)
      (stroke (width 0.15) (type solid)) (layer "B.Fab"))
    (fp_line (start -0.494 0.25) (end 0.504 0.25)
      (stroke (width 0.15) (type solid)) (layer "B.Fab"))
    (fp_line (start 0.504 -0.248) (end -0.494 -0.248)
      (stroke (width 0.15) (type solid)) (layer "B.Fab"))
    (fp_line (start 0.504 0.25) (end 0.504 -0.248)
      (stroke (width 0.15) (type solid)) (layer "B.Fab"))
    (pad "1" smd roundrect (at -0.48 0 90) (size 0.59 0.64) (layers "B.Cu" "B.Paste" "B.Mask") (roundrect_rratio 0.25)
      (net 1 "GND") (pintype "passive"))
    (pad "2" smd roundrect (at 0.48 0 90) (size 0.59 0.64) (layers "B.Cu" "B.Paste" "B.Mask") (roundrect_rratio 0.25)
      (net 2 "VCC3V3") (pintype "passive"))
  )

  (footprint "antmicro-footprints:C_0402_1005Metric" (layer "B.Cu")
    (at 140.415 92.525)
    (descr "Capacitor SMD 0402")
    (tags "capacitor SMD 0402")
    (property "Author" "Antmicro")
    (property "Dielectric" "X5R")
    (property "License" "Apache-2.0")
    (property "MPN" "GRM155R61H104KE14D")
    (property "Manufacturer" "Murata")
    (property "Public" "False")
    (property "Sheetfile" "interfaces.kicad_sch")
    (property "Sheetname" "Interfaces")
    (property "Val" "100n")
    (property "Voltage" "50V")
    (property "ki_description" "SMD Multilayer Ceramic Capacitor, 0.1 µF, 50 V, 0402 [1005 Metric], ± 10%, X5R, GRM Series")
    (property "ki_keywords" "0402, SMT, CAPACITOR, PASSIVE, CERAMIC, MLCC")
    (attr smd)
    (fp_text reference "C258" (at 2.765 -0.11) (layer "B.SilkS")
        (effects (font (size 0.7 0.7) (thickness 0.15)) (justify mirror))
    )
    (fp_text value "C_100n_0402" (at 0 -1.17) (layer "B.Fab")
        (effects (font (size 1 1) (thickness 0.15)) (justify mirror))
    )
    (fp_text user "Author: Antmicro" (at -0.939 -3.399 180) (layer "B.Fab") hide
        (effects (font (size 0.7 0.7) (thickness 0.15)) (justify left bottom mirror))
    )
    (fp_text user "License: Apache-2.0" (at -0.939 -5.799 180) (layer "B.Fab") hide
        (effects (font (size 0.7 0.7) (thickness 0.15)) (justify left bottom mirror))
    )
    (fp_text user "${REFERENCE}" (at 0 0) (layer "B.Fab")
        (effects (font (size 0.25 0.25) (thickness 0.04)) (justify mirror))
    )
    (fp_rect (start -0.925 0.47) (end 0.925 -0.47)
      (stroke (width 0.05) (type default)) (fill none) (layer "B.CrtYd"))
    (fp_line (start -0.494 -0.248) (end -0.494 0.25)
      (stroke (width 0.15) (type solid)) (layer "B.Fab"))
    (fp_line (start -0.494 0.25) (end 0.504 0.25)
      (stroke (width 0.15) (type solid)) (layer "B.Fab"))
    (fp_line (start 0.504 -0.248) (end -0.494 -0.248)
      (stroke (width 0.15) (type solid)) (layer "B.Fab"))
    (fp_line (start 0.504 0.25) (end 0.504 -0.248)
      (stroke (width 0.15) (type solid)) (layer "B.Fab"))
    (pad "1" smd roundrect (at -0.48 0) (size 0.59 0.64) (layers "B.Cu" "B.Paste" "B.Mask") (roundrect_rratio 0.25)
      (net 1 "GND") (pintype "passive"))
    (pad "2" smd roundrect (at 0.48 0) (size 0.59 0.64) (layers "B.Cu" "B.Paste" "B.Mask") (roundrect_rratio 0.25)
      (net 2 "VCC3V3") (pintype "passive"))
  )

  (footprint "antmicro-footprints:C_0402_1005Metric" (layer "B.Cu")
    (at 139.1 86.325 90)
    (descr "Capacitor SMD 0402")
    (tags "capacitor SMD 0402")
    (property "Author" "Antmicro")
    (property "Dielectric" "")
    (property "License" "Apache-2.0")
    (property "MPN" "GRM155R61A475MEAAD")
    (property "Manufacturer" "Murata")
    (property "Public" "False")
    (property "Sheetfile" "interfaces.kicad_sch")
    (property "Sheetname" "Interfaces")
    (property "Val" "4u7")
    (property "Voltage" "")
    (property "ki_description" "SMD Multilayer Ceramic Capacitor, 4.7 µF, 10 V, 0402 [1005 Metric], ± 20%, X5R, GRM Series")
    (property "ki_keywords" "0402, SMT, CAPACITOR, PASSIVE")
    (attr smd)
    (fp_text reference "C252" (at -2.96 -0.05 90) (layer "B.SilkS")
        (effects (font (size 0.7 0.7) (thickness 0.15)) (justify mirror))
    )
    (fp_text value "C_4u7_0402" (at 0 -1.17 90) (layer "B.Fab")
        (effects (font (size 1 1) (thickness 0.15)) (justify mirror))
    )
    (fp_text user "${REFERENCE}" (at 0 0 90) (layer "B.Fab")
        (effects (font (size 0.25 0.25) (thickness 0.04)) (justify mirror))
    )
    (fp_text user "Author: Antmicro" (at -0.939 -3.399 270) (layer "B.Fab") hide
        (effects (font (size 0.7 0.7) (thickness 0.15)) (justify left bottom mirror))
    )
    (fp_text user "License: Apache-2.0" (at -0.939 -5.799 270) (layer "B.Fab") hide
        (effects (font (size 0.7 0.7) (thickness 0.15)) (justify left bottom mirror))
    )
    (fp_rect (start -0.925 0.47) (end 0.925 -0.47)
      (stroke (width 0.05) (type default)) (fill none) (layer "B.CrtYd"))
    (fp_line (start -0.494 -0.248) (end -0.494 0.25)
      (stroke (width 0.15) (type solid)) (layer "B.Fab"))
    (fp_line (start -0.494 0.25) (end 0.504 0.25)
      (stroke (width 0.15) (type solid)) (layer "B.Fab"))
    (fp_line (start 0.504 -0.248) (end -0.494 -0.248)
      (stroke (width 0.15) (type solid)) (layer "B.Fab"))
    (fp_line (start 0.504 0.25) (end 0.504 -0.248)
      (stroke (width 0.15) (type solid)) (layer "B.Fab"))
    (pad "1" smd roundrect (at -0.48 0 90) (size 0.59 0.64) (layers "B.Cu" "B.Paste" "B.Mask") (roundrect_rratio 0.25)
      (net 1 "GND") (pintype "passive"))
    (pad "2" smd roundrect (at 0.48 0 90) (size 0.59 0.64) (layers "B.Cu" "B.Paste" "B.Mask") (roundrect_rratio 0.25)
      (net 307 "Net-(U14-V_{PHY})") (pintype "passive"))
  )

  (footprint "antmicro-footprints:C_0402_1005Metric" (layer "B.Cu")
    (at 138.1 86.325 90)
    (descr "Capacitor SMD 0402")
    (tags "capacitor SMD 0402")
    (property "Author" "Antmicro")
    (property "Dielectric" "X5R")
    (property "License" "Apache-2.0")
    (property "MPN" "GRM155R61H104KE14D")
    (property "Manufacturer" "Murata")
    (property "Public" "False")
    (property "Sheetfile" "interfaces.kicad_sch")
    (property "Sheetname" "Interfaces")
    (property "Val" "100n")
    (property "Voltage" "50V")
    (property "ki_description" "SMD Multilayer Ceramic Capacitor, 0.1 µF, 50 V, 0402 [1005 Metric], ± 10%, X5R, GRM Series")
    (property "ki_keywords" "0402, SMT, CAPACITOR, PASSIVE, CERAMIC, MLCC")
    (attr smd)
    (fp_text reference "C249" (at -3.04 -0.09 90) (layer "B.SilkS")
        (effects (font (size 0.7 0.7) (thickness 0.15)) (justify mirror))
    )
    (fp_text value "C_100n_0402" (at 0 -1.17 90) (layer "B.Fab")
        (effects (font (size 1 1) (thickness 0.15)) (justify mirror))
    )
    (fp_text user "Author: Antmicro" (at -0.939 -3.399 270) (layer "B.Fab") hide
        (effects (font (size 0.7 0.7) (thickness 0.15)) (justify left bottom mirror))
    )
    (fp_text user "License: Apache-2.0" (at -0.939 -5.799 270) (layer "B.Fab") hide
        (effects (font (size 0.7 0.7) (thickness 0.15)) (justify left bottom mirror))
    )
    (fp_text user "${REFERENCE}" (at 0 0 90) (layer "B.Fab")
        (effects (font (size 0.25 0.25) (thickness 0.04)) (justify mirror))
    )
    (fp_rect (start -0.925 0.47) (end 0.925 -0.47)
      (stroke (width 0.05) (type default)) (fill none) (layer "B.CrtYd"))
    (fp_line (start -0.494 -0.248) (end -0.494 0.25)
      (stroke (width 0.15) (type solid)) (layer "B.Fab"))
    (fp_line (start -0.494 0.25) (end 0.504 0.25)
      (stroke (width 0.15) (type solid)) (layer "B.Fab"))
    (fp_line (start 0.504 -0.248) (end -0.494 -0.248)
      (stroke (width 0.15) (type solid)) (layer "B.Fab"))
    (fp_line (start 0.504 0.25) (end 0.504 -0.248)
      (stroke (width 0.15) (type solid)) (layer "B.Fab"))
    (pad "1" smd roundrect (at -0.48 0 90) (size 0.59 0.64) (layers "B.Cu" "B.Paste" "B.Mask") (roundrect_rratio 0.25)
      (net 1 "GND") (pintype "passive"))
    (pad "2" smd roundrect (at 0.48 0 90) (size 0.59 0.64) (layers "B.Cu" "B.Paste" "B.Mask") (roundrect_rratio 0.25)
      (net 307 "Net-(U14-V_{PHY})") (pintype "passive"))
  )

  (footprint "antmicro-footprints:C_0402_1005Metric" (layer "B.Cu")
    (at 144.675 87.425 -90)
    (descr "Capacitor SMD 0402")
    (tags "capacitor SMD 0402")
    (property "Author" "Antmicro")
    (property "Dielectric" "X5R")
    (property "License" "Apache-2.0")
    (property "MPN" "GRM155R61H104KE14D")
    (property "Manufacturer" "Murata")
    (property "Public" "False")
    (property "Sheetfile" "interfaces.kicad_sch")
    (property "Sheetname" "Interfaces")
    (property "Val" "100n")
    (property "Voltage" "50V")
    (property "ki_description" "SMD Multilayer Ceramic Capacitor, 0.1 µF, 50 V, 0402 [1005 Metric], ± 10%, X5R, GRM Series")
    (property "ki_keywords" "0402, SMT, CAPACITOR, PASSIVE, CERAMIC, MLCC")
    (attr smd)
    (fp_text reference "C251" (at -0.34 1.025 90) (layer "B.SilkS")
        (effects (font (size 0.7 0.7) (thickness 0.15)) (justify mirror))
    )
    (fp_text value "C_100n_0402" (at 0 -1.17 90) (layer "B.Fab")
        (effects (font (size 1 1) (thickness 0.15)) (justify mirror))
    )
    (fp_text user "Author: Antmicro" (at -0.939 -3.399 90) (layer "B.Fab") hide
        (effects (font (size 0.7 0.7) (thickness 0.15)) (justify left bottom mirror))
    )
    (fp_text user "License: Apache-2.0" (at -0.939 -5.799 90) (layer "B.Fab") hide
        (effects (font (size 0.7 0.7) (thickness 0.15)) (justify left bottom mirror))
    )
    (fp_text user "${REFERENCE}" (at 0 0 90) (layer "B.Fab")
        (effects (font (size 0.25 0.25) (thickness 0.04)) (justify mirror))
    )
    (fp_rect (start -0.925 0.47) (end 0.925 -0.47)
      (stroke (width 0.05) (type default)) (fill none) (layer "B.CrtYd"))
    (fp_line (start -0.494 -0.248) (end -0.494 0.25)
      (stroke (width 0.15) (type solid)) (layer "B.Fab"))
    (fp_line (start -0.494 0.25) (end 0.504 0.25)
      (stroke (width 0.15) (type solid)) (layer "B.Fab"))
    (fp_line (start 0.504 -0.248) (end -0.494 -0.248)
      (stroke (width 0.15) (type solid)) (layer "B.Fab"))
    (fp_line (start 0.504 0.25) (end 0.504 -0.248)
      (stroke (width 0.15) (type solid)) (layer "B.Fab"))
    (pad "1" smd roundrect (at -0.48 0 270) (size 0.59 0.64) (layers "B.Cu" "B.Paste" "B.Mask") (roundrect_rratio 0.25)
      (net 1 "GND") (pintype "passive"))
    (pad "2" smd roundrect (at 0.48 0 270) (size 0.59 0.64) (layers "B.Cu" "B.Paste" "B.Mask") (roundrect_rratio 0.25)
      (net 2 "VCC3V3") (pintype "passive"))
  )

  (footprint "antmicro-footprints:C_0402_1005Metric" (layer "B.Cu")
    (at 135.1 86.325 90)
    (descr "Capacitor SMD 0402")
    (tags "capacitor SMD 0402")
    (property "Author" "Antmicro")
    (property "Dielectric" "")
    (property "License" "Apache-2.0")
    (property "MPN" "GRM155R61A475MEAAD")
    (property "Manufacturer" "Murata")
    (property "Public" "False")
    (property "Sheetfile" "interfaces.kicad_sch")
    (property "Sheetname" "Interfaces")
    (property "Val" "4u7")
    (property "Voltage" "")
    (property "ki_description" "SMD Multilayer Ceramic Capacitor, 4.7 µF, 10 V, 0402 [1005 Metric], ± 20%, X5R, GRM Series")
    (property "ki_keywords" "0402, SMT, CAPACITOR, PASSIVE")
    (attr smd)
    (fp_text reference "C250" (at -3.06 0.075 90) (layer "B.SilkS")
        (effects (font (size 0.7 0.7) (thickness 0.15)) (justify mirror))
    )
    (fp_text value "C_4u7_0402" (at 0 -1.17 90) (layer "B.Fab")
        (effects (font (size 1 1) (thickness 0.15)) (justify mirror))
    )
    (fp_text user "${REFERENCE}" (at 0 0 90) (layer "B.Fab")
        (effects (font (size 0.25 0.25) (thickness 0.04)) (justify mirror))
    )
    (fp_text user "License: Apache-2.0" (at -0.939 -5.799 270) (layer "B.Fab") hide
        (effects (font (size 0.7 0.7) (thickness 0.15)) (justify left bottom mirror))
    )
    (fp_text user "Author: Antmicro" (at -0.939 -3.399 270) (layer "B.Fab") hide
        (effects (font (size 0.7 0.7) (thickness 0.15)) (justify left bottom mirror))
    )
    (fp_rect (start -0.925 0.47) (end 0.925 -0.47)
      (stroke (width 0.05) (type default)) (fill none) (layer "B.CrtYd"))
    (fp_line (start -0.494 -0.248) (end -0.494 0.25)
      (stroke (width 0.15) (type solid)) (layer "B.Fab"))
    (fp_line (start -0.494 0.25) (end 0.504 0.25)
      (stroke (width 0.15) (type solid)) (layer "B.Fab"))
    (fp_line (start 0.504 -0.248) (end -0.494 -0.248)
      (stroke (width 0.15) (type solid)) (layer "B.Fab"))
    (fp_line (start 0.504 0.25) (end 0.504 -0.248)
      (stroke (width 0.15) (type solid)) (layer "B.Fab"))
    (pad "1" smd roundrect (at -0.48 0 90) (size 0.59 0.64) (layers "B.Cu" "B.Paste" "B.Mask") (roundrect_rratio 0.25)
      (net 1 "GND") (pintype "passive"))
    (pad "2" smd roundrect (at 0.48 0 90) (size 0.59 0.64) (layers "B.Cu" "B.Paste" "B.Mask") (roundrect_rratio 0.25)
      (net 306 "Net-(U14-V_{PLL})") (pintype "passive"))
  )

  (footprint "antmicro-footprints:C_0402_1005Metric" (layer "B.Cu")
    (at 136.1 86.325 90)
    (descr "Capacitor SMD 0402")
    (tags "capacitor SMD 0402")
    (property "Author" "Antmicro")
    (property "Dielectric" "X5R")
    (property "License" "Apache-2.0")
    (property "MPN" "GRM155R61H104KE14D")
    (property "Manufacturer" "Murata")
    (property "Public" "False")
    (property "Sheetfile" "interfaces.kicad_sch")
    (property "Sheetname" "Interfaces")
    (property "Val" "100n")
    (property "Voltage" "50V")
    (property "ki_description" "SMD Multilayer Ceramic Capacitor, 0.1 µF, 50 V, 0402 [1005 Metric], ± 10%, X5R, GRM Series")
    (property "ki_keywords" "0402, SMT, CAPACITOR, PASSIVE, CERAMIC, MLCC")
    (attr smd)
    (fp_text reference "C227" (at -3.04 0.01 90) (layer "B.SilkS")
        (effects (font (size 0.7 0.7) (thickness 0.15)) (justify mirror))
    )
    (fp_text value "C_100n_0402" (at 0 -1.17 90) (layer "B.Fab")
        (effects (font (size 1 1) (thickness 0.15)) (justify mirror))
    )
    (fp_text user "Author: Antmicro" (at -0.939 -3.399 270) (layer "B.Fab") hide
        (effects (font (size 0.7 0.7) (thickness 0.15)) (justify left bottom mirror))
    )
    (fp_text user "${REFERENCE}" (at 0 0 90) (layer "B.Fab")
        (effects (font (size 0.25 0.25) (thickness 0.04)) (justify mirror))
    )
    (fp_text user "License: Apache-2.0" (at -0.939 -5.799 270) (layer "B.Fab") hide
        (effects (font (size 0.7 0.7) (thickness 0.15)) (justify left bottom mirror))
    )
    (fp_rect (start -0.925 0.47) (end 0.925 -0.47)
      (stroke (width 0.05) (type default)) (fill none) (layer "B.CrtYd"))
    (fp_line (start -0.494 -0.248) (end -0.494 0.25)
      (stroke (width 0.15) (type solid)) (layer "B.Fab"))
    (fp_line (start -0.494 0.25) (end 0.504 0.25)
      (stroke (width 0.15) (type solid)) (layer "B.Fab"))
    (fp_line (start 0.504 -0.248) (end -0.494 -0.248)
      (stroke (width 0.15) (type solid)) (layer "B.Fab"))
    (fp_line (start 0.504 0.25) (end 0.504 -0.248)
      (stroke (width 0.15) (type solid)) (layer "B.Fab"))
    (pad "1" smd roundrect (at -0.48 0 90) (size 0.59 0.64) (layers "B.Cu" "B.Paste" "B.Mask") (roundrect_rratio 0.25)
      (net 1 "GND") (pintype "passive"))
    (pad "2" smd roundrect (at 0.48 0 90) (size 0.59 0.64) (layers "B.Cu" "B.Paste" "B.Mask") (roundrect_rratio 0.25)
      (net 306 "Net-(U14-V_{PLL})") (pintype "passive"))
  )

  (footprint "antmicro-footprints:C_0402_1005Metric" (layer "B.Cu")
    (at 140.415 89.775)
    (descr "Capacitor SMD 0402")
    (tags "capacitor SMD 0402")
    (property "Author" "Antmicro")
    (property "Dielectric" "X5R")
    (property "License" "Apache-2.0")
    (property "MPN" "GRM155R61H104KE14D")
    (property "Manufacturer" "Murata")
    (property "Public" "False")
    (property "Sheetfile" "interfaces.kicad_sch")
    (property "Sheetname" "Interfaces")
    (property "Val" "100n")
    (property "Voltage" "50V")
    (property "ki_description" "SMD Multilayer Ceramic Capacitor, 0.1 µF, 50 V, 0402 [1005 Metric], ± 10%, X5R, GRM Series")
    (property "ki_keywords" "0402, SMT, CAPACITOR, PASSIVE, CERAMIC, MLCC")
    (attr smd)
    (fp_text reference "C256" (at 0.055 1.42) (layer "B.SilkS")
        (effects (font (size 0.7 0.7) (thickness 0.15)) (justify mirror))
    )
    (fp_text value "C_100n_0402" (at 0 -1.17) (layer "B.Fab")
        (effects (font (size 1 1) (thickness 0.15)) (justify mirror))
    )
    (fp_text user "Author: Antmicro" (at -0.939 -3.399 180) (layer "B.Fab") hide
        (effects (font (size 0.7 0.7) (thickness 0.15)) (justify left bottom mirror))
    )
    (fp_text user "${REFERENCE}" (at 0 0) (layer "B.Fab")
        (effects (font (size 0.25 0.25) (thickness 0.04)) (justify mirror))
    )
    (fp_text user "License: Apache-2.0" (at -0.939 -5.799 180) (layer "B.Fab") hide
        (effects (font (size 0.7 0.7) (thickness 0.15)) (justify left bottom mirror))
    )
    (fp_rect (start -0.925 0.47) (end 0.925 -0.47)
      (stroke (width 0.05) (type default)) (fill none) (layer "B.CrtYd"))
    (fp_line (start -0.494 -0.248) (end -0.494 0.25)
      (stroke (width 0.15) (type solid)) (layer "B.Fab"))
    (fp_line (start -0.494 0.25) (end 0.504 0.25)
      (stroke (width 0.15) (type solid)) (layer "B.Fab"))
    (fp_line (start 0.504 -0.248) (end -0.494 -0.248)
      (stroke (width 0.15) (type solid)) (layer "B.Fab"))
    (fp_line (start 0.504 0.25) (end 0.504 -0.248)
      (stroke (width 0.15) (type solid)) (layer "B.Fab"))
    (pad "1" smd roundrect (at -0.48 0) (size 0.59 0.64) (layers "B.Cu" "B.Paste" "B.Mask") (roundrect_rratio 0.25)
      (net 1 "GND") (pintype "passive"))
    (pad "2" smd roundrect (at 0.48 0) (size 0.59 0.64) (layers "B.Cu" "B.Paste" "B.Mask") (roundrect_rratio 0.25)
      (net 2 "VCC3V3") (pintype "passive"))
  )

  (footprint "antmicro-footprints:C_0402_1005Metric" (layer "B.Cu")
    (at 129.65 115.525)
    (descr "Capacitor SMD 0402")
    (tags "capacitor SMD 0402")
    (property "Author" "Antmicro")
    (property "Dielectric" "X5R")
    (property "License" "Apache-2.0")
    (property "MPN" "GRM155R61H104KE14D")
    (property "Manufacturer" "Murata")
    (property "Public" "False")
    (property "Sheetfile" "interfaces.kicad_sch")
    (property "Sheetname" "Interfaces")
    (property "Val" "100n")
    (property "Voltage" "50V")
    (property "ki_description" "SMD Multilayer Ceramic Capacitor, 0.1 µF, 50 V, 0402 [1005 Metric], ± 10%, X5R, GRM Series")
    (property "ki_keywords" "0402, SMT, CAPACITOR, PASSIVE, CERAMIC, MLCC")
    (attr smd)
    (fp_text reference "C74" (at 2 -0.025 180) (layer "B.SilkS")
        (effects (font (size 0.7 0.7) (thickness 0.127)) (justify mirror))
    )
    (fp_text value "C_100n_0402" (at 0 -1.17) (layer "B.Fab")
        (effects (font (size 1 1) (thickness 0.15)) (justify mirror))
    )
    (fp_text user "${REFERENCE}" (at 0 0) (layer "B.Fab")
        (effects (font (size 0.25 0.25) (thickness 0.04)) (justify mirror))
    )
    (fp_text user "License: Apache-2.0" (at -0.939 -5.799 180) (layer "B.Fab") hide
        (effects (font (size 0.7 0.7) (thickness 0.15)) (justify left bottom mirror))
    )
    (fp_text user "Author: Antmicro" (at -0.939 -3.399 180) (layer "B.Fab") hide
        (effects (font (size 0.7 0.7) (thickness 0.15)) (justify left bottom mirror))
    )
    (fp_rect (start -0.925 0.47) (end 0.925 -0.47)
      (stroke (width 0.05) (type default)) (fill none) (layer "B.CrtYd"))
    (fp_line (start -0.494 -0.248) (end -0.494 0.25)
      (stroke (width 0.15) (type solid)) (layer "B.Fab"))
    (fp_line (start -0.494 0.25) (end 0.504 0.25)
      (stroke (width 0.15) (type solid)) (layer "B.Fab"))
    (fp_line (start 0.504 -0.248) (end -0.494 -0.248)
      (stroke (width 0.15) (type solid)) (layer "B.Fab"))
    (fp_line (start 0.504 0.25) (end 0.504 -0.248)
      (stroke (width 0.15) (type solid)) (layer "B.Fab"))
    (pad "1" smd roundrect (at -0.48 0) (size 0.59 0.64) (layers "B.Cu" "B.Paste" "B.Mask") (roundrect_rratio 0.25)
      (net 226 "Net-(U9-VDDA1.8)") (pintype "passive"))
    (pad "2" smd roundrect (at 0.48 0) (size 0.59 0.64) (layers "B.Cu" "B.Paste" "B.Mask") (roundrect_rratio 0.25)
      (net 1 "GND") (pintype "passive"))
  )

  (footprint "antmicro-footprints:C_0402_1005Metric" (layer "B.Cu")
    (at 81.715 125.095 90)
    (descr "Capacitor SMD 0402")
    (tags "capacitor SMD 0402")
    (property "Author" "Antmicro")
    (property "Dielectric" "")
    (property "License" "Apache-2.0")
    (property "MPN" "C1005X5R1E474M050BB")
    (property "Manufacturer" "TDK")
    (property "Public" "False")
    (property "Sheetfile" "ddr3.kicad_sch")
    (property "Sheetname" "DDR3")
    (property "Val" "470n")
    (property "Voltage" "")
    (property "ki_description" "SMD Multilayer Ceramic Capacitor, 0.47 µF, 25 V, 0402 [1005 Metric], ± 20%, X5R, C")
    (property "ki_keywords" "0402, SMT, CAPACITOR, PASSIVE, CERAMIC, MLCC")
    (attr smd)
    (fp_text reference "C91" (at -1.76 0.835 90) (layer "B.SilkS")
        (effects (font (size 0.7 0.7) (thickness 0.127)) (justify mirror))
    )
    (fp_text value "C_470n_0402" (at 0 -1.17 90) (layer "B.Fab")
        (effects (font (size 1 1) (thickness 0.15)) (justify mirror))
    )
    (fp_text user "${REFERENCE}" (at 0 0 90) (layer "B.Fab")
        (effects (font (size 0.25 0.25) (thickness 0.04)) (justify mirror))
    )
    (fp_text user "License: Apache-2.0" (at -0.939 -5.799 270) (layer "B.Fab") hide
        (effects (font (size 0.7 0.7) (thickness 0.15)) (justify left bottom mirror))
    )
    (fp_text user "Author: Antmicro" (at -0.939 -3.399 270) (layer "B.Fab") hide
        (effects (font (size 0.7 0.7) (thickness 0.15)) (justify left bottom mirror))
    )
    (fp_rect (start -0.925 0.47) (end 0.925 -0.47)
      (stroke (width 0.05) (type default)) (fill none) (layer "B.CrtYd"))
    (fp_line (start -0.494 -0.248) (end -0.494 0.25)
      (stroke (width 0.15) (type solid)) (layer "B.Fab"))
    (fp_line (start -0.494 0.25) (end 0.504 0.25)
      (stroke (width 0.15) (type solid)) (layer "B.Fab"))
    (fp_line (start 0.504 -0.248) (end -0.494 -0.248)
      (stroke (width 0.15) (type solid)) (layer "B.Fab"))
    (fp_line (start 0.504 0.25) (end 0.504 -0.248)
      (stroke (width 0.15) (type solid)) (layer "B.Fab"))
    (pad "1" smd roundrect (at -0.48 0 90) (size 0.59 0.64) (layers "B.Cu" "B.Paste" "B.Mask") (roundrect_rratio 0.25)
      (net 1 "GND") (pintype "passive"))
    (pad "2" smd roundrect (at 0.48 0 90) (size 0.59 0.64) (layers "B.Cu" "B.Paste" "B.Mask") (roundrect_rratio 0.25)
      (net 3 "VCC1V35") (pintype "passive"))
  )

  (footprint "antmicro-footprints:C_0402_1005Metric" (layer "B.Cu")
    (at 97.68 138.47 90)
    (descr "Capacitor SMD 0402")
    (tags "capacitor SMD 0402")
    (property "Author" "Antmicro")
    (property "Dielectric" "X5R")
    (property "License" "Apache-2.0")
    (property "MPN" "GRM155R61H104KE14D")
    (property "Manufacturer" "Murata")
    (property "Public" "False")
    (property "Sheetfile" "fpga-banks.kicad_sch")
    (property "Sheetname" "FPGA banks")
    (property "Val" "100n")
    (property "Voltage" "50V")
    (property "ki_description" "SMD Multilayer Ceramic Capacitor, 0.1 µF, 50 V, 0402 [1005 Metric], ± 10%, X5R, GRM Series")
    (property "ki_keywords" "0402, SMT, CAPACITOR, PASSIVE, CERAMIC, MLCC")
    (attr smd)
    (fp_text reference "C57" (at 0.045 -2.03 270) (layer "B.SilkS")
        (effects (font (size 0.7 0.7) (thickness 0.15)) (justify mirror))
    )
    (fp_text value "C_100n_0402" (at 0 -1.17 270) (layer "B.Fab")
        (effects (font (size 1 1) (thickness 0.15)) (justify mirror))
    )
    (fp_text user "${REFERENCE}" (at 0 0 270) (layer "B.Fab")
        (effects (font (size 0.25 0.25) (thickness 0.04)) (justify mirror))
    )
    (fp_text user "Author: Antmicro" (at -0.939 -3.399 270) (layer "B.Fab") hide
        (effects (font (size 0.7 0.7) (thickness 0.15)) (justify left bottom mirror))
    )
    (fp_text user "License: Apache-2.0" (at -0.939 -5.799 270) (layer "B.Fab") hide
        (effects (font (size 0.7 0.7) (thickness 0.15)) (justify left bottom mirror))
    )
    (fp_rect (start -0.925 0.47) (end 0.925 -0.47)
      (stroke (width 0.05) (type default)) (fill none) (layer "B.CrtYd"))
    (fp_line (start -0.494 -0.248) (end -0.494 0.25)
      (stroke (width 0.15) (type solid)) (layer "B.Fab"))
    (fp_line (start -0.494 0.25) (end 0.504 0.25)
      (stroke (width 0.15) (type solid)) (layer "B.Fab"))
    (fp_line (start 0.504 -0.248) (end -0.494 -0.248)
      (stroke (width 0.15) (type solid)) (layer "B.Fab"))
    (fp_line (start 0.504 0.25) (end 0.504 -0.248)
      (stroke (width 0.15) (type solid)) (layer "B.Fab"))
    (pad "1" smd roundrect (at -0.48 0 90) (size 0.59 0.64) (layers "B.Cu" "B.Paste" "B.Mask") (roundrect_rratio 0.25)
      (net 106 "PCIE_BMC_TX_DN") (pintype "passive"))
    (pad "2" smd roundrect (at 0.48 0 90) (size 0.59 0.64) (layers "B.Cu" "B.Paste" "B.Mask") (roundrect_rratio 0.25)
      (net 686 "/FPGA banks/PCIE_BMC_TX_C_DN") (pintype "passive"))
  )

  (footprint "antmicro-footprints:C_0402_1005Metric" (layer "B.Cu")
    (at 96.71 138.47 90)
    (descr "Capacitor SMD 0402")
    (tags "capacitor SMD 0402")
    (property "Author" "Antmicro")
    (property "Dielectric" "X5R")
    (property "License" "Apache-2.0")
    (property "MPN" "GRM155R61H104KE14D")
    (property "Manufacturer" "Murata")
    (property "Public" "False")
    (property "Sheetfile" "fpga-banks.kicad_sch")
    (property "Sheetname" "FPGA banks")
    (property "Val" "100n")
    (property "Voltage" "50V")
    (property "ki_description" "SMD Multilayer Ceramic Capacitor, 0.1 µF, 50 V, 0402 [1005 Metric], ± 10%, X5R, GRM Series")
    (property "ki_keywords" "0402, SMT, CAPACITOR, PASSIVE, CERAMIC, MLCC")
    (attr smd)
    (fp_text reference "C58" (at 0.045 -2.035 270) (layer "B.SilkS")
        (effects (font (size 0.7 0.7) (thickness 0.15)) (justify mirror))
    )
    (fp_text value "C_100n_0402" (at 0 -1.17 270) (layer "B.Fab")
        (effects (font (size 1 1) (thickness 0.15)) (justify mirror))
    )
    (fp_text user "License: Apache-2.0" (at -0.939 -5.799 270) (layer "B.Fab") hide
        (effects (font (size 0.7 0.7) (thickness 0.15)) (justify left bottom mirror))
    )
    (fp_text user "Author: Antmicro" (at -0.939 -3.399 270) (layer "B.Fab") hide
        (effects (font (size 0.7 0.7) (thickness 0.15)) (justify left bottom mirror))
    )
    (fp_text user "${REFERENCE}" (at 0 0 270) (layer "B.Fab")
        (effects (font (size 0.25 0.25) (thickness 0.04)) (justify mirror))
    )
    (fp_rect (start -0.925 0.47) (end 0.925 -0.47)
      (stroke (width 0.05) (type default)) (fill none) (layer "B.CrtYd"))
    (fp_line (start -0.494 -0.248) (end -0.494 0.25)
      (stroke (width 0.15) (type solid)) (layer "B.Fab"))
    (fp_line (start -0.494 0.25) (end 0.504 0.25)
      (stroke (width 0.15) (type solid)) (layer "B.Fab"))
    (fp_line (start 0.504 -0.248) (end -0.494 -0.248)
      (stroke (width 0.15) (type solid)) (layer "B.Fab"))
    (fp_line (start 0.504 0.25) (end 0.504 -0.248)
      (stroke (width 0.15) (type solid)) (layer "B.Fab"))
    (pad "1" smd roundrect (at -0.48 0 90) (size 0.59 0.64) (layers "B.Cu" "B.Paste" "B.Mask") (roundrect_rratio 0.25)
      (net 105 "PCIE_BMC_TX_DP") (pintype "passive"))
    (pad "2" smd roundrect (at 0.48 0 90) (size 0.59 0.64) (layers "B.Cu" "B.Paste" "B.Mask") (roundrect_rratio 0.25)
      (net 687 "/FPGA banks/PCIE_BMC_TX_C_DP") (pintype "passive"))
  )

  (footprint "antmicro-footprints:FB_0603_1608Metric" (layer "B.Cu")
    (at 108.75 92.75 90)
    (property "Author" "Antmicro")
    (property "Current" "")
    (property "License" "Apache-2.0")
    (property "MPN" "BLM18PG121SN1D")
    (property "Manufacturer" "Murata")
    (property "Public" "False")
    (property "Sheetfile" "ethernet.kicad_sch")
    (property "Sheetname" "Ethernet")
    (property "Val" "120Z/2A")
    (property "ki_description" "Ferrite Bead, 0603 [1608 Metric], 120 ohm, 2 A, BLM18P, 0.05 ohm, ± 25%, DC power line")
    (property "ki_keywords" "0603, SMT, FERRITE BEAD, PASSIVE")
    (attr smd)
    (fp_text reference "FB3" (at 0.435 1.56 90) (layer "B.SilkS")
        (effects (font (size 0.7 0.7) (thickness 0.127)) (justify mirror))
    )
    (fp_text value "FB_120Z_2A_Murata-BLM18PG_0603" (at 0 -1.9 90) (layer "B.Fab")
        (effects (font (size 1 1) (thickness 0.15)) (justify mirror))
    )
    (fp_text user "${REFERENCE}" (at -1.653 -4.6 270) (layer "B.Fab") hide
        (effects (font (size 0.7 0.7) (thickness 0.15)) (justify left bottom mirror))
    )
    (fp_text user "Author: Antmicro" (at -1.653 -3.162 270) (layer "B.Fab") hide
        (effects (font (size 0.7 0.7) (thickness 0.15)) (justify left bottom mirror))
    )
    (fp_text user "License: Apache-2.0" (at -1.653 -5.9 270) (layer "B.Fab") hide
        (effects (font (size 0.7 0.7) (thickness 0.15)) (justify left bottom mirror))
    )
    (fp_line (start -0.15 -0.4) (end 0.15 -0.4)
      (stroke (width 0.15) (type solid)) (layer "B.SilkS"))
    (fp_line (start -0.15 0.4) (end 0.15 0.4)
      (stroke (width 0.15) (type solid)) (layer "B.SilkS"))
    (fp_rect (start -1.25 0.65) (end 1.25 -0.65)
      (stroke (width 0.05) (type solid)) (fill none) (layer "B.CrtYd"))
    (fp_line (start -0.803 -0.406) (end -0.803 0.408)
      (stroke (width 0.15) (type solid)) (layer "B.Fab"))
    (fp_line (start 0.8 -0.406) (end -0.803 -0.406)
      (stroke (width 0.15) (type solid)) (layer "B.Fab"))
    (fp_line (start 0.8 0.408) (end -0.803 0.408)
      (stroke (width 0.15) (type solid)) (layer "B.Fab"))
    (fp_line (start 0.8 0.408) (end 0.8 -0.406)
      (stroke (width 0.15) (type solid)) (layer "B.Fab"))
    (pad "1" smd roundrect (at -0.7 0 90) (size 0.8 1) (layers "B.Cu" "B.Paste" "B.Mask") (roundrect_rratio 0.2)
      (net 10 "/Ethernet/AVDDL_PLL") (pintype "passive"))
    (pad "2" smd roundrect (at 0.7 0 90) (size 0.8 1) (layers "B.Cu" "B.Paste" "B.Mask") (roundrect_rratio 0.2)
      (net 211 "VCC1V2") (pintype "passive"))
  )

  (footprint "antmicro-footprints:R_0402_1005Metric" (layer "B.Cu")
    (at 94.55 98.125 180)
    (descr "Resistor SMD 0402")
    (tags "resistor SMD 0402")
    (property "Author" "Antmicro")
    (property "License" "Apache-2.0")
    (property "MPN" "CR0402-FX-4702GLF")
    (property "Manufacturer" "Bourns")
    (property "Public" "False")
    (property "Sheetfile" "interfaces.kicad_sch")
    (property "Sheetname" "Interfaces")
    (property "Tolerance" "1%")
    (property "Val" "47k")
    (property "ki_description" "SMD Chip Resistor, 47 kohm, ± 1%, 62.5 mW, 0402 [1005 Metric], Thick Film, General Purpose")
    (property "ki_keywords" "0402, SMT, RESISTOR, PASSIVE")
    (attr smd)
    (fp_text reference "R60" (at 0 -7.275) (layer "B.SilkS")
        (effects (font (size 0.7 0.7) (thickness 0.127)) (justify mirror))
    )
    (fp_text value "R_47k_0402" (at 0 -1.17) (layer "B.Fab")
        (effects (font (size 1 1) (thickness 0.15)) (justify mirror))
    )
    (fp_text user "Author: Antmicro" (at -0.95 -4.169) (layer "B.Fab") hide
        (effects (font (size 0.7 0.7) (thickness 0.15)) (justify left bottom mirror))
    )
    (fp_text user "${REFERENCE}" (at 0 0) (layer "B.Fab")
        (effects (font (size 0.25 0.25) (thickness 0.04)) (justify mirror))
    )
    (fp_text user "License: Apache-2.0" (at -0.95 -5.169) (layer "B.Fab") hide
        (effects (font (size 0.7 0.7) (thickness 0.15)) (justify left bottom mirror))
    )
    (fp_rect (start -0.925 0.47) (end 0.925 -0.47)
      (stroke (width 0.05) (type default)) (fill none) (layer "B.CrtYd"))
    (fp_rect (start -0.5 0.25) (end 0.5 -0.25)
      (stroke (width 0.15) (type solid)) (fill none) (layer "B.Fab"))
    (pad "1" smd roundrect (at -0.48 0 180) (size 0.59 0.64) (layers "B.Cu" "B.Paste" "B.Mask") (roundrect_rratio 0.25)
      (net 2 "VCC3V3") (pintype "passive"))
    (pad "2" smd roundrect (at 0.48 0 180) (size 0.59 0.64) (layers "B.Cu" "B.Paste" "B.Mask") (roundrect_rratio 0.25)
      (net 287 "MMC_CMD") (pintype "passive"))
  )

  (footprint "antmicro-footprints:R_0402_1005Metric" (layer "B.Cu")
    (at 94.565 97.1)
    (descr "Resistor SMD 0402")
    (tags "resistor SMD 0402")
    (property "Author" "Antmicro")
    (property "License" "Apache-2.0")
    (property "MPN" "CR0402-FX-22R0GLF")
    (property "Manufacturer" "Bourns")
    (property "Public" "False")
    (property "Sheetfile" "interfaces.kicad_sch")
    (property "Sheetname" "Interfaces")
    (property "Tolerance" "1%")
    (property "Val" "22R")
    (property "ki_description" "SMD Chip Resistor, 22 ohm, ± 1%, 62.5 mW, 0402 [1005 Metric], Thick Film, General Purpose")
    (property "ki_keywords" "0402, SMT, RESISTOR, PASSIVE")
    (attr smd)
    (fp_text reference "R14" (at -0.015 7.375) (layer "B.SilkS")
        (effects (font (size 0.7 0.7) (thickness 0.127)) (justify mirror))
    )
    (fp_text value "R_22R_0402" (at 0 -1.17) (layer "B.Fab")
        (effects (font (size 1 1) (thickness 0.15)) (justify mirror))
    )
    (fp_text user "Author: Antmicro" (at -0.95 -4.169 180) (layer "B.Fab") hide
        (effects (font (size 0.7 0.7) (thickness 0.15)) (justify left bottom mirror))
    )
    (fp_text user "${REFERENCE}" (at 0 0) (layer "B.Fab")
        (effects (font (size 0.25 0.25) (thickness 0.04)) (justify mirror))
    )
    (fp_text user "License: Apache-2.0" (at -0.95 -5.169 180) (layer "B.Fab") hide
        (effects (font (size 0.7 0.7) (thickness 0.15)) (justify left bottom mirror))
    )
    (fp_rect (start -0.925 0.47) (end 0.925 -0.47)
      (stroke (width 0.05) (type default)) (fill none) (layer "B.CrtYd"))
    (fp_rect (start -0.5 0.25) (end 0.5 -0.25)
      (stroke (width 0.15) (type solid)) (fill none) (layer "B.Fab"))
    (pad "1" smd roundrect (at -0.48 0) (size 0.59 0.64) (layers "B.Cu" "B.Paste" "B.Mask") (roundrect_rratio 0.25)
      (net 403 "Net-(U6-CLK)") (pintype "passive"))
    (pad "2" smd roundrect (at 0.48 0) (size 0.59 0.64) (layers "B.Cu" "B.Paste" "B.Mask") (roundrect_rratio 0.25)
      (net 288 "MMC_CLK") (pintype "passive"))
  )

  (footprint "antmicro-footprints:C_0402_1005Metric" (layer "B.Cu")
    (at 97.3 95.2)
    (descr "Capacitor SMD 0402")
    (tags "capacitor SMD 0402")
    (property "Author" "Antmicro")
    (property "Dielectric" "X7R")
    (property "License" "Apache-2.0")
    (property "MPN" "GRM155R71H103KA88D")
    (property "Manufacturer" "Murata")
    (property "Public" "False")
    (property "Sheetfile" "ethernet.kicad_sch")
    (property "Sheetname" "Ethernet")
    (property "Val" "10n")
    (property "Voltage" "50V")
    (property "ki_description" "SMD Multilayer Ceramic Capacitor, 10000 pF, 50 V, 0402 [1005 Metric], ± 10%, X7R, GRM Series")
    (property "ki_keywords" "0402, SMT, CAPACITOR, PASSIVE")
    (attr smd)
    (fp_text reference "C11" (at 0.08 1.145) (layer "B.SilkS")
        (effects (font (size 0.7 0.7) (thickness 0.127)) (justify mirror))
    )
    (fp_text value "C_10n_0402" (at 0 -1.17) (layer "B.Fab")
        (effects (font (size 1 1) (thickness 0.15)) (justify mirror))
    )
    (fp_text user "${REFERENCE}" (at 0 0) (layer "B.Fab")
        (effects (font (size 0.25 0.25) (thickness 0.04)) (justify mirror))
    )
    (fp_text user "License: Apache-2.0" (at -0.939 -5.799 180) (layer "B.Fab") hide
        (effects (font (size 0.7 0.7) (thickness 0.15)) (justify left bottom mirror))
    )
    (fp_text user "Author: Antmicro" (at -0.939 -3.399 180) (layer "B.Fab") hide
        (effects (font (size 0.7 0.7) (thickness 0.15)) (justify left bottom mirror))
    )
    (fp_rect (start -0.925 0.47) (end 0.925 -0.47)
      (stroke (width 0.05) (type default)) (fill none) (layer "B.CrtYd"))
    (fp_line (start -0.494 -0.248) (end -0.494 0.25)
      (stroke (width 0.15) (type solid)) (layer "B.Fab"))
    (fp_line (start -0.494 0.25) (end 0.504 0.25)
      (stroke (width 0.15) (type solid)) (layer "B.Fab"))
    (fp_line (start 0.504 -0.248) (end -0.494 -0.248)
      (stroke (width 0.15) (type solid)) (layer "B.Fab"))
    (fp_line (start 0.504 0.25) (end 0.504 -0.248)
      (stroke (width 0.15) (type solid)) (layer "B.Fab"))
    (pad "1" smd roundrect (at -0.48 0) (size 0.59 0.64) (layers "B.Cu" "B.Paste" "B.Mask") (roundrect_rratio 0.25)
      (net 1 "GND") (pintype "passive"))
    (pad "2" smd roundrect (at 0.48 0) (size 0.59 0.64) (layers "B.Cu" "B.Paste" "B.Mask") (roundrect_rratio 0.25)
      (net 2 "VCC3V3") (pintype "passive"))
  )

  (footprint "antmicro-footprints:C_0402_1005Metric" (layer "B.Cu")
    (at 100.1 96.95 180)
    (descr "Capacitor SMD 0402")
    (tags "capacitor SMD 0402")
    (property "Author" "Antmicro")
    (property "Dielectric" "X7R")
    (property "License" "Apache-2.0")
    (property "MPN" "GRM155R71H103KA88D")
    (property "Manufacturer" "Murata")
    (property "Public" "False")
    (property "Sheetfile" "ethernet.kicad_sch")
    (property "Sheetname" "Ethernet")
    (property "Val" "10n")
    (property "Voltage" "50V")
    (property "ki_description" "SMD Multilayer Ceramic Capacitor, 10000 pF, 50 V, 0402 [1005 Metric], ± 10%, X7R, GRM Series")
    (property "ki_keywords" "0402, SMT, CAPACITOR, PASSIVE")
    (attr smd)
    (fp_text reference "C9" (at 1.61 -0.345) (layer "B.SilkS")
        (effects (font (size 0.7 0.7) (thickness 0.127)) (justify mirror))
    )
    (fp_text value "C_10n_0402" (at 0 -1.17) (layer "B.Fab")
        (effects (font (size 1 1) (thickness 0.15)) (justify mirror))
    )
    (fp_text user "${REFERENCE}" (at 0 0) (layer "B.Fab")
        (effects (font (size 0.25 0.25) (thickness 0.04)) (justify mirror))
    )
    (fp_text user "License: Apache-2.0" (at -0.939 -5.799) (layer "B.Fab") hide
        (effects (font (size 0.7 0.7) (thickness 0.15)) (justify left bottom mirror))
    )
    (fp_text user "Author: Antmicro" (at -0.939 -3.399) (layer "B.Fab") hide
        (effects (font (size 0.7 0.7) (thickness 0.15)) (justify left bottom mirror))
    )
    (fp_rect (start -0.925 0.47) (end 0.925 -0.47)
      (stroke (width 0.05) (type default)) (fill none) (layer "B.CrtYd"))
    (fp_line (start -0.494 -0.248) (end -0.494 0.25)
      (stroke (width 0.15) (type solid)) (layer "B.Fab"))
    (fp_line (start -0.494 0.25) (end 0.504 0.25)
      (stroke (width 0.15) (type solid)) (layer "B.Fab"))
    (fp_line (start 0.504 -0.248) (end -0.494 -0.248)
      (stroke (width 0.15) (type solid)) (layer "B.Fab"))
    (fp_line (start 0.504 0.25) (end 0.504 -0.248)
      (stroke (width 0.15) (type solid)) (layer "B.Fab"))
    (pad "1" smd roundrect (at -0.48 0 180) (size 0.59 0.64) (layers "B.Cu" "B.Paste" "B.Mask") (roundrect_rratio 0.25)
      (net 1 "GND") (pintype "passive"))
    (pad "2" smd roundrect (at 0.48 0 180) (size 0.59 0.64) (layers "B.Cu" "B.Paste" "B.Mask") (roundrect_rratio 0.25)
      (net 211 "VCC1V2") (pintype "passive"))
  )

  (footprint "antmicro-footprints:C_0402_1005Metric" (layer "B.Cu")
    (at 97.3 94.15)
    (descr "Capacitor SMD 0402")
    (tags "capacitor SMD 0402")
    (property "Author" "Antmicro")
    (property "Dielectric" "X7R")
    (property "License" "Apache-2.0")
    (property "MPN" "GRM155R71H103KA88D")
    (property "Manufacturer" "Murata")
    (property "Public" "False")
    (property "Sheetfile" "ethernet.kicad_sch")
    (property "Sheetname" "Ethernet")
    (property "Val" "10n")
    (property "Voltage" "50V")
    (property "ki_description" "SMD Multilayer Ceramic Capacitor, 10000 pF, 50 V, 0402 [1005 Metric], ± 10%, X7R, GRM Series")
    (property "ki_keywords" "0402, SMT, CAPACITOR, PASSIVE")
    (attr smd)
    (fp_text reference "C5" (at -0.47 -0.885) (layer "B.SilkS")
        (effects (font (size 0.7 0.7) (thickness 0.127)) (justify mirror))
    )
    (fp_text value "C_10n_0402" (at 0 -1.17) (layer "B.Fab")
        (effects (font (size 1 1) (thickness 0.15)) (justify mirror))
    )
    (fp_text user "Author: Antmicro" (at -0.939 -3.399 180) (layer "B.Fab") hide
        (effects (font (size 0.7 0.7) (thickness 0.15)) (justify left bottom mirror))
    )
    (fp_text user "${REFERENCE}" (at 0 0) (layer "B.Fab")
        (effects (font (size 0.25 0.25) (thickness 0.04)) (justify mirror))
    )
    (fp_text user "License: Apache-2.0" (at -0.939 -5.799 180) (layer "B.Fab") hide
        (effects (font (size 0.7 0.7) (thickness 0.15)) (justify left bottom mirror))
    )
    (fp_rect (start -0.925 0.47) (end 0.925 -0.47)
      (stroke (width 0.05) (type default)) (fill none) (layer "B.CrtYd"))
    (fp_line (start -0.494 -0.248) (end -0.494 0.25)
      (stroke (width 0.15) (type solid)) (layer "B.Fab"))
    (fp_line (start -0.494 0.25) (end 0.504 0.25)
      (stroke (width 0.15) (type solid)) (layer "B.Fab"))
    (fp_line (start 0.504 -0.248) (end -0.494 -0.248)
      (stroke (width 0.15) (type solid)) (layer "B.Fab"))
    (fp_line (start 0.504 0.25) (end 0.504 -0.248)
      (stroke (width 0.15) (type solid)) (layer "B.Fab"))
    (pad "1" smd roundrect (at -0.48 0) (size 0.59 0.64) (layers "B.Cu" "B.Paste" "B.Mask") (roundrect_rratio 0.25)
      (net 1 "GND") (pintype "passive"))
    (pad "2" smd roundrect (at 0.48 0) (size 0.59 0.64) (layers "B.Cu" "B.Paste" "B.Mask") (roundrect_rratio 0.25)
      (net 211 "VCC1V2") (pintype "passive"))
  )

  (footprint "antmicro-footprints:C_0402_1005Metric" (layer "B.Cu")
    (at 100.1 97.95 180)
    (descr "Capacitor SMD 0402")
    (tags "capacitor SMD 0402")
    (property "Author" "Antmicro")
    (property "Dielectric" "")
    (property "License" "Apache-2.0")
    (property "MPN" "C1005X5R1E474M050BB")
    (property "Manufacturer" "TDK")
    (property "Public" "False")
    (property "Sheetfile" "ethernet.kicad_sch")
    (property "Sheetname" "Ethernet")
    (property "Val" "470n")
    (property "Voltage" "")
    (property "ki_description" "SMD Multilayer Ceramic Capacitor, 0.47 µF, 25 V, 0402 [1005 Metric], ± 20%, X5R, C")
    (property "ki_keywords" "0402, SMT, CAPACITOR, PASSIVE, CERAMIC, MLCC")
    (attr smd)
    (fp_text reference "C4" (at 1.7 -0.225) (layer "B.SilkS")
        (effects (font (size 0.7 0.7) (thickness 0.127)) (justify mirror))
    )
    (fp_text value "C_470n_0402" (at 0 -1.17) (layer "B.Fab")
        (effects (font (size 1 1) (thickness 0.15)) (justify mirror))
    )
    (fp_text user "${REFERENCE}" (at 0 0) (layer "B.Fab")
        (effects (font (size 0.25 0.25) (thickness 0.04)) (justify mirror))
    )
    (fp_text user "Author: Antmicro" (at -0.939 -3.399) (layer "B.Fab") hide
        (effects (font (size 0.7 0.7) (thickness 0.15)) (justify left bottom mirror))
    )
    (fp_text user "License: Apache-2.0" (at -0.939 -5.799) (layer "B.Fab") hide
        (effects (font (size 0.7 0.7) (thickness 0.15)) (justify left bottom mirror))
    )
    (fp_rect (start -0.925 0.47) (end 0.925 -0.47)
      (stroke (width 0.05) (type default)) (fill none) (layer "B.CrtYd"))
    (fp_line (start -0.494 -0.248) (end -0.494 0.25)
      (stroke (width 0.15) (type solid)) (layer "B.Fab"))
    (fp_line (start -0.494 0.25) (end 0.504 0.25)
      (stroke (width 0.15) (type solid)) (layer "B.Fab"))
    (fp_line (start 0.504 -0.248) (end -0.494 -0.248)
      (stroke (width 0.15) (type solid)) (layer "B.Fab"))
    (fp_line (start 0.504 0.25) (end 0.504 -0.248)
      (stroke (width 0.15) (type solid)) (layer "B.Fab"))
    (pad "1" smd roundrect (at -0.48 0 180) (size 0.59 0.64) (layers "B.Cu" "B.Paste" "B.Mask") (roundrect_rratio 0.25)
      (net 1 "GND") (pintype "passive"))
    (pad "2" smd roundrect (at 0.48 0 180) (size 0.59 0.64) (layers "B.Cu" "B.Paste" "B.Mask") (roundrect_rratio 0.25)
      (net 211 "VCC1V2") (pintype "passive"))
  )
  (gr_arc (start 72.909901 172.7849) (mid 73.263524 172.931376) (end 73.41 173.285)
    (stroke (width 0.12) (type solid)) (layer "Edge.Cuts"))
  (gr_arc (start 70.9092 173.2858) (mid 71.055676 172.932177) (end 71.409299 172.785701)
    (stroke (width 0.12) (type solid)) (layer "Edge.Cuts"))
  (gr_arc (start 138.889802 172.784901) (mid 139.243425 172.931377) (end 139.389901 173.285)
    (stroke (width 0.12) (type solid)) (layer "Edge.Cuts"))
  (gr_line (start 70.9 178.5) (end 70.2 179.3)
    (stroke (width 0.12) (type solid)) (layer "Edge.Cuts"))
  (gr_line (start 140.2 179.3) (end 149 179.3)
    (stroke (width 0.12) (type solid)) (layer "Edge.Cuts"))
  (gr_line (start 140.2 179.3) (end 139.4 178.5)
    (stroke (width 0.12) (type solid)) (layer "Edge.Cuts"))
  (gr_line (start 139.4 178.5) (end 139.389901 173.285)
    (stroke (width 0.12) (type solid)) (layer "Edge.Cuts"))
  (gr_line (start 138.889802 172.784901) (end 137.39 172.784901)
    (stroke (width 0.12) (type solid)) (layer "Edge.Cuts"))
  (gr_line (start 149 179.3) (end 150.1 177.3)
    (stroke (width 0.12) (type solid)) (layer "Edge.Cuts"))
  (gr_line (start 150.1 58.9) (end 113.74 58.9)
    (stroke (width 0.12) (type solid)) (layer "Edge.Cuts"))
  (gr_line (start 150.1 177.3) (end 150.1 58.9)
    (stroke (width 0.12) (type solid)) (layer "Edge.Cuts"))
  (gr_line (start 70.2 179.3) (end 61.3 179.3)
    (stroke (width 0.12) (type solid)) (layer "Edge.Cuts"))
  (gr_line (start 60.1 177.3) (end 61.3 179.3)
    (stroke (width 0.12) (type solid)) (layer "Edge.Cuts"))
  (gr_line (start 60.1 177.3) (end 60.1 58.9)
    (stroke (width 0.12) (type solid)) (layer "Edge.Cuts"))
  (gr_line (start 70.9092 173.2858) (end 70.9 178.5)
    (stroke (width 0.12) (type solid)) (layer "Edge.Cuts"))
  (gr_line (start 72.909901 172.784901) (end 71.409299 172.785701)
    (stroke (width 0.12) (type solid)) (layer "Edge.Cuts"))
  (gr_line (start 73.4 178.5) (end 73.41 173.285)
    (stroke (width 0.12) (type solid)) (layer "Edge.Cuts"))
  (gr_line (start 74.2 179.3) (end 73.4 178.5)
    (stroke (width 0.12) (type solid)) (layer "Edge.Cuts"))
  (gr_line (start 82.6 179.3) (end 74.2 179.3)
    (stroke (width 0.12) (type solid)) (layer "Edge.Cuts"))
  (gr_line (start 83.4 178.5) (end 82.6 179.3)
    (stroke (width 0.12) (type solid)) (layer "Edge.Cuts"))
  (gr_line (start 83.365 173.245) (end 83.4 178.5)
    (stroke (width 0.12) (type solid)) (layer "Edge.Cuts"))
  (gr_arc (start 83.365 173.245) (mid 84.49 172.12) (end 85.615 173.245)
    (stroke (width 0.12) (type solid)) (layer "Edge.Cuts"))
  (gr_line (start 85.6 178.5) (end 85.615 173.245)
    (stroke (width 0.12) (type solid)) (layer "Edge.Cuts"))
  (gr_line (start 86.4 179.3) (end 85.6 178.5)
    (stroke (width 0.12) (type solid)) (layer "Edge.Cuts"))
  (gr_line (start 103.2 179.3) (end 86.4 179.3)
    (stroke (width 0.12) (type solid)) (layer "Edge.Cuts"))
  (gr_line (start 104 178.5) (end 103.2 179.3)
    (stroke (width 0.12) (type solid)) (layer "Edge.Cuts"))
  (gr_line (start 103.97 173.045) (end 104 178.5)
    (stroke (width 0.12) (type solid)) (layer "Edge.Cuts"))
  (gr_arc (start 103.97 173.045) (mid 104.895 172.12) (end 105.82 173.045)
    (stroke (width 0.12) (type solid)) (layer "Edge.Cuts"))
  (gr_arc (start 115.779502 173.490245) (mid 117.154755 172.114992) (end 118.530008 173.490245)
    (stroke (width 0.12) (type solid)) (layer "Edge.Cuts"))
  (gr_line (start 105.8 178.5) (end 105.82 173.045)
    (stroke (width 0.12) (type solid)) (layer "Edge.Cuts"))
  (gr_line (start 106.6 179.3) (end 105.8 178.5)
    (stroke (width 0.12) (type solid)) (layer "Edge.Cuts"))
  (gr_line (start 115 179.3) (end 106.6 179.3)
    (stroke (width 0.12) (type solid)) (layer "Edge.Cuts"))
  (gr_line (start 115.8 178.5) (end 115 179.3)
    (stroke (width 0.12) (type solid)) (layer "Edge.Cuts"))
  (gr_line (start 115.779502 173.490245) (end 115.8 178.5)
    (stroke (width 0.12) (type solid)) (layer "Edge.Cuts"))
  (gr_line (start 118.5 178.5) (end 118.530008 173.490245)
    (stroke (width 0.12) (type solid)) (layer "Edge.Cuts"))
  (gr_line (start 119.3 179.3) (end 118.5 178.5)
    (stroke (width 0.12) (type solid)) (layer "Edge.Cuts"))
  (gr_line (start 136.1 179.3) (end 119.3 179.3)
    (stroke (width 0.12) (type solid)) (layer "Edge.Cuts"))
  (gr_line (start 136.9 178.5) (end 136.1 179.3)
    (stroke (width 0.12) (type solid)) (layer "Edge.Cuts"))
  (gr_arc (start 136.889901 173.285) (mid 137.036377 172.931377) (end 137.39 172.784901)
    (stroke (width 0.12) (type solid)) (layer "Edge.Cuts"))
  (gr_line (start 136.9 178.5) (end 136.889901 173.285)
    (stroke (width 0.12) (type solid)) (layer "Edge.Cuts"))
  (gr_line (start 96.32 58.9) (end 60.1 58.9)
    (stroke (width 0.12) (type solid)) (layer "Edge.Cuts"))
  (gr_line (start 67.385 169.43) (end 67.39 176.43)
    (stroke (width 0.12) (type solid)) (layer "Edge.Cuts"))
  (gr_line (start 62.39 176.43) (end 62.39 169.43)
    (stroke (width 0.12) (type solid)) (layer "Edge.Cuts"))
  (gr_line (start 67.39 176.43) (end 62.39 176.43)
    (stroke (width 0.12) (type solid)) (layer "Edge.Cuts"))
  (gr_line (start 62.39 169.43) (end 67.385 169.43)
    (stroke (width 0.12) (type solid)) (layer "Edge.Cuts"))
  (gr_arc (start 113.74 61.69) (mid 113.450036 62.390036) (end 112.75 62.68)
    (stroke (width 0.05) (type default)) (layer "Edge.Cuts"))
  (gr_line (start 99.95 62.68) (end 99.95 77.69)
    (stroke (width 0.05) (type default)) (layer "Edge.Cuts"))
  (gr_line (start 100.94 78.68) (end 109.12 78.68)
    (stroke (width 0.05) (type default)) (layer "Edge.Cuts"))
  (gr_line (start 97.31 62.68) (end 99.95 62.68)
    (stroke (width 0.05) (type default)) (layer "Edge.Cuts"))
  (gr_line (start 96.32 58.9) (end 96.32 61.69)
    (stroke (width 0.05) (type default)) (layer "Edge.Cuts"))
  (gr_line (start 113.74 58.9) (end 113.74 61.69)
    (stroke (width 0.05) (type default)) (layer "Edge.Cuts"))
  (gr_line (start 110.11 77.69) (end 110.11 62.68)
    (stroke (width 0.05) (type default)) (layer "Edge.Cuts"))
  (gr_arc (start 97.31 62.68) (mid 96.609964 62.390036) (end 96.32 61.69)
    (stroke (width 0.05) (type default)) (layer "Edge.Cuts"))
  (gr_line (start 110.11 62.68) (end 112.75 62.68)
    (stroke (width 0.05) (type default)) (layer "Edge.Cuts"))
  (gr_arc (start 110.11 77.69) (mid 109.820036 78.390036) (end 109.12 78.68)
    (stroke (width 0.05) (type default)) (layer "Edge.Cuts"))
  (gr_arc (start 100.94 78.68) (mid 100.239964 78.390036) (end 99.95 77.69)
    (stroke (width 0.05) (type default)) (layer "Edge.Cuts"))
  (gr_text "ECP5 DC-SCM \nRev. 1.2.1" (at 88.9 157.6) (layer "F.Cu")
    (effects (font (size 1 1) (thickness 0.2)) (justify left))
  )

  (segment (start 95.2 119.35) (end 95.6 119.75) (width 0.15) (layer "F.Cu") (net 1))
  (segment (start 92.8 119.35) (end 93.2 118.95) (width 0.15) (layer "F.Cu") (net 1))
  (segment (start 95.2 126.55) (end 94.8 126.15) (width 0.15) (layer "F.Cu") (net 1))
  (segment (start 92.8 121.75) (end 93.2 122.15) (width 0.15) (layer "F.Cu") (net 1))
  (segment (start 80.3 118.95) (end 79.9 119.35) (width 0.15) (layer "F.Cu") (net 1))
  (segment (start 129.285 113.015) (end 129.285 112.4) (width 0.2) (layer "F.Cu") (net 1))
  (segment (start 86.7 118.95) (end 87.1 118.55) (width 0.15) (layer "F.Cu") (net 1))
  (segment (start 86.7 120.55) (end 87.1 120.95) (width 0.15) (layer "F.Cu") (net 1))
  (segment (start 80.285 129.355) (end 79.885 129.755) (width 0.15) (layer "F.Cu") (net 1))
  (segment (start 123.185 177.37) (end 123.185 175.895) (width 0.2) (layer "F.Cu") (net 1))
  (segment (start 124.985 175.945) (end 125.005 175.925) (width 0.2) (layer "F.Cu") (net 1))
  (segment (start 124.985 177.37) (end 124.985 175.945) (width 0.2) (layer "F.Cu") (net 1))
  (segment (start 126.785 177.37) (end 126.785 175.895) (width 0.2) (layer "F.Cu") (net 1))
  (segment (start 136.795 164.825) (end 136.795 166.125) (width 0.2) (layer "F.Cu") (net 1))
  (segment (start 135.295 164.825) (end 135.295 166.125) (width 0.2) (layer "F.Cu") (net 1))
  (segment (start 133.795 164.825) (end 133.795 166.125) (width 0.2) (layer "F.Cu") (net 1))
  (segment (start 132.295 164.825) (end 132.295 166.125) (width 0.2) (layer "F.Cu") (net 1))
  (segment (start 130.795 164.825) (end 130.795 166.125) (width 0.2) (layer "F.Cu") (net 1))
  (segment (start 129.295 164.825) (end 129.295 166.125) (width 0.2) (layer "F.Cu") (net 1))
  (segment (start 127.795 164.825) (end 127.795 166.125) (width 0.2) (layer "F.Cu") (net 1))
  (segment (start 126.295 164.825) (end 126.295 166.125) (width 0.2) (layer "F.Cu") (net 1))
  (segment (start 85.9 122.95) (end 86.3 122.55) (width 0.15) (layer "F.Cu") (net 1))
  (segment (start 92.8 123.35) (end 92.4 122.95) (width 0.15) (layer "F.Cu") (net 1))
  (segment (start 85.9 126.15) (end 86.3 126.55) (width 0.15) (layer "F.Cu") (net 1))
  (segment (start 86.7 126.95) (end 87.1 126.55) (width 0.15) (layer "F.Cu") (net 1))
  (segment (start 86.7 128.55) (end 87.1 128.95) (width 0.15) (layer "F.Cu") (net 1))
  (segment (start 116 132.15) (end 116.4 132.55) (width 0.15) (layer "F.Cu") (net 1))
  (segment (start 137.15 154.415) (end 137.15 153.65) (width 0.25) (layer "F.Cu") (net 1))
  (segment (start 105.6 108.95) (end 105.2 109.35) (width 0.15) (layer "F.Cu") (net 1))
  (segment (start 116 114.55) (end 116.4 114.95) (width 0.15) (layer "F.Cu") (net 1))
  (segment (start 92.8 108.95) (end 93.2 108.55) (width 0.15) (layer "F.Cu") (net 1))
  (segment (start 92.8 114.55) (end 92.4 114.95) (width 0.15) (layer "F.Cu") (net 1))
  (segment (start 107.2 108.95) (end 107.6 109.35) (width 0.15) (layer "F.Cu") (net 1))
  (segment (start 92.8 111.35) (end 92.4 111.75) (width 0.15) (layer "F.Cu") (net 1))
  (segment (start 86.3 94.6) (end 86.8 94.1) (width 0.25) (layer "F.Cu") (net 1))
  (segment (start 93.3 101.6) (end 92.8 101.1) (width 0.15) (layer "F.Cu") (net 1))
  (segment (start 83.2 88.05) (end 83.2 88.5) (width 0.25) (layer "F.Cu") (net 1))
  (segment (start 118.239056 84.318104) (end 118.239056 85.393104) (width 0.25) (layer "F.Cu") (net 1))
  (segment (start 71.15 88.05) (end 71.15 88.5) (width 0.25) (layer "F.Cu") (net 1))
  (segment (start 118.239056 85.393104) (end 118.089056 85.543104) (width 0.25) (layer "F.Cu") (net 1))
  (segment (start 89.2 88.05) (end 89.2 88.5) (width 0.25) (layer "F.Cu") (net 1))
  (segment (start 77.25 88.05) (end 77.25 88.5) (width 0.25) (layer "F.Cu") (net 1))
  (segment (start 83.35 87.9) (end 83.2 88.05) (width 0.25) (layer "F.Cu") (net 1))
  (segment (start 83.35 86.825) (end 83.35 87.9) (width 0.25) (layer "F.Cu") (net 1))
  (segment (start 89.35 86.825) (end 89.35 87.9) (width 0.25) (layer "F.Cu") (net 1))
  (segment (start 89.35 87.9) (end 89.2 88.05) (width 0.25) (layer "F.Cu") (net 1))
  (segment (start 71.3 86.825) (end 71.3 87.9) (width 0.25) (layer "F.Cu") (net 1))
  (segment (start 77.4 87.9) (end 77.25 88.05) (width 0.25) (layer "F.Cu") (net 1))
  (segment (start 118.089056 85.543104) (end 118.089056 85.993104) (width 0.25) (layer "F.Cu") (net 1))
  (segment (start 71.3 87.9) (end 71.15 88.05) (width 0.25) (layer "F.Cu") (net 1))
  (segment (start 77.4 86.825) (end 77.4 87.9) (width 0.25) (layer "F.Cu") (net 1))
  (segment (start 91.3 99.6) (end 91.8 100.1) (width 0.15) (layer "F.Cu") (net 1))
  (segment (start 88.3 98.6) (end 87.8 99.1) (width 0.15) (layer "F.Cu") (net 1))
  (segment (start 101.6 116.15) (end 101.2 115.75) (width 0.15) (layer "F.Cu") (net 1))
  (segment (start 106.4 116.15) (end 106.8 115.75) (width 0.15) (layer "F.Cu") (net 1))
  (segment (start 104 116.15) (end 103.6 115.75) (width 0.15) (layer "F.Cu") (net 1))
  (segment (start 104.8 130.55) (end 104.4 130.95) (width 0.15) (layer "F.Cu") (net 1))
  (segment (start 103.2 117.75) (end 102.8 117.35) (width 0.15) (layer "F.Cu") (net 1))
  (segment (start 105.6 117.75) (end 106 117.35) (width 0.15) (layer "F.Cu") (net 1))
  (segment (start 108.8 118.55) (end 108.4 118.95) (width 0.15) (layer "F.Cu") (net 1))
  (segment (start 108.8 120.95) (end 108.4 120.55) (width 0.15) (layer "F.Cu") (net 1))
  (segment (start 100 124.95) (end 99.6 125.35) (width 0.15) (layer "F.Cu") (net 1))
  (segment (start 102.4 121.75) (end 102 122.15) (width 0.15) (layer "F.Cu") (net 1))
  (segment (start 109.6 129.75) (end 110 130.15) (width 0.15) (layer "F.Cu") (net 1))
  (segment (start 107.2 130.55) (end 106.8 130.95) (width 0.15) (layer "F.Cu") (net 1))
  (segment (start 116 108.95) (end 116.4 109.35) (width 0.15) (layer "F.Cu") (net 1))
  (segment (start 102.4 118.55) (end 102 118.15) (width 0.15) (layer "F.Cu") (net 1))
  (segment (start 95.195 132.135) (end 94.795 132.535) (width 0.15) (layer "F.Cu") (net 1))
  (segment (start 101.6 123.35) (end 101.2 123.75) (width 0.15) (layer "F.Cu") (net 1))
  (segment (start 115.2 109.75) (end 115.6 109.35) (width 0.15) (layer "F.Cu") (net 1))
  (segment (start 100 131.35) (end 100.4 130.95) (width 0.15) (layer "F.Cu") (net 1))
  (segment (start 102.4 128.15) (end 102 128.55) (width 0.15) (layer "F.Cu") (net 1))
  (segment (start 104.8 123.35) (end 105.2 123.75) (width 0.15) (layer "F.Cu") (net 1))
  (segment (start 102.4 130.55) (end 102.8 130.15) (width 0.15) (layer "F.Cu") (net 1))
  (segment (start 104.8 129.75) (end 104.4 130.15) (width 0.15) (layer "F.Cu") (net 1))
  (segment (start 103.2 122.55) (end 102.8 122.95) (width 0.15) (layer "F.Cu") (net 1))
  (segment (start 103.2 129.75) (end 103.6 130.15) (width 0.15) (layer "F.Cu") (net 1))
  (segment (start 104 129.75) (end 103.6 130.15) (width 0.15) (layer "F.Cu") (net 1))
  (segment (start 104 121.75) (end 103.6 122.15) (width 0.15) (layer "F.Cu") (net 1))
  (segment (start 107.2 128.15) (end 106.8 128.55) (width 0.15) (layer "F.Cu") (net 1))
  (segment (start 109.6 128.95) (end 109.2 128.55) (width 0.15) (layer "F.Cu") (net 1))
  (segment (start 109.6 128.15) (end 109.2 128.55) (width 0.15) (layer "F.Cu") (net 1))
  (segment (start 112 132.15) (end 111.6 132.55) (width 0.15) (layer "F.Cu") (net 1))
  (segment (start 103.2 116.15) (end 102.8 115.75) (width 0.15) (layer "F.Cu") (net 1))
  (segment (start 112 131.35) (end 111.6 131.75) (width 0.15) (layer "F.Cu") (net 1))
  (segment (start 116 117.75) (end 116.4 117.35) (width 0.15) (layer "F.Cu") (net 1))
  (segment (start 116 119.35) (end 116.4 119.75) (width 0.15) (layer "F.Cu") (net 1))
  (segment (start 113.6 114.55) (end 114 114.95) (width 0.15) (layer "F.Cu") (net 1))
  (segment (start 127.385 127.86) (end 128.135 127.86) (width 0.2) (layer "F.Cu") (net 1))
  (segment (start 128.135 127.86) (end 128.35 128.075) (width 0.2) (layer "F.Cu") (net 1))
  (segment (start 127.935 128.36) (end 128.35 128.775) (width 0.2) (layer "F.Cu") (net 1))
  (segment (start 127.385 128.36) (end 127.935 128.36) (width 0.2) (layer "F.Cu") (net 1))
  (segment (start 95.2 117.75) (end 94.8 117.35) (width 0.15) (layer "F.Cu") (net 1))
  (segment (start 116 129.75) (end 115.6 130.15) (width 0.15) (layer "F.Cu") (net 1))
  (segment (start 105.6 111.35) (end 106 111.75) (width 0.15) (layer "F.Cu") (net 1))
  (segment (start 86.7 117.35) (end 87.1 117.75) (width 0.15) (layer "F.Cu") (net 1))
  (segment (start 80.3 120.55) (end 79.9 120.15) (width 0.15) (layer "F.Cu") (net 1))
  (segment (start 93.3 94.56) (end 92.8 94.06) (width 0.15) (layer "F.Cu") (net 1))
  (segment (start 95.2 114.55) (end 95.6 114.95) (width 0.15) (layer "F.Cu") (net 1))
  (segment (start 94.25 60.45) (end 94.25 61.15) (width 0.25) (layer "F.Cu") (net 1))
  (segment (start 93.15 61.25) (end 93.15 60.45) (width 0.25) (layer "F.Cu") (net 1))
  (segment (start 88.55 61.25) (end 88.55 62) (width 0.25) (layer "F.Cu") (net 1))
  (segment (start 87.85 61.25) (end 87.85 62.05) (width 0.25) (layer "F.Cu") (net 1))
  (segment (start 88.55 61.25) (end 88.55 60.45) (width 0.25) (layer "F.Cu") (net 1))
  (segment (start 87.85 61.25) (end 87.85 60.4) (width 0.25) (layer "F.Cu") (net 1))
  (segment (start 88.024999 64.550001) (end 88.024999 62.275001) (width 0.25) (layer "F.Cu") (net 1))
  (segment (start 89.05 63.25) (end 88.35 62.55) (width 0.25) (layer "F.Cu") (net 1))
  (segment (start 88.675001 64.550001) (end 88.675001 63.624999) (width 0.25) (layer "F.Cu") (net 1))
  (segment (start 88.675001 63.624999) (end 89.05 63.25) (width 0.25) (layer "F.Cu") (net 1))
  (segment (start 89.05 63.25) (end 89.324999 63.524999) (width 0.25) (layer "F.Cu") (net 1))
  (segment (start 89.324999 63.524999) (end 89.324999 64.550001) (width 0.25) (layer "F.Cu") (net 1))
  (segment (start 94.45 74.85) (end 93.3 74.85) (width 0.5) (layer "F.Cu") (net 1))
  (segment (start 75.8 117.095) (end 75.8 116.2) (width 0.25) (layer "F.Cu") (net 1))
  (segment (start 76.355 125.18) (end 77.25 125.18) (width 0.25) (layer "F.Cu") (net 1))
  (segment (start 116 121.75) (end 116.4 122.15) (width 0.15) (layer "F.Cu") (net 1))
  (segment (start 91.3 96.59) (end 91.8 97.09) (width 0.15) (layer "F.Cu") (net 1))
  (segment (start 87.29 101.59) (end 86.79 101.09) (width 0.25) (layer "F.Cu") (net 1))
  (segment (start 140.6875 92.275) (end 141.55 92.275) (width 0.15) (layer "F.Cu") (net 1))
  (segment (start 141.55 92.275) (end 141.6 92.225) (width 0.15) (layer "F.Cu") (net 1))
  (segment (start 132.8125 89.775) (end 131.9 89.775) (width 0.15) (layer "F.Cu") (net 1))
  (segment (start 135.5 86.0875) (end 135.5 84.775) (width 0.15) (layer "F.Cu") (net 1))
  (segment (start 135.5 84.775) (end 135.55 84.725) (width 0.15) (layer "F.Cu") (net 1))
  (segment (start 139.5 93.9625) (end 139.5 94.775) (width 0.15) (layer "F.Cu") (net 1))
  (segment (start 145.725 86.135) (end 144.685 86.135) (width 0.2) (layer "F.Cu") (net 1))
  (segment (start 144.685 86.135) (end 144.675 86.125) (width 0.2) (layer "F.Cu") (net 1))
  (segment (start 68.077 158.00622) (end 68.077 157.00712) (width 0.15) (layer "F.Cu") (net 1))
  (segment (start 68.577 158.00622) (end 68.577 156.60712) (width 0.15) (layer "F.Cu") (net 1))
  (segment (start 90.29 95.6) (end 90.79 95.1) (width 0.15) (layer "F.Cu") (net 1))
  (segment (start 87.4 140.565) (end 87.4 139.75) (width 0.2) (layer "F.Cu") (net 1))
  (segment (start 86.3 99.6) (end 86.8 99.1) (width 0.25) (layer "F.Cu") (net 1))
  (segment (start 109.6 116.15) (end 110 115.75) (width 0.15) (layer "F.Cu") (net 1))
  (segment (start 87.3 94.6) (end 86.8 94.1) (width 0.15) (layer "F.Cu") (net 1))
  (segment (start 127.75 132.11) (end 127.77 132.13) (width 0.2) (layer "F.Cu") (net 1))
  (segment (start 118.739056 83.339056) (end 118.239056 83.839056) (width 0.25) (layer "F.Cu") (net 1))
  (segment (start 107.57533 111.72533) (end 107.60001 111.72533) (width 0.15) (layer "F.Cu") (net 1))
  (segment (start 126.235 112.615) (end 126.45 112.4) (width 0.2) (layer "F.Cu") (net 1))
  (segment (start 80.3 117.35) (end 80.7 116.95) (width 0.15) (layer "F.Cu") (net 1))
  (segment (start 109.6 132.15) (end 110 132.55) (width 0.15) (layer "F.Cu") (net 1))
  (segment (start 99.2 115.35) (end 98.8 114.95) (width 0.15) (layer "F.Cu") (net 1))
  (segment (start 73.515 62.35) (end 72.3726 62.35) (width 0.3) (layer "F.Cu") (net 1))
  (segment (start 100 115.35) (end 99.6 114.95) (width 0.15) (layer "F.Cu") (net 1))
  (segment (start 102 122.95) (end 102.4 122.55) (width 0.15) (layer "F.Cu") (net 1))
  (segment (start 102.4 128.95) (end 102 129.35) (width 0.15) (layer "F.Cu") (net 1))
  (segment (start 108.8 124.95) (end 109.2 125.35) (width 0.15) (layer "F.Cu") (net 1))
  (segment (start 100.8 125.75) (end 100.4 126.15) (width 0.15) (layer "F.Cu") (net 1))
  (segment (start 100 119.35) (end 99.6 118.95) (width 0.15) (layer "F.Cu") (net 1))
  (segment (start 64.12 166.995) (end 65.595 166.995) (width 0.25) (layer "F.Cu") (net 1))
  (segment (start 75.81 118.31) (end 76.25 118.75) (width 0.25) (layer "F.Cu") (net 1))
  (segment (start 106.4 117.75) (end 106.8 117.35) (width 0.15) (layer "F.Cu") (net 1))
  (segment (start 112.223 94.73) (end 112.223 93.72) (width 0.2) (layer "F.Cu") (net 1))
  (segment (start 103.2 119.35) (end 102.8 118.95) (width 0.15) (layer "F.Cu") (net 1))
  (segment (start 92.09 177.345) (end 92.09 175.635) (width 0.3) (layer "F.Cu") (net 1))
  (segment (start 70.42 120.770002) (end 70.42 121.555) (width 0.25) (layer "F.Cu") (net 1))
  (segment (start 71.84 166.06) (end 72.94 166.06) (width 0.2) (layer "F.Cu") (net 1))
  (segment (start 109.6 131.35) (end 110 131.75) (width 0.15) (layer "F.Cu") (net 1))
  (segment (start 107.2 118.55) (end 106.8 118.15) (width 0.15) (layer "F.Cu") (net 1))
  (segment (start 135.7 154.415) (end 135.7 153.65) (width 0.25) (layer "F.Cu") (net 1))
  (segment (start 99.65 128.5) (end 100 128.15) (width 0.15) (layer "F.Cu") (net 1))
  (segment (start 116 126.55) (end 115.6 126.95) (width 0.15) (layer "F.Cu") (net 1))
  (segment (start 126.735 112.815) (end 127.15 112.4) (width 0.2) (layer "F.Cu") (net 1))
  (segment (start 76.3 136.1) (end 76.3 136.85) (width 0.3) (layer "F.Cu") (net 1))
  (segment (start 86.3 98.6) (end 86.8 98.1) (width 0.25) (layer "F.Cu") (net 1))
  (segment (start 104 128.95) (end 103.6 129.35) (width 0.15) (layer "F.Cu") (net 1))
  (segment (start 86.7 124.55) (end 87 124.55) (width 0.15) (layer "F.Cu") (net 1))
  (segment (start 87.4 142.565) (end 86.665 142.565) (width 0.15) (layer "F.Cu") (net 1))
  (segment (start 65.645 160.285) (end 65.65 160.29) (width 0.25) (layer "F.Cu") (net 1))
  (segment (start 92.09 175.635) (end 92.4 175.325) (width 0.3) (layer "F.Cu") (net 1))
  (segment (start 119.2 164.1) (end 119.2 165.95) (width 0.2) (layer "F.Cu") (net 1))
  (segment (start 108.8 116.95) (end 109.2 117.35) (width 0.15) (layer "F.Cu") (net 1))
  (segment (start 133.985 177.37) (end 133.985 175.725) (width 0.2) (layer "F.Cu") (net 1))
  (segment (start 126.59 132.13) (end 127.77 132.13) (width 0.2) (layer "F.Cu") (net 1))
  (segment (start 100 132.15) (end 100.4 132.55) (width 0.15) (layer "F.Cu") (net 1))
  (segment (start 79.050857 76.199143) (end 77.650857 76.199143) (width 0.3) (layer "F.Cu") (net 1))
  (segment (start 97.6 129.75) (end 97.2 130.15) (width 0.15) (layer "F.Cu") (net 1))
  (segment (start 73.82 119.4325) (end 73.82 118.52) (width 0.2) (layer "F.Cu") (net 1))
  (segment (start 142.25 152.7) (end 142.19 152.76) (width 0.2) (layer "F.Cu") (net 1))
  (segment (start 104.8 120.95) (end 105.2 121.35) (width 0.15) (layer "F.Cu") (net 1))
  (segment (start 104.8 124.95) (end 105.2 125.35) (width 0.15) (layer "F.Cu") (net 1))
  (segment (start 79.325 62.4) (end 78.8 61.875) (width 0.25) (layer "F.Cu") (net 1))
  (segment (start 99.2 116.15) (end 98.8 115.75) (width 0.15) (layer "F.Cu") (net 1))
  (segment (start 90.55 142.55) (end 87.45 142.55) (width 0.2) (layer "F.Cu") (net 1))
  (segment (start 139.9 164.1) (end 139.9 165.75) (width 0.2) (layer "F.Cu") (net 1))
  (segment (start 112 129.75) (end 112.7 129.75) (width 0.15) (layer "F.Cu") (net 1))
  (segment (start 80.285 125.355) (end 79.885 125.755) (width 0.15) (layer "F.Cu") (net 1))
  (segment (start 71.4 120.085) (end 71.4 120.79) (width 0.15) (layer "F.Cu") (net 1))
  (segment (start 108.8 120.15) (end 109.2 119.75) (width 0.15) (layer "F.Cu") (net 1))
  (segment (start 120.8 163.42001) (end 120.77999 163.4) (width 0.2) (layer "F.Cu") (net 1))
  (segment (start 116 123.35) (end 115.6 122.95) (width 0.15) (layer "F.Cu") (net 1))
  (segment (start 108.8 119.35) (end 108.4 118.95) (width 0.15) (layer "F.Cu") (net 1))
  (segment (start 101.6 118.55) (end 102 118.15) (width 0.15) (layer "F.Cu") (net 1))
  (segment (start 119.225 74.2) (end 119.25 74.225) (width 0.2) (layer "F.Cu") (net 1))
  (segment (start 113.6 121.75) (end 114 122.15) (width 0.15) (layer "F.Cu") (net 1))
  (segment (start 101.6 117.75) (end 101.2 117.35) (width 0.15) (layer "F.Cu") (net 1))
  (segment (start 106.4 118.55) (end 106.8 118.15) (width 0.15) (layer "F.Cu") (net 1))
  (segment (start 76.32 125.155) (end 76.32 126.05) (width 0.25) (layer "F.Cu") (net 1))
  (segment (start 139.645 146.33) (end 139.645 148.315) (width 0.2) (layer "F.Cu") (net 1))
  (segment (start 109.6 130.55) (end 110 130.95) (width 0.15) (layer "F.Cu") (net 1))
  (segment (start 74.32 122.3075) (end 74.32 123.22) (width 0.15) (layer "F.Cu") (net 1))
  (segment (start 78.98 79.07) (end 78.98 78.33) (width 0.2) (layer "F.Cu") (net 1))
  (segment (start 100.8 124.95) (end 100.4 125.35) (width 0.15) (layer "F.Cu") (net 1))
  (segment (start 107.2 122.55) (end 107.6 122.95) (width 0.15) (layer "F.Cu") (net 1))
  (segment (start 96.8 129.75) (end 96.4 130.15) (width 0.15) (layer "F.Cu") (net 1))
  (segment (start 102.45 99.2) (end 102.25 99) (width 0.2) (layer "F.Cu") (net 1))
  (segment (start 109.29 175.435) (end 109.3 175.425) (width 0.3) (layer "F.Cu") (net 1))
  (segment (start 100 130.55) (end 99.6 130.95) (width 0.15) (layer "F.Cu") (net 1))
  (segment (start 107.2 119.35) (end 107.6 118.95) (width 0.15) (layer "F.Cu") (net 1))
  (segment (start 92.8 126.55) (end 92.4 126.95) (width 0.15) (layer "F.Cu") (net 1))
  (segment (start 113.6 126.55) (end 114 126.95) (width 0.15) (layer "F.Cu") (net 1))
  (segment (start 100 121.75) (end 99.6 122.15) (width 0.15) (layer "F.Cu") (net 1))
  (segment (start 114.45 116.9) (end 114.55 116.9) (width 0.15) (layer "F.Cu") (net 1))
  (segment (start 111.2 129.75) (end 111.6 129.35) (width 0.15) (layer "F.Cu") (net 1))
  (segment (start 64.12 168.23) (end 64.14 168.25) (width 0.25) (layer "F.Cu") (net 1))
  (segment (start 107.2 123.35) (end 107.6 123.75) (width 0.15) (layer "F.Cu") (net 1))
  (segment (start 124.925 65.65) (end 124.925 64.375) (width 0.25) (layer "F.Cu") (net 1))
  (segment (start 87 124.55) (end 87.4 124.15) (width 0.15) (layer "F.Cu") (net 1))
  (segment (start 100 117.75) (end 99.6 117.35) (width 0.15) (layer "F.Cu") (net 1))
  (segment (start 94.45 73.45) (end 93.3 73.45) (width 0.5) (layer "F.Cu") (net 1))
  (segment (start 85.1 128.55) (end 84.5 128.55) (width 0.2) (layer "F.Cu") (net 1))
  (segment (start 90.65 143.165) (end 90.65 142.65) (width 0.2) (layer "F.Cu") (net 1))
  (segment (start 104.8 121.75) (end 105.2 122.15) (width 0.15) (layer "F.Cu") (net 1))
  (segment (start 76.29 177.345) (end 76.29 175.61) (width 0.3) (layer "F.Cu") (net 1))
  (segment (start 64.6001 144.915) (end 64.6001 145.7499) (width 0.3) (layer "F.Cu") (net 1))
  (segment (start 138.03 76.975) (end 138.025 76.98) (width 0.15) (layer "F.Cu") (net 1))
  (segment (start 96.29 177.345) (end 96.29 173.999994) (width 0.3) (layer "F.Cu") (net 1))
  (segment (start 114.4 132.15) (end 114.8 132.55) (width 0.15) (layer "F.Cu") (net 1))
  (segment (start 86.3 101.6) (end 86.8 101.1) (width 0.25) (layer "F.Cu") (net 1))
  (segment (start 104.8 128.95) (end 104.4 129.35) (width 0.15) (layer "F.Cu") (net 1))
  (segment (start 75.81 118.065) (end 75.81 118.31) (width 0.25) (layer "F.Cu") (net 1))
  (segment (start 108.8 120.95) (end 109.2 121.35) (width 0.15) (layer "F.Cu") (net 1))
  (segment (start 106.4 121.75) (end 106.8 122.15) (width 0.15) (layer "F.Cu") (net 1))
  (segment (start 131.49 116.05) (end 131.49 115.23) (width 0.2) (layer "F.Cu") (net 1))
  (segment (start 103.2 120.95) (end 102.8 121.35) (width 0.15) (layer "F.Cu") (net 1))
  (segment (start 74.94001 73.14) (end 74.99 73.14) (width 0.2) (layer "F.Cu") (net 1))
  (segment (start 122.45 61.65) (end 121.25 61.65) (width 0.15) (layer "F.Cu") (net 1))
  (segment (start 100 120.95) (end 99.6 121.35) (width 0.15) (layer "F.Cu") (net 1))
  (segment (start 130.385 177.37) (end 130.385 175.76) (width 0.2) (layer "F.Cu") (net 1))
  (segment (start 107.2 120.95) (end 107.6 121.35) (width 0.15) (layer "F.Cu") (net 1))
  (segment (start 113.6 108.95) (end 114 109.35) (width 0.15) (layer "F.Cu") (net 1))
  (segment (start 110.2 98.75) (end 111.025 98.75) (width 0.2) (layer "F.Cu") (net 1))
  (segment (start 127.77 132.13) (end 128.24 132.6) (width 0.2) (layer "F.Cu") (net 1))
  (segment (start 100.8 128.15) (end 101.2 128.55) (width 0.15) (layer "F.Cu") (net 1))
  (segment (start 112.29 177.345) (end 112.29 175.61) (width 0.3) (layer "F.Cu") (net 1))
  (segment (start 138.03 75.91) (end 138.03 76.975) (width 0.15) (layer "F.Cu") (net 1))
  (segment (start 102.25 99) (end 102 99) (width 0.2) (layer "F.Cu") (net 1))
  (segment (start 132.185 175.74) (end 132.2 175.725) (width 0.2) (layer "F.Cu") (net 1))
  (segment (start 100 122.55) (end 99.6 122.95) (width 0.15) (layer "F.Cu") (net 1))
  (segment (start 101.6 120.15) (end 102 119.75) (width 0.15) (layer "F.Cu") (net 1))
  (segment (start 102.4 117.75) (end 102 117.35) (width 0.15) (layer "F.Cu") (net 1))
  (segment (start 146.355 148.235) (end 146.32 148.27) (width 0.2) (layer "F.Cu") (net 1))
  (segment (start 81.085 126.155) (end 80.685 126.555) (width 0.15) (layer "F.Cu") (net 1))
  (segment (start 78.09 175.64) (end 78.09 177.345) (width 0.3) (layer "F.Cu") (net 1))
  (segment (start 96.8 130.55) (end 96.4 130.95) (width 0.15) (layer "F.Cu") (net 1))
  (segment (start 120.3 164.875) (end 120.3 162.9) (width 0.2) (layer "F.Cu") (net 1))
  (segment (start 104.8 120.15) (end 105.2 119.75) (width 0.15) (layer "F.Cu") (net 1))
  (segment (start 98.4 132.15) (end 98 132.55) (width 0.15) (layer "F.Cu") (net 1))
  (segment (start 108 125.75) (end 108.4 126.15) (width 0.15) (layer "F.Cu") (net 1))
  (segment (start 121.3 163.92001) (end 120.77999 163.4) (width 0.2) (layer "F.Cu") (net 1))
  (segment (start 107.2 131.35) (end 106.8 131.75) (width 0.15) (layer "F.Cu") (net 1))
  (segment (start 72.42 125.155) (end 72.42 126.05) (width 0.25) (layer "F.Cu") (net 1))
  (segment (start 104 124.95) (end 103.6 125.35) (width 0.15) (layer "F.Cu") (net 1))
  (segment (start 131.1 64.2) (end 131.250002 64.2) (width 0.15) (layer "F.Cu") (net 1))
  (segment (start 104.8 128.15) (end 104.4 128.55) (width 0.15) (layer "F.Cu") (net 1))
  (segment (start 127.45 61.65) (end 127.45 60.25) (width 0.15) (layer "F.Cu") (net 1))
  (segment (start 142.25 151.52) (end 142.25 152.7) (width 0.2) (layer "F.Cu") (net 1))
  (segment (start 100.8 116.15) (end 100.4 115.75) (width 0.15) (layer "F.Cu") (net 1))
  (segment (start 103.2 108.95) (end 102.8 108.55) (width 0.15) (layer "F.Cu") (net 1))
  (segment (start 124.795 166.345) (end 124.95 166.5) (width 0.2) (layer "F.Cu") (net 1))
  (segment (start 81.89 63.195) (end 81.89 62.495) (width 0.25) (layer "F.Cu") (net 1))
  (segment (start 107.2 116.15) (end 107.6 115.75) (width 0.15) (layer "F.Cu") (net 1))
  (segment (start 113.6 119.35) (end 113.2 119.75) (width 0.15) (layer "F.Cu") (net 1))
  (segment (start 101.2 109.35) (end 101.14999 109.35) (width 0.15) (layer "F.Cu") (net 1))
  (segment (start 103.2 111.35) (end 102.8 111.75) (width 0.15) (layer "F.Cu") (net 1))
  (segment (start 105.6 120.95) (end 106 121.35) (width 0.15) (layer "F.Cu") (net 1))
  (segment (start 118.239056 84.318104) (end 118.239056 83.839056) (width 0.25) (layer "F.Cu") (net 1))
  (segment (start 138.295 166.105) (end 138.2 166.2) (width 0.2) (layer "F.Cu") (net 1))
  (segment (start 100 128.95) (end 99.608716 129.341284) (width 0.15) (layer "F.Cu") (net 1))
  (segment (start 74.32 123.22) (end 74.35 123.25) (width 0.15) (layer "F.Cu") (net 1))
  (segment (start 130.52 119.66) (end 129.33 119.66) (width 0.2) (layer "F.Cu") (net 1))
  (segment (start 96.8 132.95) (end 96.4 133.35) (width 0.15) (layer "F.Cu") (net 1))
  (segment (start 92.8 129.75) (end 92.4 130.15) (width 0.15) (layer "F.Cu") (net 1))
  (segment (start 113.6 111.35) (end 114 111.75) (width 0.15) (layer "F.Cu") (net 1))
  (segment (start 104 118.55) (end 103.6 118.15) (width 0.15) (layer "F.Cu") (net 1))
  (segment (start 121.05 154.315) (end 121.05 153.61) (width 0.15) (layer "F.Cu") (net 1))
  (segment (start 104 123.35) (end 103.6 123.75) (width 0.15) (layer "F.Cu") (net 1))
  (segment (start 72.25 95.125) (end 72.23465 95.10965) (width 0.2) (layer "F.Cu") (net 1))
  (segment (start 106.4 119.35) (end 106.8 118.95) (width 0.15) (layer "F.Cu") (net 1))
  (segment (start 130.05 61.65) (end 131.275004 61.65) (width 0.15) (layer "F.Cu") (net 1))
  (segment (start 101.6 111.35) (end 101.2 110.95) (width 0.15) (layer "F.Cu") (net 1))
  (segment (start 97.6 132.15) (end 97.2 132.55) (width 0.15) (layer "F.Cu") (net 1))
  (segment (start 102.4 132.15) (end 102 132.55) (width 0.15) (layer "F.Cu") (net 1))
  (segment (start 104.8 122.55) (end 105.2 122.95) (width 0.15) (layer "F.Cu") (net 1))
  (segment (start 96.8 131.35) (end 96.4 131.75) (width 0.15) (layer "F.Cu") (net 1))
  (segment (start 118.739056 82.968104) (end 118.739056 83.339056) (width 0.25) (layer "F.Cu") (net 1))
  (segment (start 103.2 118.55) (end 102.8 118.15) (width 0.15) (layer "F.Cu") (net 1))
  (segment (start 104 117.75) (end 103.6 117.35) (width 0.15) (layer "F.Cu") (net 1))
  (segment (start 101.69 175.685) (end 101.975 175.4) (width 0.3) (layer "F.Cu") (net 1))
  (segment (start 77.650857 76.199143) (end 77.65 76.2) (width 0.3) (layer "F.Cu") (net 1))
  (segment (start 138.295 164.825) (end 138.295 166.105) (width 0.2) (layer "F.Cu") (net 1))
  (segment (start 106.4 124.95) (end 106.8 125.35) (width 0.15) (layer "F.Cu") (net 1))
  (segment (start 101.6 108.95) (end 101.2 109.35) (width 0.15) (layer "F.Cu") (net 1))
  (segment (start 105.6 121.75) (end 106 122.15) (width 0.15) (layer "F.Cu") (net 1))
  (segment (start 64.12 160.285) (end 65.645 160.285) (width 0.25) (layer "F.Cu") (net 1))
  (segment (start 97.6 130.55) (end 97.2 130.95) (width 0.15) (layer "F.Cu") (net 1))
  (segment (start 108 116.15) (end 108.4 115.75) (width 0.15) (layer "F.Cu") (net 1))
  (segment (start 92.8 117.75) (end 92.4 118.15) (width 0.15) (layer "F.Cu") (net 1))
  (segment (start 100 116.15) (end 99.6 115.75) (width 0.15) (layer "F.Cu") (net 1))
  (segment (start 73.5 63.95) (end 73.5 62.4) (width 0.25) (layer "F.Cu") (net 1))
  (segment (start 80.738335 75.525) (end 80.756896 75.506439) (width 0.25) (layer "F.Cu") (net 1))
  (segment (start 119.225 70.2) (end 119.2 70.225) (width 0.2) (layer "F.Cu") (net 1))
  (segment (start 64.12 160.285) (end 64.12 159.05) (width 0.25) (layer "F.Cu") (net 1))
  (segment (start 87.5 115.8) (end 87.5 114.7) (width 0.25) (layer "F.Cu") (net 1))
  (segment (start 102.4 120.95) (end 102 121.35) (width 0.15) (layer "F.Cu") (net 1))
  (segment (start 98.4 108.95) (end 98 109.35) (width 0.15) (layer "F.Cu") (net 1))
  (segment (start 125.05 61.65) (end 125.05 60.25) (width 0.15) (layer "F.Cu") (net 1))
  (segment (start 76.24 73.155) (end 75.005 73.155) (width 0.25) (layer "F.Cu") (net 1))
  (segment (start 95.2 108.95) (end 95.6 108.55) (width 0.15) (layer "F.Cu") (net 1))
  (segment (start 103.2 120.15) (end 102.8 119.75) (width 0.15) (layer "F.Cu") (net 1))
  (segment (start 119.225 69.4) (end 119.225 70.2) (width 0.2) (layer "F.Cu") (net 1))
  (segment (start 74.55 65) (end 73.5 63.95) (width 0.25) (layer "F.Cu") (net 1))
  (segment (start 102.4 124.95) (end 102 125.35) (width 0.15) (layer "F.Cu") (net 1))
  (segment (start 101.6 120.15) (end 101.2 119.75) (width 0.15) (layer "F.Cu") (net 1))
  (segment (start 101.6 119.35) (end 101.2 118.95) (width 0.15) (layer "F.Cu") (net 1))
  (segment (start 129.35 64.2) (end 131.1 64.2) (width 0.15) (layer "F.Cu") (net 1))
  (segment (start 104.8 117.75) (end 105.2 117.35) (width 0.15) (layer "F.Cu") (net 1))
  (segment (start 139.9 165.75) (end 140.35 166.2) (width 0.2) (layer "F.Cu") (net 1))
  (segment (start 121.3 164.875) (end 121.3 163.92001) (width 0.2) (layer "F.Cu") (net 1))
  (segment (start 108.8 124.15) (end 109.2 124.55) (width 0.15) (layer "F.Cu") (net 1))
  (segment (start 101.6 124.95) (end 101.2 125.35) (width 0.15) (layer "F.Cu") (net 1))
  (segment (start 90.3 100.6) (end 89.8 100.1) (width 0.15) (layer "F.Cu") (net 1))
  (segment (start 126.735 113.365) (end 126.735 112.815) (width 0.2) (layer "F.Cu") (net 1))
  (segment (start 126.235 113.365) (end 126.235 112.615) (width 0.2) (layer "F.Cu") (net 1))
  (segment (start 101.6 118.55) (end 101.2 118.15) (width 0.15) (layer "F.Cu") (net 1))
  (segment (start 119.2 165.95) (end 118.9 166.25) (width 0.2) (layer "F.Cu") (net 1))
  (segment (start 100 123.35) (end 99.6 123.75) (width 0.15) (layer "F.Cu") (net 1))
  (segment (start 112 130.55) (end 112.7 130.55) (width 0.15) (layer "F.Cu") (net 1))
  (segment (start 108.8 123.35) (end 109.2 123.75) (width 0.15) (layer "F.Cu") (net 1))
  (segment (start 123.15 64.2) (end 121.275 64.2) (width 0.15) (layer "F.Cu") (net 1))
  (segment (start 100.8 132.15) (end 100.4 132.55) (width 0.15) (layer "F.Cu") (net 1))
  (segment (start 71.4 120.79) (end 71.43 120.82) (width 0.15) (layer "F.Cu") (net 1))
  (segment (start 107.2 128.95) (end 106.8 129.35) (width 0.15) (layer "F.Cu") (net 1))
  (segment (start 109.29 177.345) (end 109.29 175.435) (width 0.3) (layer "F.Cu") (net 1))
  (segment (start 105.6 122.55) (end 106 122.95) (width 0.15) (layer "F.Cu") (net 1))
  (segment (start 77.8 175.35) (end 78.09 175.64) (width 0.3) (layer "F.Cu") (net 1))
  (segment (start 73.375 95.125) (end 72.25 95.125) (width 0.2) (layer "F.Cu") (net 1))
  (segment (start 101 96.45) (end 103.2 96.45) (width 0.2) (layer "F.Cu") (net 1))
  (segment (start 110.4 132.15) (end 110 132.55) (width 0.15) (layer "F.Cu") (net 1))
  (segment (start 79.89 177.345) (end 79.89 175.66) (width 0.3) (layer "F.Cu") (net 1))
  (segment (start 105.6 120.15) (end 106 119.75) (width 0.15) (layer "F.Cu") (net 1))
  (segment (start 73.82 118.52) (end 73.8 118.5) (width 0.2) (layer "F.Cu") (net 1))
  (segment (start 100 120.15) (end 99.6 119.75) (width 0.15) (layer "F.Cu") (net 1))
  (segment (start 105.6 123.35) (end 106 123.75) (width 0.15) (layer "F.Cu") (net 1))
  (segment (start 103.2 128.95) (end 103.6 129.35) (width 0.15) (layer "F.Cu") (net 1))
  (segment (start 79.050857 75.525) (end 80.738335 75.525) (width 0.25) (layer "F.Cu") (net 1))
  (segment (start 71.43 121.555) (end 71.43 120.82) (width 0.25) (layer "F.Cu") (net 1))
  (segment (start 79.89 175.66) (end 80.175 175.375) (width 0.3) (layer "F.Cu") (net 1))
  (segment (start 146.355 146.33) (end 146.355 148.235) (width 0.2) (layer "F.Cu") (net 1))
  (segment (start 99.608716 129.341284) (end 99.608716 129.34929) (width 0.15) (layer "F.Cu") (net 1))
  (segment (start 106.4 123.35) (end 106.8 123.75) (width 0.15) (layer "F.Cu") (net 1))
  (segment (start 102.4 131.35) (end 102 131.75) (width 0.15) (layer "F.Cu") (net 1))
  (segment (start 111.25 98.525) (end 111.25 98.11) (width 0.2) (layer "F.Cu") (net 1))
  (segment (start 121.05 153.61) (end 120.87 153.43) (width 0.15) (layer "F.Cu") (net 1))
  (segment (start 100 116.95) (end 99.6 116.55) (width 0.15) (layer "F.Cu") (net 1))
  (segment (start 108.8 122.55) (end 109.2 122.95) (width 0.15) (layer "F.Cu") (net 1))
  (segment (start 65.595 166.995) (end 65.63 167.03) (width 0.25) (layer "F.Cu") (net 1))
  (segment (start 104 122.55) (end 103.6 122.95) (width 0.15) (layer "F.Cu") (net 1))
  (segment (start 99.65 128.545) (end 99.65 128.5) (width 0.15) (layer "F.Cu") (net 1))
  (segment (start 105.6 132.15) (end 106 132.55) (width 0.15) (layer "F.Cu") (net 1))
  (segment (start 100 124.15) (end 99.6 124.55) (width 0.15) (layer "F.Cu") (net 1))
  (segment (start 105.6 116.15) (end 106 115.75) (width 0.15) (layer "F.Cu") (net 1))
  (segment (start 76.29 175.61) (end 76.3 175.6) (width 0.3) (layer "F.Cu") (net 1))
  (segment (start 102.4 119.35) (end 102 118.95) (width 0.15) (layer "F.Cu") (net 1))
  (segment (start 104.8 116.15) (end 105.2 115.75) (width 0.15) (layer "F.Cu") (net 1))
  (segment (start 106.4 128.15) (end 106 128.55) (width 0.15) (layer "F.Cu") (net 1))
  (segment (start 138.795 164.825) (end 138.795 165.945) (width 0.2) (layer "F.Cu") (net 1))
  (segment (start 123.15 73.4) (end 123.15 74.2) (width 0.2) (layer "F.Cu") (net 1))
  (segment (start 90.65 142.65) (end 90.55 142.55) (width 0.2) (layer "F.Cu") (net 1))
  (segment (start 80.285 124.555) (end 79.885 124.955) (width 0.15) (layer "F.Cu") (net 1))
  (segment (start 106.4 120.95) (end 106.8 121.35) (width 0.15) (layer "F.Cu") (net 1))
  (segment (start 116 111.35) (end 116.4 111.75) (width 0.15) (layer "F.Cu") (net 1))
  (segment (start 104 120.95) (end 103.6 121.35) (width 0.15) (layer "F.Cu") (net 1))
  (segment (start 131.06 114.8) (end 129.9 114.8) (width 0.2) (layer "F.Cu") (net 1))
  (segment (start 93.875001 70.450002) (end 93.875001 72.624999) (width 0.5) (layer "F.Cu") (net 1))
  (segment (start 102.4 120.15) (end 102 119.75) (width 0.15) (layer "F.Cu") (net 1))
  (segment (start 120.8 164.75) (end 120.8 163.42001) (width 0.2) (layer "F.Cu") (net 1))
  (segment (start 112.7 130.55) (end 113.1 130.15) (width 0.15) (layer "F.Cu") (net 1))
  (segment (start 94.235 76.85) (end 94.235 76.135) (width 0.3) (layer "F.Cu") (net 1))
  (segment (start 130.385 175.76) (end 130.375 175.75) (width 0.2) (layer "F.Cu") (net 1))
  (segment (start 111.025 98.75) (end 111.25 98.525) (width 0.2) (layer "F.Cu") (net 1))
  (segment (start 86.1 113.585) (end 85.085 113.585) (width 0.25) (layer "F.Cu") (net 1))
  (segment (start 138.025 75.905) (end 138.025 74.65) (width 0.15) (layer "F.Cu") (net 1))
  (segment (start 112.7 129.75) (end 113.1 130.15) (width 0.15) (layer "F.Cu") (net 1))
  (segment (start 85.085 113.585) (end 85 113.5) (width 0.25) (layer "F.Cu") (net 1))
  (segment (start 81.085 126.955) (end 80.685 127.355) (width 0.15) (layer "F.Cu") (net 1))
  (segment (start 70.420001 120.770001) (end 70.42 120.770002) (width 0.25) (layer "F.Cu") (net 1))
  (segment (start 111.6 132.55) (end 112 132.95) (width 0.15) (layer "F.Cu") (net 1))
  (segment (start 75.005 73.155) (end 74.99 73.14) (width 0.25) (layer "F.Cu") (net 1))
  (segment (start 107.2 117.75) (end 107.6 117.35) (width 0.15) (layer "F.Cu") (net 1))
  (segment (start 138.795 165.945) (end 139.05 166.2) (width 0.2) (layer "F.Cu") (net 1))
  (segment (start 81.085 124.555) (end 80.685 124.955) (width 0.15) (layer "F.Cu") (net 1))
  (segment (start 79.85 62.4) (end 79.325 62.4) (width 0.25) (layer "F.Cu") (net 1))
  (segment (start 112.29 175.61) (end 112.575 175.325) (width 0.3) (layer "F.Cu") (net 1))
  (segment (start 81.1 122.95) (end 80.7 122.55) (width 0.15) (layer "F.Cu") (net 1))
  (segment (start 104 119.35) (end 103.6 118.95) (width 0.15) (layer "F.Cu") (net 1))
  (segment (start 103.2 124.95) (end 102.8 125.35) (width 0.15) (layer "F.Cu") (net 1))
  (segment (start 86.3 95.6) (end 86.8 95.1) (width 0.25) (layer "F.Cu") (net 1))
  (segment (start 119.225 73.425) (end 119.225 74.2) (width 0.2) (layer "F.Cu") (net 1))
  (segment (start 107.2 132.15) (end 106.8 132.55) (width 0.15) (layer "F.Cu") (net 1))
  (segment (start 100 118.55) (end 99.6 118.15) (width 0.15) (layer "F.Cu") (net 1))
  (segment (start 127.75 131.275) (end 127.75 132.11) (width 0.2) (layer "F.Cu") (net 1))
  (segment (start 101.6 121.75) (end 101.2 122.15) (width 0.15) (layer "F.Cu") (net 1))
  (segment (start 132.185 177.37) (end 132.185 175.74) (width 0.2) (layer "F.Cu") (net 1))
  (segment (start 95.2 121.75) (end 95.6 122.15) (width 0.15) (layer "F.Cu") (net 1))
  (segment (start 92.497995 132.419441) (end 92.297996 132.61944) (width 0.15) (layer "F.Cu") (net 1))
  (segment (start 76.25 145) (end 76.25 145.7) (width 0.3) (layer "F.Cu") (net 1))
  (segment (start 124.795 164.825) (end 124.795 166.345) (width 0.2) (layer "F.Cu") (net 1))
  (segment (start 103.2 123.35) (end 102.8 123.75) (width 0.15) (layer "F.Cu") (net 1))
  (segment (start 64.6001 145.7499) (end 64.6 145.75) (width 0.3) (layer "F.Cu") (net 1))
  (segment (start 108.8 115.35) (end 109.2 114.95) (width 0.15) (layer "F.Cu") (net 1))
  (segment (start 102.4 123.35) (end 102 123.75) (width 0.15) (layer "F.Cu") (net 1))
  (segment (start 86.665 142.565) (end 86.65 142.55) (width 0.15) (layer "F.Cu") (net 1))
  (segment (start 106.4 122.55) (end 106.8 122.95) (width 0.15) (layer "F.Cu") (net 1))
  (segment (start 64.12 166.995) (end 64.12 168.23) (width 0.25) (layer "F.Cu") (net 1))
  (segment (start 110.4 111.35) (end 110.8 111.75) (width 0.15) (layer "F.Cu") (net 1))
  (segment (start 97.6 131.35) (end 97.2 131.75) (width 0.15) (layer "F.Cu") (net 1))
  (segment (start 76.8 65) (end 74.55 65) (width 0.25) (layer "F.Cu") (net 1))
  (segment (start 128.24 132.6) (end 128.24 133.255) (width 0.2) (layer "F.Cu") (net 1))
  (segment (start 96.29 173.999994) (end 96.3 173.989994) (width 0.3) (layer "F.Cu") (net 1))
  (segment (start 64.6001 136.8999) (end 64.6 136.9) (width 0.3) (layer "F.Cu") (net 1))
  (segment (start 73.41 125.155) (end 73.41 126.05) (width 0.25) (layer "F.Cu") (net 1))
  (segment (start 108.8 121.75) (end 109.2 122.15) (width 0.15) (layer "F.Cu") (net 1))
  (segment (start 86.3 100.6) (end 86.8 100.1) (width 0.25) (layer "F.Cu") (net 1))
  (segment (start 134.7 154.415) (end 134.7 153.65) (width 0.25) (layer "F.Cu") (net 1))
  (segment (start 108.8 116.15) (end 109.2 115.75) (width 0.15) (layer "F.Cu") (net 1))
  (segment (start 95.2 129.75) (end 95.6 130.15) (width 0.15) (layer "F.Cu") (net 1))
  (segment (start 106.8 119.75) (end 106.4 120.15) (width 0.15) (layer "F.Cu") (net 1))
  (segment (start 86.3 96.6) (end 86.8 96.1) (width 0.25) (layer "F.Cu") (net 1))
  (segment (start 108 124.95) (end 108.4 125.35) (width 0.15) (layer "F.Cu") (net 1))
  (segment (start 104 120.15) (end 103.6 119.75) (width 0.15) (layer "F.Cu") (net 1))
  (segment (start 135.785 177.37) (end 135.785 175.725) (width 0.2) (layer "F.Cu") (net 1))
  (segment (start 108 132.15) (end 108.4 132.55) (width 0.15) (layer "F.Cu") (net 1))
  (segment (start 101.69 177.345) (end 101.69 175.685) (width 0.3) (layer "F.Cu") (net 1))
  (segment (start 103.2 121.75) (end 102.8 122.15) (width 0.15) (layer "F.Cu") (net 1))
  (segment (start 131.49 115.23) (end 131.06 114.8) (width 0.2) (layer "F.Cu") (net 1))
  (segment (start 105.6 118.55) (end 106 118.15) (width 0.15) (layer "F.Cu") (net 1))
  (segment (start 102.4 129.75) (end 102 130.15) (width 0.15) (layer "F.Cu") (net 1))
  (segment (start 107.2 121.75) (end 107.6 122.15) (width 0.15) (layer "F.Cu") (net 1))
  (segment (start 100.7 96.15) (end 101 96.45) (width 0.2) (layer "F.Cu") (net 1))
  (segment (start 103.2 128.15) (end 102.8 128.55) (width 0.15) (layer "F.Cu") (net 1))
  (segment (start 109.6 115.35) (end 110 114.95) (width 0.15) (layer "F.Cu") (net 1))
  (segment (start 113.6 117.75) (end 114.45 116.9) (width 0.15) (layer "F.Cu") (net 1))
  (segment (start 98.4 111.35) (end 98.8 110.95) (width 0.15) (layer "F.Cu") (net 1))
  (segment (start 107.2 111.35) (end 107.57533 111.72533) (width 0.15) (layer "F.Cu") (net 1))
  (segment (start 104.8 131.35) (end 105.2 131.75) (width 0.15) (layer "F.Cu") (net 1))
  (segment (start 80.285 128.555) (end 79.885 128.955) (width 0.15) (layer "F.Cu") (net 1))
  (segment (start 105.6 119.35) (end 106 118.95) (width 0.15) (layer "F.Cu") (net 1))
  (segment (start 114.4 129.75) (end 114.799471 129.350529) (width 0.15) (layer "F.Cu") (net 1))
  (segment (start 74.43 125.155) (end 74.43 126.05) (width 0.25) (layer "F.Cu") (net 1))
  (segment (start 96.8 132.15) (end 96.4 132.55) (width 0.15) (layer "F.Cu") (net 1))
  (segment (start 86.3 97.6) (end 86.8 97.1) (width 0.25) (layer "F.Cu") (net 1))
  (segment (start 107.2 129.75) (end 106.8 130.15) (width 0.15) (layer "F.Cu") (net 1))
  (segment (start 102.45 99.877149) (end 102.45 99.2) (width 0.2) (layer "F.Cu") (net 1))
  (segment (start 110.4 129.75) (end 110 130.15) (width 0.15) (layer "F.Cu") (net 1))
  (segment (start 93.875001 72.624999) (end 93.3 73.2) (width 0.5) (layer "F.Cu") (net 1))
  (segment (start 104 128.15) (end 103.6 128.55) (width 0.15) (layer "F.Cu") (net 1))
  (segment (start 110.2 93.7) (end 109.5 93.7) (width 0.2) (layer "F.Cu") (net 1))
  (segment (start 92.782436 132.135) (end 92.497995 132.419441) (width 0.15) (layer "F.Cu") (net 1))
  (segment (start 76.8 65) (end 77.8 65) (width 0.25) (layer "F.Cu") (net 1))
  (segment (start 127.75 131.275) (end 127.75 130.575) (width 0.15) (layer "F.Cu") (net 1))
  (segment (start 107.2 124.95) (end 107.6 125.35) (width 0.15) (layer "F.Cu") (net 1))
  (segment (start 107.2 120.15) (end 106.8 119.75) (width 0.15) (layer "F.Cu") (net 1))
  (segment (start 94.235 76.135) (end 93.4 75.3) (width 0.3) (layer "F.Cu") (net 1))
  (segment (start 100 129.75) (end 99.6 130.15) (width 0.15) (layer "F.Cu") (net 1))
  (segment (start 86.7 126.15) (end 87.1 126.55) (width 0.15) (layer "F.Cu") (net 1))
  (segment (start 101.6 120.95) (end 101.2 121.35) (width 0.15) (layer "F.Cu") (net 1))
  (segment (start 74.352 125.155) (end 76.355 125.155) (width 0.3) (layer "F.Cu") (net 1))
  (segment (start 102.4 116.15) (end 102 115.75) (width 0.15) (layer "F.Cu") (net 1))
  (segment (start 110.4 108.95) (end 110.8 109.35) (width 0.15) (layer "F.Cu") (net 1))
  (segment (start 105.6 124.95) (end 106 125.35) (width 0.15) (layer "F.Cu") (net 1))
  (segment (start 129.33 119.66) (end 129.11 119.44) (width 0.2) (layer "F.Cu") (net 1))
  (segment (start 128.585 177.37) (end 128.585 175.775) (width 0.2) (layer "F.Cu") (net 1))
  (segment (start 104.8 119.35) (end 105.2 118.95) (width 0.15) (layer "F.Cu") (net 1))
  (segment (start 103.2 132.15) (end 102.8 132.55) (width 0.15) (layer "F.Cu") (net 1))
  (segment (start 104.8 118.55) (end 105.2 118.15) (width 0.15) (layer "F.Cu") (net 1))
  (segment (start 104.8 132.15) (end 105.2 132.55) (width 0.15) (layer "F.Cu") (net 1))
  (segment (start 64.6001 136.015) (end 64.6001 136.8999) (width 0.3) (layer "F.Cu") (net 1))
  (segment (start 108.8 117.75) (end 109.2 117.35) (width 0.15) (layer "F.Cu") (net 1))
  (segment (start 95.2 111.35) (end 95.6 110.95) (width 0.15) (layer "F.Cu") (net 1))
  (segment (start 101.6 122.55) (end 101.2 122.95) (width 0.15) (layer "F.Cu") (net 1))
  (via (at 95.6 119.75) (size 0.5) (drill 0.2) (layers "F.Cu" "B.Cu") (net 1))
  (via blind (at 93.2 118.95) (size 0.5) (drill 0.2) (layers "F.Cu" "In1.Cu") (net 1))
  (via (at 94.8 126.15) (size 0.5) (drill 0.2) (layers "F.Cu" "B.Cu") (net 1))
  (via (at 93.2 122.15) (size 0.5) (drill 0.2) (layers "F.Cu" "B.Cu") (net 1))
  (via blind (at 79.89 119.315) (size 0.5) (drill 0.2) (layers "F.Cu" "In2.Cu") (net 1))
  (via (at 129.285 112.4) (size 0.5) (drill 0.2) (layers "F.Cu" "B.Cu") (net 1))
  (via (at 87.1 118.55) (size 0.5) (drill 0.2) (layers "F.Cu" "B.Cu") (net 1))
  (via (at 87.1 120.95) (size 0.5) (drill 0.2) (layers "F.Cu" "B.Cu") (net 1))
  (via (at 79.885 129.755) (size 0.5) (drill 0.2) (layers "F.Cu" "B.Cu") (net 1))
  (via blind (at 123.185 175.895) (size 0.5) (drill 0.2) (layers "F.Cu" "In1.Cu") (net 1))
  (via blind (at 125.005 175.925) (size 0.5) (drill 0.2) (layers "F.Cu" "In1.Cu") (net 1))
  (via blind (at 126.785 175.895) (size 0.5) (drill 0.2) (layers "F.Cu" "In1.Cu") (net 1))
  (via (at 136.795 166.125) (size 0.5) (drill 0.2) (layers "F.Cu" "B.Cu") (net 1))
  (via (at 135.295 166.125) (size 0.5) (drill 0.2) (layers "F.Cu" "B.Cu") (net 1))
  (via (at 132.295 166.125) (size 0.5) (drill 0.2) (layers "F.Cu" "B.Cu") (net 1))
  (via (at 130.795 166.125) (size 0.5) (drill 0.2) (layers "F.Cu" "B.Cu") (net 1))
  (via (at 129.295 166.125) (size 0.5) (drill 0.2) (layers "F.Cu" "B.Cu") (net 1))
  (via (at 127.795 166.125) (size 0.5) (drill 0.2) (layers "F.Cu" "B.Cu") (net 1))
  (via (at 126.295 166.125) (size 0.5) (drill 0.2) (layers "F.Cu" "B.Cu") (net 1))
  (via (at 133.795 166.125) (size 0.5) (drill 0.2) (layers "F.Cu" "B.Cu") (net 1))
  (via (at 86.3 122.55) (size 0.5) (drill 0.2) (layers "F.Cu" "B.Cu") (net 1))
  (via (at 92.4 122.95) (size 0.5) (drill 0.2) (layers "F.Cu" "B.Cu") (net 1))
  (via (at 86.3 126.55) (size 0.5) (drill 0.2) (layers "F.Cu" "B.Cu") (net 1))
  (via (at 87.1 128.95) (size 0.5) (drill 0.2) (layers "F.Cu" "B.Cu") (net 1))
  (via (at 116.4 132.55) (size 0.5) (drill 0.2) (layers "F.Cu" "B.Cu") (net 1))
  (via (at 137.15 153.65) (size 0.5) (drill 0.2) (layers "F.Cu" "B.Cu") (net 1))
  (via (at 105.2 109.35) (size 0.5) (drill 0.2) (layers "F.Cu" "B.Cu") (net 1))
  (via (at 116.4 114.95) (size 0.5) (drill 0.2) (layers "F.Cu" "B.Cu") (net 1))
  (via (at 93.2 108.55) (size 0.5) (drill 0.2) (layers "F.Cu" "B.Cu") (net 1))
  (via (at 92.4 114.95) (size 0.5) (drill 0.2) (layers "F.Cu" "B.Cu") (net 1))
  (via (at 107.6 109.35) (size 0.5) (drill 0.2) (layers "F.Cu" "B.Cu") (net 1))
  (via (at 92.4 111.75) (size 0.5) (drill 0.2) (layers "F.Cu" "B.Cu") (net 1))
  (via (at 86.8 94.1) (size 0.5) (drill 0.2) (layers "F.Cu" "B.Cu") (net 1))
  (via (at 92.8 101.1) (size 0.5) (drill 0.2) (layers "F.Cu" "B.Cu") (net 1))
  (via (at 78.625 83.775) (size 0.5) (drill 0.2) (layers "F.Cu" "B.Cu") (net 1))
  (via (at 78.65 85.35) (size 0.5) (drill 0.2) (layers "F.Cu" "B.Cu") (net 1))
  (via (at 78.625 84.525) (size 0.5) (drill 0.2) (layers "F.Cu" "B.Cu") (net 1))
  (via (at 78.65 86.25) (size 0.5) (drill 0.2) (layers "F.Cu" "B.Cu") (net 1))
  (via (at 91.8 100.1) (size 0.5) (drill 0.2) (layers "F.Cu" "B.Cu") (net 1))
  (via (at 87.8 99.1) (size 0.5) (drill 0.2) (layers "F.Cu" "B.Cu") (net 1))
  (via (at 101.2 115.75) (size 0.5) (drill 0.2) (layers "F.Cu" "B.Cu") (net 1))
  (via (at 106.8 115.75) (size 0.5) (drill 0.2) (layers "F.Cu" "B.Cu") (net 1))
  (via (at 109.2 117.35) (size 0.5) (drill 0.2) (layers "F.Cu" "B.Cu") (net 1))
  (via (at 104.4 130.95) (size 0.5) (drill 0.2) (layers "F.Cu" "B.Cu") (net 1))
  (via (at 74.95 60.05) (size 0.6) (drill 0.3) (layers "F.Cu" "B.Cu") (net 1))
  (via (at 106 117.35) (size 0.5) (drill 0.2) (layers "F.Cu" "B.Cu") (net 1))
  (via (at 108.4 120.55) (size 0.5) (drill 0.2) (layers "F.Cu" "B.Cu") (net 1))
  (via blind (at 99.6 125.35) (size 0.5) (drill 0.2) (layers "F.Cu" "In1.Cu") (net 1))
  (via blind (at 102 122.15) (size 0.5) (drill 0.2) (layers "F.Cu" "In1.Cu") (net 1))
  (via (at 110 130.15) (size 0.5) (drill 0.2) (layers "F.Cu" "B.Cu") (net 1))
  (via (at 106.8 130.95) (size 0.5) (drill 0.2) (layers "F.Cu" "B.Cu") (net 1))
  (via (at 116.4 109.35) (size 0.5) (drill 0.2) (layers "F.Cu" "B.Cu") (net 1))
  (via (at 99.65 128.545) (size 0.5) (drill 0.2) (layers "F.Cu" "B.Cu") (net 1))
  (via (at 94.795 132.535) (size 0.5) (drill 0.2) (layers "F.Cu" "B.Cu") (net 1))
  (via (at 101.2 123.75) (size 0.5) (drill 0.2) (layers "F.Cu" "B.Cu") (net 1))
  (via (at 109.4 133.95) (size 0.5) (drill 0.2) (layers "F.Cu" "B.Cu") (net 1))
  (via (at 100.4 130.95) (size 0.5) (drill 0.2) (layers "F.Cu" "B.Cu") (net 1))
  (via (at 102 128.55) (size 0.5) (drill 0.2) (layers "F.Cu" "B.Cu") (net 1))
  (via blind (at 105.2 123.75) (size 0.5) (drill 0.2) (layers "F.Cu" "In1.Cu") (net 1))
  (via blind (at 102.8 130.15) (size 0.5) (drill 0.2) (layers "F.Cu" "In1.Cu") (net 1))
  (via blind (at 104.4 130.15) (size 0.5) (drill 0.2) (layers "F.Cu" "In1.Cu") (net 1))
  (via (at 102.8 122.95) (size 0.5) (drill 0.2) (layers "F.Cu" "B.Cu") (net 1))
  (via (at 103.6 130.15) (size 0.5) (drill 0.2) (layers "F.Cu" "B.Cu") (net 1))
  (via blind (at 103.6 122.15) (size 0.5) (drill 0.2) (layers "F.Cu" "In1.Cu") (net 1))
  (via (at 106.8 128.55) (size 0.5) (drill 0.2) (layers "F.Cu" "B.Cu") (net 1))
  (via (at 109.2 128.55) (size 0.5) (drill 0.2) (layers "F.Cu" "B.Cu") (net 1))
  (via (at 111.6 132.55) (size 0.5) (drill 0.2) (layers "F.Cu" "B.Cu") (net 1))
  (via (at 102.8 115.75) (size 0.5) (drill 0.2) (layers "F.Cu" "B.Cu") (net 1))
  (via blind (at 111.6 131.75) (size 0.5) (drill 0.2) (layers "F.Cu" "In1.Cu") (net 1))
  (via (at 124.970002 126.61) (size 0.5) (drill 0.2) (layers "F.Cu" "B.Cu") (net 1))
  (via (at 116.4 117.35) (size 0.5) (drill 0.2) (layers "F.Cu" "B.Cu") (net 1))
  (via (at 102.8 117.35) (size 0.5) (drill 0.2) (layers "F.Cu" "B.Cu") (net 1))
  (via blind (at 116.4 119.75) (size 0.5) (drill 0.2) (layers "F.Cu" "In1.Cu") (net 1))
  (via (at 99.608716 129.34929) (size 0.5) (drill 0.2) (layers "F.Cu" "B.Cu") (net 1))
  (via (at 114 114.95) (size 0.5) (drill 0.2) (layers "F.Cu" "B.Cu") (net 1))
  (via (at 128.35 128.075) (size 0.5) (drill 0.2) (layers "F.Cu" "B.Cu") (net 1))
  (via (at 112.4 119.75) (size 0.5) (drill 0.2) (layers "F.Cu" "B.Cu") (net 1))
  (via (at 128.325 128.725) (size 0.5) (drill 0.2) (layers "F.Cu" "B.Cu") (net 1))
  (via (at 94.8 117.35) (size 0.5) (drill 0.2) (layers "F.Cu" "B.Cu") (net 1))
  (via (at 115.6 130.15) (size 0.5) (drill 0.2) (layers "F.Cu" "B.Cu") (net 1))
  (via (at 96.4 122.15) (size 0.5) (drill 0.2) (layers "F.Cu" "B.Cu") (net 1))
  (via (at 106 111.75) (size 0.5) (drill 0.2) (layers "F.Cu" "B.Cu") (net 1))
  (via (at 98.8 113.35) (size 0.5) (drill 0.2) (layers "F.Cu" "B.Cu") (net 1))
  (via (at 76.3 93.375) (size 0.5) (drill 0.2) (layers "F.Cu" "B.Cu") (net 1))
  (via blind (at 87.1 117.75) (size 0.5) (drill 0.2) (layers "F.Cu" "In1.Cu") (net 1))
  (via blind (at 79.89 120.175) (size 0.5) (drill 0.2) (layers "F.Cu" "In2.Cu") (net 1))
  (via (at 74.37 120.84) (size 0.5) (drill 0.2) (layers "F.Cu" "B.Cu") (net 1))
  (via (at 73.8 118.5) (size 0.5) (drill 0.2) (layers "F.Cu" "B.Cu") (net 1))
  (via (at 92.8 94.06) (size 0.5) (drill 0.2) (layers "F.Cu" "B.Cu") (net 1))
  (via (at 95.6 114.95) (size 0.5) (drill 0.2) (layers "F.Cu" "B.Cu") (net 1))
  (via (at 89.05 63.25) (size 0.6) (drill 0.3) (layers "F.Cu" "B.Cu") (net 1))
  (via (at 88.05 63.35) (size 0.6) (drill 0.3) (layers "F.Cu" "B.Cu") (net 1))
  (via (at 87.85 61.25) (size 0.6) (drill 0.3) (layers "F.Cu" "B.Cu") (net 1))
  (via (at 88.55 61.25) (size 0.6) (drill 0.3) (layers "F.Cu" "B.Cu") (net 1))
  (via (at 94.25 60.45) (size 0.6) (drill 0.3) (layers "F.Cu" "B.Cu") (net 1))
  (via (at 93.15 60.45) (size 0.6) (drill 0.3) (layers "F.Cu" "B.Cu") (net 1))
  (via (at 93.64 82.51) (size 0.5) (drill 0.2) (layers "F.Cu" "B.Cu") (net 1))
  (via (at 93.64 83.51) (size 0.5) (drill 0.2) (layers "F.Cu" "B.Cu") (net 1))
  (via (at 94.45 74.85) (size 0.5) (drill 0.2) (layers "F.Cu" "B.Cu") (net 1))
  (via (at 75.8 116.2) (size 0.5) (drill 0.2) (layers "F.Cu" "B.Cu") (net 1))
  (via (at 104.4 111.75) (size 0.5) (drill 0.2) (layers "F.Cu" "B.Cu") (net 1))
  (via (at 77.25 125.18) (size 0.5) (drill 0.2) (layers "F.Cu" "B.Cu") (net 1))
  (via (at 116.4 122.15) (size 0.5) (drill 0.2) (layers "F.Cu" "B.Cu") (net 1))
  (via (at 80.175 175.375) (size 0.6) (drill 0.3) (layers "F.Cu" "B.Cu") (net 1))
  (via (at 91.8 97.09) (size 0.5) (drill 0.2) (layers "F.Cu" "B.Cu") (net 1))
  (via (at 115.225 175.375) (size 0.6) (drill 0.3) (layers "F.Cu" "B.Cu") (net 1))
  (via (at 141.6 92.225) (size 0.5) (drill 0.2) (layers "F.Cu" "B.Cu") (net 1))
  (via (at 131.9 89.775) (size 0.5) (drill 0.2) (layers "F.Cu" "B.Cu") (net 1))
  (via (at 135.55 84.725) (size 0.5) (drill 0.2) (layers "F.Cu" "B.Cu") (net 1))
  (via (at 139.5 94.775) (size 0.5) (drill 0.2) (layers "F.Cu" "B.Cu") (net 1))
  (via (at 135.4 94.825) (size 0.5) (drill 0.2) (layers "F.Cu" "B.Cu") (net 1))
  (via (at 138 94.875) (size 0.5) (drill 0.2) (layers "F.Cu" "B.Cu") (net 1))
  (via (at 144.675 86.125) (size 0.5) (drill 0.2) (layers "F.Cu" "B.Cu") (net 1))
  (via (at 138.75 84.875) (size 0.5) (drill 0.2) (layers "F.Cu" "B.Cu") (net 1))
  (via (at 141.55 82.575) (size 0.5) (drill 0.2) (layers "F.Cu" "B.Cu") (net 1))
  (via (at 68.077 157.00712) (size 0.5) (drill 0.2) (layers "F.Cu" "B.Cu") (net 1))
  (via (at 68.577 156.60712) (size 0.5) (drill 0.2) (layers "F.Cu" "B.Cu") (net 1))
  (via (at 90.79 95.1) (size 0.5) (drill 0.2) (layers "F.Cu" "B.Cu") (net 1))
  (via (at 97.3 119.75) (size 0.5) (drill 0.2) (layers "F.Cu" "B.Cu") (net 1))
  (via (at 68.32 164.415) (size 0.6) (drill 0.3) (layers "F.Cu" "B.Cu") (net 1))
  (via (at 67.52 165.29) (size 0.6) (drill 0.3) (layers "F.Cu" "B.Cu") (net 1))
  (via (at 66.72 164.415) (size 0.6) (drill 0.3) (layers "F.Cu" "B.Cu") (net 1))
  (via (at 67.52 164.415) (size 0.6) (drill 0.3) (layers "F.Cu" "B.Cu") (net 1))
  (via (at 66.72 165.29) (size 0.6) (drill 0.3) (layers "F.Cu" "B.Cu") (net 1))
  (via (at 68.32 165.29) (size 0.6) (drill 0.3) (layers "F.Cu" "B.Cu") (net 1))
  (via (at 63.2 60.15) (size 0.5) (drill 0.2) (layers "F.Cu" "B.Cu") (net 1))
  (via blind (at 108.4 115.75) (size 0.5) (drill 0.2) (layers "F.Cu" "In1.Cu") (net 1))
  (via (at 61.35 108.5228) (size 0.5) (drill 0.2) (layers "F.Cu" "B.Cu") (net 1))
  (via blind (at 100.4 125.35) (size 0.5) (drill 0.2) (layers "F.Cu" "In1.Cu") (net 1))
  (via (at 139 89.8) (size 0.5) (drill 0.2) (layers "F.Cu" "B.Cu") (net 1))
  (via (at 99 86.99) (size 0.5) (drill 0.2) (layers "F.Cu" "B.Cu") (net 1))
  (via (at 86.8 95.1) (size 0.5) (drill 0.2) (layers "F.Cu" "B.Cu") (net 1))
  (via (at 78.98 78.33) (size 0.5) (drill 0.2) (layers "F.Cu" "B.Cu") (net 1))
  (via (at 99.6 123.75) (size 0.5) (drill 0.2) (layers "F.Cu" "B.Cu") (net 1))
  (via (at 113.2 125.35) (size 0.5) (drill 0.2) (layers "F.Cu" "B.Cu") (net 1))
  (via (at 124.95 166.5) (size 0.5) (drill 0.2) (layers "F.Cu" "B.Cu") (net 1))
  (via (at 84.775 83.775) (size 0.5) (drill 0.2) (layers "F.Cu" "B.Cu") (net 1))
  (via blind (at 109.2 122.15) (size 0.5) (drill 0.2) (layers "F.Cu" "In1.Cu") (net 1))
  (via (at 99.6 117.35) (size 0.5) (drill 0.2) (layers "F.Cu" "B.Cu") (net 1))
  (via (at 112.4 123.75) (size 0.5) (drill 0.2) (layers "F.Cu" "B.Cu") (net 1))
  (via (at 106 123.75) (size 0.5) (drill 0.2) (layers "F.Cu" "B.Cu") (net 1))
  (via (at 61.35 162.9422) (size 0.5) (drill 0.2) (layers "F.Cu" "B.Cu") (net 1))
  (via blind (at 110 131.75) (size 0.5) (drill 0.2) (layers "F.Cu" "In1.Cu") (net 1))
  (via (at 100.9 133.55) (size 0.5) (drill 0.2) (layers "F.Cu" "B.Cu") (net 1))
  (via (at 61.35 80.305333) (size 0.5) (drill 0.2) (layers "F.Cu" "B.Cu") (net 1))
  (via (at 67.096794 178.09999) (size 0.5) (drill 0.2) (layers "F.Cu" "B.Cu") (net 1))
  (via (at 61.35 136.740267) (size 0.5) (drill 0.2) (layers "F.Cu" "B.Cu") (net 1))
  (via (at 99.6 118.15) (size 0.5) (drill 0.2) (layers "F.Cu" "B.Cu") (net 1))
  (via blind (at 105.2 122.15) (size 0.5) (drill 0.2) (layers "F.Cu" "In1.Cu") (net 1))
  (via (at 101.2 118.15) (size 0.5) (drill 0.2) (layers "F.Cu" "B.Cu") (net 1))
  (via (at 105.2 118.95) (size 0.5) (drill 0.2) (layers "F.Cu" "B.Cu") (net 1))
  (via (at 96.3 173.989994) (size 0.5) (drill 0.2) (layers "F.Cu" "B.Cu") (net 1))
  (via blind (at 101.2 122.15) (size 0.5) (drill 0.2) (layers "F.Cu" "In1.Cu") (net 1))
  (via (at 95.6 110.95) (size 0.5) (drill 0.2) (layers "F.Cu" "B.Cu") (net 1))
  (via (at 61.35 116.584933) (size 0.5) (drill 0.2) (layers "F.Cu" "B.Cu") (net 1))
  (via (at 148.85 112.56809) (size 0.5) (drill 0.2) (layers "F.Cu" "B.Cu") (net 1))
  (via blind (at 103.6 117.35) (size 0.5) (drill 0.2) (layers "F.Cu" "In1.Cu") (net 1))
  (via (at 132.2 175.725) (size 0.6) (drill 0.3) (layers "F.Cu" "B.Cu") (net 1))
  (via (at 102 112.55) (size 0.5) (drill 0.2) (layers "F.Cu" "B.Cu") (net 1))
  (via (at 133.985 175.725) (size 0.6) (drill 0.3) (layers "F.Cu" "B.Cu") (net 1))
  (via (at 103.6 118.15) (size 0.5) (drill 0.2) (layers "F.Cu" "B.Cu") (net 1))
  (via blind (at 98 109.35) (size 0.5) (drill 0.2) (layers "F.Cu" "In1.Cu") (net 1))
  (via (at 148.85 106.519849) (size 0.5) (drill 0.2) (layers "F.Cu" "B.Cu") (net 1))
  (via (at 148.85 60.15) (size 0.5) (drill 0.2) (layers "F.Cu" "B.Cu") (net 1))
  (via (at 90.775 83.775) (size 0.5) (drill 0.2) (layers "F.Cu" "B.Cu") (net 1))
  (via (at 148.85 100.471608) (size 0.5) (drill 0.2) (layers "F.Cu" "B.Cu") (net 1))
  (via (at 61.35 144.8024) (size 0.5) (drill 0.2) (layers "F.Cu" "B.Cu") (net 1))
  (via (at 148.85 160.95402) (size 0.5) (drill 0.2) (layers "F.Cu" "B.Cu") (net 1))
  (via (at 148.85 96.439447) (size 0.5) (drill 0.2) (layers "F.Cu" "B.Cu") (net 1))
  (via (at 108.1 133.55) (size 0.5) (drill 0.2) (layers "F.Cu" "B.Cu") (net 1))
  (via (at 61.35 146.817933) (size 0.5) (drill 0.2) (layers "F.Cu" "B.Cu") (net 1))
  (via (at 120.3 162.9) (size 0.5) (drill 0.2) (layers "F.Cu" "B.Cu") (net 1))
  (via (at 61.35 78.2898) (size 0.5) (drill 0.2) (layers "F.Cu" "B.Cu") (net 1))
  (via (at 82.55 97.45) (size 0.5) (drill 0.2) (layers "F.Cu" "B.Cu") (net 1))
  (via blind (at 101.2 118.95) (size 0.5) (drill 0.2) (layers "F.Cu" "In1.Cu") (net 1))
  (via blind (at 106.8 131.75) (size 0.5) (drill 0.2) (layers "F.Cu" "In1.Cu") (net 1))
  (via (at 114.95501 67.230597) (size 0.5) (drill 0.2) (layers "F.Cu" "B.Cu") (net 1))
  (via (at 148.85 128.696734) (size 0.5) (drill 0.2) (layers "F.Cu" "B.Cu") (net 1))
  (via (at 65.1 60.15) (size 0.5) (drill 0.2) (layers "F.Cu" "B.Cu") (free) (net 1))
  (via (at 61.35 82.320866) (size 0.5) (drill 0.2) (layers "F.Cu" "B.Cu") (net 1))
  (via (at 148.85 80.310804) (size 0.5) (drill 0.2) (layers "F.Cu" "B.Cu") (net 1))
  (via (at 106.8 119.75) (size 0.5) (drill 0.2) (layers "F.Cu" "B.Cu") (net 1))
  (via (at 85.85 134) (size 0.5) (drill 0.2) (layers "F.Cu" "B.Cu") (net 1))
  (via (at 78 125.95) (size 0.5) (drill 0.2) (layers "F.Cu" "B.Cu") (net 1))
  (via blind (at 102.8 122.15) (size 0.5) (drill 0.2) (layers "F.Cu" "In1.Cu") (net 1))
  (via (at 148.85 90.391206) (size 0.5) (drill 0.2) (layers "F.Cu" "B.Cu") (net 1))
  (via (at 102 118.15) (size 0.5) (drill 0.2) (layers "F.Cu" "B.Cu") (net 1))
  (via (at 76.32 126.05) (size 0.5) (drill 0.2) (layers "F.Cu" "B.Cu") (net 1))
  (via (at 134.7 153.65) (size 0.5) (drill 0.2) (layers "F.Cu" "B.Cu") (net 1))
  (via blind (at 97.2 132.55) (size 0.5) (drill 0.2) (layers "F.Cu" "In1.Cu") (net 1))
  (via (at 102 117.35) (size 0.5) (drill 0.2) (layers "F.Cu" "B.Cu") (net 1))
  (via (at 148.85 94.423367) (size 0.5) (drill 0.2) (layers "F.Cu" "B.Cu") (net 1))
  (via (at 73.9 60.05) (size 0.6) (drill 0.3) (layers "F.Cu" "B.Cu") (net 1))
  (via blind (at 98 132.55) (size 0.5) (drill 0.2) (layers "F.Cu" "In1.Cu") (net 1))
  (via (at 87.4 139.75) (size 0.5) (drill 0.2) (layers "F.Cu" "B.Cu") (net 1))
  (via (at 108.4 118.95) (size 0.5) (drill 0.2) (layers "F.Cu" "B.Cu") (net 1))
  (via (at 70.9 90.55) (size 0.5) (drill 0.2) (layers "F.Cu" "B.Cu") (net 1))
  (via (at 106.8 122.95) (size 0.5) (drill 0.2) (layers "F.Cu" "B.Cu") (net 1))
  (via (at 112.223 93.72) (size 0.5) (drill 0.2) (layers "F.Cu" "B.Cu") (net 1))
  (via (at 72.23465 95.10965) (size 0.5) (drill 0.2) (layers "F.Cu" "B.Cu") (net 1))
  (via (at 61.35 134.724733) (size 0.5) (drill 0.2) (layers "F.Cu" "B.Cu") (net 1))
  (via (at 109.2 123.75) (size 0.5) (drill 0.2) (layers "F.Cu" "B.Cu") (net 1))
  (via (at 61.35 72.2432) (size 0.5) (drill 0.2) (layers "F.Cu" "B.Cu") (net 1))
  (via (at 148.85 154.905779) (size 0.5) (drill 0.2) (layers "F.Cu" "B.Cu") (net 1))
  (via (at 61.35 128.678133) (size 0.5) (drill 0.2) (layers "F.Cu" "B.Cu") (net 1))
  (via (at 148.85 162.970101) (size 0.5) (drill 0.2) (layers "F.Cu" "B.Cu") (net 1))
  (via (at 120.139056 83.493104) (size 0.5) (drill 0.2) (layers "F.Cu" "B.Cu") (free) (net 1))
  (via (at 148.85 144.825377) (size 0.5) (drill 0.2) (layers "F.Cu" "B.Cu") (net 1))
  (via blind (at 102 131.75) (size 0.5) (drill 0.2) (layers "F.Cu" "In1.Cu") (net 1))
  (via (at 83.25 68) (size 0.6) (drill 0.3) (layers "F.Cu" "B.Cu") (net 1))
  (via (at 76.3 175.6) (size 0.6) (drill 0.3) (layers "F.Cu" "B.Cu") (net 1))
  (via (at 121.65 112.45) (size 0.5) (drill 0.2) (layers "F.Cu" "B.Cu") (net 1))
  (via (at 83.4 119.9) (size 0.5) (drill 0.2) (layers "F.Cu" "B.Cu") (net 1))
  (via (at 131.275004 61.65) (size 0.5) (drill 0.2) (layers "F.Cu" "B.Cu") (net 1))
  (via blind (at 110 130.95) (size 0.5) (drill 0.2) (layers "F.Cu" "In1.Cu") (net 1))
  (via (at 95.65 128.5) (size 0.5) (drill 0.2) (layers "F.Cu" "B.Cu") (net 1))
  (via (at 78.8 61.875) (size 0.6) (drill 0.3) (layers "F.Cu" "B.Cu") (net 1))
  (via (at 119.191883 60.15) (size 0.5) (drill 0.2) (layers "F.Cu" "B.Cu") (net 1))
  (via (at 86.77 110.11) (size 0.5) (drill 0.2) (layers "F.Cu" "B.Cu") (net 1))
  (via (at 89.41 68.565) (size 0.6) (drill 0.3) (layers "F.Cu" "B.Cu") (net 1))
  (via (at 102 99) (size 0.5) (drill 0.2) (layers "F.Cu" "B.Cu") (net 1))
  (via (at 84.7 68.05) (size 0.6) (drill 0.3) (layers "F.Cu" "B.Cu") (net 1))
  (via (at 103.95 133.5) (size 0.5) (drill 0.2) (layers "F.Cu" "B.Cu") (net 1))
  (via (at 146.731563 60.15) (size 0.5) (drill 0.2) (layers "F.Cu" "B.Cu") (net 1))
  (via blind (at 101.2 121.35) (size 0.5) (drill 0.2) (layers "F.Cu" "In1.Cu") (net 1))
  (via (at 61.35 66.1966) (size 0.5) (drill 0.2) (layers "F.Cu" "B.Cu") (net 1))
  (via (at 118.9 166.25) (size 0.5) (drill 0.2) (layers "F.Cu" "B.Cu") (net 1))
  (via (at 95.6 130.15) (size 0.5) (drill 0.2) (layers "F.Cu" "B.Cu") (net 1))
  (via (at 148.85 130.712814) (size 0.5) (drill 0.2) (layers "F.Cu" "B.Cu") (net 1))
  (via (at 148.85 142.809296) (size 0.5) (drill 0.2) (layers "F.Cu" "B.Cu") (net 1))
  (via (at 101.95 133.55) (size 0.5) (drill 0.2) (layers "F.Cu" "B.Cu") (net 1))
  (via (at 61.35 100.460666) (size 0.5) (drill 0.2) (layers "F.Cu" "B.Cu") (net 1))
  (via (at 115.6 126.95) (size 0.5) (drill 0.2) (layers "F.Cu" "B.Cu") (net 1))
  (via (at 129.36 137.68) (size 0.5) (drill 0.2) (layers "F.Cu" "B.Cu") (net 1))
  (via (at 106.82 146.65) (size 0.5) (drill 0.2) (layers "F.Cu" "B.Cu") (net 1))
  (via (at 77.65 76.2) (size 0.5) (drill 0.2) (layers "F.Cu" "B.Cu") (net 1))
  (via (at 102 121.35) (size 0.5) (drill 0.2) (layers "F.Cu" "B.Cu") (net 1))
  (via blind (at 99.6 114.95) (size 0.5) (drill 0.2) (layers "F.Cu" "In1.Cu") (net 1))
  (via (at 148.85 148.857538) (size 0.5) (drill 0.2) (layers "F.Cu" "B.Cu") (net 1))
  (via (at 72.94 166.06) (size 0.5) (drill 0.2) (layers "F.Cu" "B.Cu") (net 1))
  (via (at 70.280922 171.810739) (size 0.5) (drill 0.2) (layers "F.Cu" "B.Cu") (net 1))
  (via (at 76.25 145.7) (size 0.5) (drill 0.2) (layers "F.Cu" "B.Cu") (net 1))
  (via (at 99.6 115.75) (size 0.5) (drill 0.2) (layers "F.Cu" "B.Cu") (net 1))
  (via blind (at 99.6 122.95) (size 0.5) (drill 0.2) (layers "F.Cu" "In1.Cu") (net 1))
  (via (at 61.35 138.7558) (size 0.5) (drill 0.2) (layers "F.Cu" "B.Cu") (net 1))
  (via blind (at 102 118.95) (size 0.5) (drill 0.2) (layers "F.Cu" "In1.Cu") (net 1))
  (via (at 88.05 130.57) (size 0.5) (drill 0.2) (layers "F.Cu" "B.Cu") (net 1))
  (via (at 138.025 76.98) (size 0.5) (drill 0.2) (layers "F.Cu" "B.Cu") (net 1))
  (via (at 61.35 94.414066) (size 0.5) (drill 0.2) (layers "F.Cu" "B.Cu") (net 1))
  (via (at 116.1 71.357643) (size 0.5) (drill 0.2) (layers "F.Cu" "B.Cu") (net 1))
  (via (at 148.85 72.246482) (size 0.5) (drill 0.2) (layers "F.Cu" "B.Cu") (net 1))
  (via (at 139 88.4) (size 0.5) (drill 0.2) (layers "F.Cu" "B.Cu") (net 1))
  (via (at 143.239626 178.09999) (size 0.5) (drill 0.2) (layers "F.Cu" "B.Cu") (net 1))
  (via blind (at 110 115.75) (size 0.5) (drill 0.2) (layers "F.Cu" "In1.Cu") (net 1))
  (via blind (at 109.2 125.35) (size 0.5) (drill 0.2) (layers "F.Cu" "In1.Cu") (net 1))
  (via blind (at 102 123.75) (size 0.5) (drill 0.2) (layers "F.Cu" "In1.Cu") (net 1))
  (via (at 103.6 118.95) (size 0.5) (drill 0.2) (layers "F.Cu" "B.Cu") (net 1))
  (via (at 131.250002 64.2) (size 0.5) (drill 0.2) (layers "F.Cu" "B.Cu") (net 1))
  (via (at 76.3 174.8) (size 0.6) (drill 0.3) (layers "F.Cu" "B.Cu") (net 1))
  (via blind (at 111.6 129.35) (size 0.5) (drill 0.2) (layers "F.Cu" "In1.Cu") (net 1))
  (via blind (at 102.8 108.55) (size 0.5) (drill 0.2) (layers "F.Cu" "In1.Cu") (net 1))
  (via (at 61.35 130.693667) (size 0.5) (drill 0.2) (layers "F.Cu" "B.Cu") (net 1))
  (via (at 86.58 130.52) (size 0.5) (drill 0.2) (layers "F.Cu" "B.Cu") (net 1))
  (via blind (at 97.2 130.95) (size 0.5) (drill 0.2) (layers "F.Cu" "In1.Cu") (net 1))
  (via (at 69.700123 175.903091) (size 0.5) (drill 0.2) (layers "F.Cu" "B.Cu") (net 1))
  (via (at 128.425 129.7) (size 0.5) (drill 0.2) (layers "F.Cu" "B.Cu") (net 1))
  (via (at 77.67 128.34) (size 0.5) (drill 0.2) (layers "F.Cu" "B.Cu") (net 1))
  (via (at 119.2 70.225) (size 0.5) (drill 0.2) (layers "F.Cu" "B.Cu") (net 1))
  (via (at 110.2 97.85) (size 0.5) (drill 0.2) (layers "F.Cu" "B.Cu") (net 1))
  (via (at 112.4 124.55) (size 0.5) (drill 0.2) (layers "F.Cu" "B.Cu") (net 1))
  (via (at 103.6 119.75) (size 0.5) (drill 0.2) (layers "F.Cu" "B.Cu") (net 1))
  (via (at 144.613126 60.15) (size 0.5) (drill 0.2) (layers "F.Cu" "B.Cu") (net 1))
  (via (at 90.775 84.525) (size 0.5) (drill 0.2) (layers "F.Cu" "B.Cu") (net 1))
  (via (at 113.1 130.15) (size 0.5) (drill 0.2) (layers "F.Cu" "B.Cu") (net 1))
  (via (at 142.05 90.7) (size 0.5) (drill 0.2) (layers "F.Cu" "B.Cu") (net 1))
  (via (at 73.41 126.05) (size 0.5) (drill 0.2) (layers "F.Cu" "B.Cu") (net 1))
  (via (at 114 126.95) (size 0.5) (drill 0.2) (layers "F.Cu" "B.Cu") (net 1))
  (via (at 148.85 76.278643) (size 0.5) (drill 0.2) (layers "F.Cu" "B.Cu") (net 1))
  (via (at 128.585 175.775) (size 0.6) (drill 0.3) (layers "F.Cu" "B.Cu") (net 1))
  (via (at 78.05 65.85) (size 0.6) (drill 0.3) (layers "F.Cu" "B.Cu") (net 1))
  (via (at 116.1 75.753821) (size 0.5) (drill 0.2) (layers "F.Cu" "B.Cu") (free) (net 1))
  (via (at 138 87.8) (size 0.5) (drill 0.2) (layers "F.Cu" "B.Cu") (net 1))
  (via (at 84.14 110.11) (size 0.5) (drill 0.2) (layers "F.Cu" "B.Cu") (net 1))
  (via (at 96.4 133.35) (size 0.5) (drill 0.2) (layers "F.Cu" "B.Cu") (net 1))
  (via (at 109.2 115.75) (size 0.5) (drill 0.2) (layers "F.Cu" "B.Cu") (net 1))
  (via (at 61.35 171.004333) (size 0.5) (drill 0.2) (layers "F.Cu" "B.Cu") (net 1))
  (via (at 69.700123 173.757218) (size 0.5) (drill 0.2) (layers "F.Cu" "B.Cu") (net 1))
  (via (at 78.1 64.2) (size 0.6) (drill 0.3) (layers "F.Cu" "B.Cu") (net 1))
  (via blind (at 106 122.15) (size 0.5) (drill 0.2) (layers "F.Cu" "In1.Cu") (net 1))
  (via blind (at 106 132.55) (size 0.5) (drill 0.2) (layers "F.Cu" "In1.Cu") (net 1))
  (via (at 101.2 90.05) (size 0.5) (drill 0.2) (layers "F.Cu" "B.Cu") (net 1))
  (via (at 98.8 115.75) (size 0.5) (drill 0.2) (layers "F.Cu" "B.Cu") (net 1))
  (via (at 109.2 124.55) (size 0.5) (drill 0.2) (layers "F.Cu" "B.Cu") (net 1))
  (via (at 61.35 104.491733) (size 0.5) (drill 0.2) (layers "F.Cu" "B.Cu") (net 1))
  (via (at 110.8 109.35) (size 0.5) (drill 0.2) (layers "F.Cu" "B.Cu") (net 1))
  (via (at 104.4 128.55) (size 0.5) (drill 0.2) (layers "F.Cu" "B.Cu") (net 1))
  (via (at 136 87.8) (size 0.5) (drill 0.2) (layers "F.Cu" "B.Cu") (net 1))
  (via (at 148.85 122.648492) (size 0.5) (drill 0.2) (layers "F.Cu" "B.Cu") (net 1))
  (via (at 106.05 133.55) (size 0.5) (drill 0.2) (layers "F.Cu" "B.Cu") (net 1))
  (via (at 106.8 118.15) (size 0.5) (drill 0.2) (layers "F.Cu" "B.Cu") (net 1))
  (via (at 73.25 120.85) (size 0.5) (drill 0.2) (layers "F.Cu" "B.Cu") (net 1))
  (via (at 77.05 60) (size 0.6) (drill 0.3) (layers "F.Cu" "B.Cu") (net 1))
  (via blind (at 106 121.35) (size 0.5) (drill 0.2) (layers "F.Cu" "In1.Cu") (net 1))
  (via (at 148.85 156.921859) (size 0.5) (drill 0.2) (layers "F.Cu" "B.Cu") (net 1))
  (via (at 78.8 65) (size 0.6) (drill 0.3) (layers "F.Cu" "B.Cu") (net 1))
  (via (at 148.85 167.002261) (size 0.5) (drill 0.2) (layers "F.Cu" "B.Cu") (net 1))
  (via (at 91.41 68.565) (size 0.6) (drill 0.3) (layers "F.Cu" "B.Cu") (net 1))
  (via (at 148.85 169.018342) (size 0.5) (drill 0.2) (layers "F.Cu" "B.Cu") (net 1))
  (via (at 61.35 126.6626) (size 0.5) (drill 0.2) (layers "F.Cu" "B.Cu") (net 1))
  (via (at 148.85 120.632412) (size 0.5) (drill 0.2) (layers "F.Cu" "B.Cu") (net 1))
  (via (at 61.35 177.050934) (size 0.5) (drill 0.2) (layers "F.Cu" "B.Cu") (net 1))
  (via blind (at 105.2 132.55) (size 0.5) (drill 0.2) (layers "F.Cu" "In1.Cu") (net 1))
  (via (at 106.8 130.15) (size 0.5) (drill 0.2) (layers "F.Cu" "B.Cu") (net 1))
  (via (at 87.43 102.8) (size 0.5) (drill 0.2) (layers "F.Cu" "B.Cu") (net 1))
  (via (at 68.3 89.15) (size 0.5) (drill 0.2) (layers "F.Cu" "B.Cu") (net 1))
  (via (at 135.785 175.725) (size 0.6) (drill 0.3) (layers "F.Cu" "B.Cu") (net 1))
  (via (at 100.4 115.75) (size 0.5) (drill 0.2) (layers "F.Cu" "B.Cu") (net 1))
  (via blind (at 96.4 130.95) (size 0.5) (drill 0.2) (layers "F.Cu" "In1.Cu") (net 1))
  (via (at 148.85 64.18216) (size 0.5) (drill 0.2) (layers "F.Cu" "B.Cu") (net 1))
  (via (at 119.499056 82.113104) (size 0.5) (drill 0.2) (layers "F.Cu" "B.Cu") (net 1))
  (via (at 138.86 141.34) (size 0.5) (drill 0.2) (layers "F.Cu" "B.Cu") (net 1))
  (via (at 138.2 166.2) (size 0.5) (drill 0.2) (layers "F.Cu" "B.Cu") (net 1))
  (via (at 88.1 116.45784) (size 0.5) (drill 0.2) (layers "F.Cu" "B.Cu") (net 1))
  (via (at 103.6 122.95) (size 0.5) (drill 0.2) (layers "F.Cu" "B.Cu") (net 1))
  (via blind (at 102 132.55) (size 0.5) (drill 0.2) (layers "F.Cu" "In1.Cu") (net 1))
  (via (at 148.85 98.455527) (size 0.5) (drill 0.2) (layers "F.Cu" "B.Cu") (net 1))
  (via (at 76 60.05) (size 0.6) (drill 0.3) (layers "F.Cu" "B.Cu") (net 1))
  (via blind (at 120.87 153.43) (size 0.5) (drill 0.2) (layers "F.Cu" "In1.Cu") (net 1))
  (via blind (at 110 114.95) (size 0.5) (drill 0.2) (layers "F.Cu" "In1.Cu") (net 1))
  (via blind (at 100.4 132.55) (size 0.5) (drill 0.2) (layers "F.Cu" "In1.Cu") (net 1))
  (via (at 80.7 116.95) (size 0.5) (drill 0.2) (layers "F.Cu" "B.Cu") (net 1))
  (via (at 114.799471 129.350529) (size 0.5) (drill 0.2) (layers "F.Cu" "B.Cu") (net 1))
  (via (at 101.975 175.4) (size 0.6) (drill 0.3) (layers "F.Cu" "B.Cu") (net 1))
  (via (at 78.1 67.05) (size 0.6) (drill 0.3) (layers "F.Cu" "B.Cu") (net 1))
  (via (at 128.6 123.4) (size 0.5) (drill 0.2) (layers "F.Cu" "B.Cu") (net 1))
  (via (at 110.2 96.2) (size 0.5) (drill 0.2) (layers "F.Cu" "B.Cu") (net 1))
  (via (at 61.35 110.538333) (size 0.5) (drill 0.2) (layers "F.Cu" "B.Cu") (net 1))
  (via (at 70.1 130.65) (size 0.5) (drill 0.2) (layers "F.Cu" "B.Cu") (net 1))
  (via (at 85.4 130.55) (size 0.5) (drill 0.2) (layers "F.Cu" "B.Cu") (net 1))
  (via (at 102 115.75) (size 0.5) (drill 0.2) (layers "F.Cu" "B.Cu") (net 1))
  (via (at 102.8 128.55) (size 0.5) (drill 0.2) (layers "F.Cu" "B.Cu") (net 1))
  (via (at 64.14 168.25) (size 0.5) (drill 0.2) (layers "F.Cu" "B.Cu") (net 1))
  (via (at 129.11 119.44) (size 0.5) (drill 0.2) (layers "F.Cu" "B.Cu") (net 1))
  (via (at 89.3 108.95) (size 0.5) (drill 0.2) (layers "F.Cu" "B.Cu") (net 1))
  (via (at 86.65 142.55) (size 0.5) (drill 0.2) (layers "F.Cu" "B.Cu") (net 1))
  (via (at 106.8 121.35) (size 0.5) (drill 0.2) (layers "F.Cu" "B.Cu") (net 1))
  (via (at 92.4 175.325) (size 0.6) (drill 0.3) (layers "F.Cu" "B.Cu") (net 1))
  (via (at 61.35 124.647067) (size 0.5) (drill 0.2) (layers "F.Cu" "B.Cu") (net 1))
  (via blind (at 108.4 125.35) (size 0.5) (drill 0.2) (layers "F.Cu" "In1.Cu") (net 1))
  (via (at 99.314 173.99) (size 0.5) (drill 0.2) (layers "F.Cu" "B.Cu") (net 1))
  (via (at 121.95 124.15) (size 0.5) (drill 0.2) (layers "F.Cu" "B.Cu") (net 1))
  (via (at 105.75 96.45) (size 0.5) (drill 0.2) (layers "F.Cu" "B.Cu") (net 1))
  (via (at 132.44 134.57) (size 0.5) (drill 0.2) (layers "F.Cu" "B.Cu") (net 1))
  (via (at 61.979433 178.09999) (size 0.5) (drill 0.2) (layers "F.Cu" "B.Cu") (net 1))
  (via (at 148.85 152.889699) (size 0.5) (drill 0.2) (layers "F.Cu" "B.Cu") (net 1))
  (via (at 140.08 124.74) (size 0.5) (drill 0.2) (layers "F.Cu" "B.Cu") (net 1))
  (via (at 96.4 131.75) (size 0.5) (drill 0.2) (layers "F.Cu" "B.Cu") (net 1))
  (via (at 148.85 126.680653) (size 0.5) (drill 0.2) (layers "F.Cu" "B.Cu") (net 1))
  (via (at 98.6 133.55) (size 0.5) (drill 0.2) (layers "F.Cu" "B.Cu") (net 1))
  (via (at 148.85 108.535929) (size 0.5) (drill 0.2) (layers "F.Cu" "B.Cu") (net 1))
  (via (at 80.685 126.555) (size 0.5) (drill 0.2) (layers "F.Cu" "B.Cu") (net 1))
  (via (at 102 119.75) (size 0.5) (drill 0.2) (layers "F.Cu" "B.Cu") (net 1))
  (via (at 106 128.55) (size 0.5) (drill 0.2) (layers "F.Cu" "B.Cu") (net 1))
  (via (at 97.5 124) (size 0.5) (drill 0.2) (layers "F.Cu" "B.Cu") (net 1))
  (via (at 110.2 93.7) (size 0.5) (drill 0.2) (layers "F.Cu" "B.Cu") (net 1))
  (via (at 65.65 160.29) (size 0.5) (drill 0.2) (layers "F.Cu" "B.Cu") (net 1))
  (via (at 67.175 94.2) (size 0.5) (drill 0.2) (layers "F.Cu" "B.Cu") (net 1))
  (via (at 91.41 66.285) (size 0.6) (drill 0.3) (layers "F.Cu" "B.Cu") (net 1))
  (via (at 148.85 164.986181) (size 0.5) (drill 0.2) (layers "F.Cu" "B.Cu") (net 1))
  (via (at 102.8 123.75) (size 0.5) (drill 0.2) (layers "F.Cu" "B.Cu") (net 1))
  (via (at 103.6 125.35) (size 0.5) (drill 0.2) (layers "F.Cu" "B.Cu") (net 1))
  (via (at 112.4 122.15) (size 0.5) (drill 0.2) (layers "F.Cu" "B.Cu") (net 1))
  (via (at 148.85 104.503769) (size 0.5) (drill 0.2) (layers "F.Cu" "B.Cu") (net 1))
  (via (at 90.8 86.25) (size 0.5) (drill 0.2) (layers "F.Cu" "B.Cu") (net 1))
  (via (at 79.55 65.8) (size 0.6) (drill 0.3) (layers "F.Cu" "B.Cu") (net 1))
  (via blind (at 107.6 122.15) (size 0.5) (drill 0.2) (layers "F.Cu" "In1.Cu") (net 1))
  (via (at 99.6 130.15) (size 0.5) (drill 0.2) (layers "F.Cu" "B.Cu") (net 1))
  (via blind (at 92.4 118.15) (size 0.5) (drill 0.2) (layers "F.Cu" "In1.Cu") (net 1))
  (via (at 95.6 108.55) (size 0.5) (drill 0.2) (layers "F.Cu" "B.Cu") (net 1))
  (via (at 115.6 109.35) (size 0.5) (drill 0.2) (layers "F.Cu" "B.Cu") (net 1))
  (via (at 106 118.95) (size 0.5) (drill 0.2) (layers "F.Cu" "B.Cu") (net 1))
  (via (at 80.756896 75.506439) (size 0.5) (drill 0.2) (layers "F.Cu" "B.Cu") (net 1))
  (via (at 114.95501 69.590796) (size 0.5) (drill 0.2) (layers "F.Cu" "B.Cu") (net 1))
  (via (at 89.8 100.1) (size 0.5) (drill 0.2) (layers "F.Cu" "B.Cu") (net 1))
  (via (at 134.020941 60.15) (size 0.5) (drill 0.2) (layers "F.Cu" "B.Cu") (net 1))
  (via (at 129.9 114.8) (size 0.5) (drill 0.2) (layers "F.Cu" "B.Cu") (net 1))
  (via (at 72.7 84.3) (size 0.5) (drill 0.2) (layers "F.Cu" "B.Cu") (net 1))
  (via (at 121.275 64.2) (size 0.5) (drill 0.2) (layers "F.Cu" "B.Cu") (net 1))
  (via (at 107.6 122.95) (size 0.5) (drill 0.2) (layers "F.Cu" "B.Cu") (net 1))
  (via (at 114.95501 60.15) (size 0.5) (drill 0.2) (layers "F.Cu" "B.Cu") (net 1))
  (via (at 105.2 125.35) (size 0.5) (drill 0.2) (layers "F.Cu" "B.Cu") (net 1))
  (via (at 122.35 95.53) (size 0.5) (drill 0.2) (layers "F.Cu" "B.Cu") (net 1))
  (via (at 148.85 146.841457) (size 0.5) (drill 0.2) (layers "F.Cu" "B.Cu") (net 1))
  (via (at 91.44 125.35) (size 0.5) (drill 0.2) (layers "F.Cu" "B.Cu") (net 1))
  (via (at 116.4 111.75) (size 0.5) (drill 0.2) (layers "F.Cu" "B.Cu") (net 1))
  (via (at 112.4 120.55) (size 0.5) (drill 0.2) (layers "F.Cu" "B.Cu") (net 1))
  (via (at 97.35 133.5) (size 0.5) (drill 0.2) (layers "F.Cu" "B.Cu") (net 1))
  (via (at 148.85 88.375125) (size 0.5) (drill 0.2) (layers "F.Cu" "B.Cu") (net 1))
  (via (at 102 122.95) (size 0.5) (drill 0.2) (layers "F.Cu" "B.Cu") (net 1))
  (via (at 86.8 98.1) (size 0.5) (drill 0.2) (layers "F.Cu" "B.Cu") (net 1))
  (via blind (at 99.6 122.15) (size 0.5) (drill 0.2) (layers "F.Cu" "In1.Cu") (net 1))
  (via (at 108.4 126.15) (size 0.5) (drill 0.2) (layers "F.Cu" "B.Cu") (net 1))
  (via (at 61.35 156.8956) (size 0.5) (drill 0.2) (layers "F.Cu" "B.Cu") (net 1))
  (via (at 105.2 90.15) (size 0.5) (drill 0.2) (layers "F.Cu" "B.Cu") (net 1))
  (via blind (at 102.8 132.55) (size 0.5) (drill 0.2) (layers "F.Cu" "In1.Cu") (net 1))
  (via (at 86.8 100.1) (size 0.5) (drill 0.2) (layers "F.Cu" "B.Cu") (net 1))
  (via (at 61.35 154.880067) (size 0.5) (drill 0.2) (layers "F.Cu" "B.Cu") (net 1))
  (via (at 148.85 136.761055) (size 0.5) (drill 0.2) (layers "F.Cu" "B.Cu") (net 1))
  (via (at 148.85 78.294723) (size 0.5) (drill 0.2) (layers "F.Cu" "B.Cu") (net 1))
  (via (at 110.8 111.75) (size 0.5) (drill 0.2) (layers "F.Cu" "B.Cu") (net 1))
  (via (at 78.25 116.95) (size 0.5) (drill 0.2) (layers "F.Cu" "B.Cu") (net 1))
  (via (at 105.2 93.95) (size 0.5) (drill 0.2) (layers "F.Cu" "B.Cu") (net 1))
  (via (at 61.35 84.3364) (size 0.5) (drill 0.2) (layers "F.Cu" "B.Cu") (net 1))
  (via (at 120.77999 163.4) (size 0.5) (drill 0.2) (layers "F.Cu" "B.Cu") (net 1))
  (via (at 139.05 166.2) (size 0.5) (drill 0.2) (layers "F.Cu" "B.Cu") (net 1))
  (via (at 61.35 150.849) (size 0.5) (drill 0.2) (layers "F.Cu" "B.Cu") (net 1))
  (via blind (at 106.8 132.55) (size 0.5) (drill 0.2) (layers "F.Cu" "In1.Cu") (net 1))
  (via (at 72.42 126.05) (size 0.5) (drill 0.2) (layers "F.Cu" "B.Cu") (net 1))
  (via blind (at 97.2 130.15) (size 0.5) (drill 0.2) (layers "F.Cu" "In1.Cu") (net 1))
  (via (at 103.35 133.5) (size 0.5) (drill 0.2) (layers "F.Cu" "B.Cu") (net 1))
  (via (at 116.1 80.15) (size 0.5) (drill 0.2) (layers "F.Cu" "B.Cu") (net 1))
  (via (at 125.05 60.25) (size 0.5) (drill 0.2) (layers "F.Cu" "B.Cu") (net 1))
  (via (at 84.775 84.525) (size 0.5) (drill 0.2) (layers "F.Cu" "B.Cu") (net 1))
  (via (at 104 99) (size 0.5) (drill 0.2) (layers "F.Cu" "B.Cu") (net 1))
  (via (at 101.14999 109.35) (size 0.5) (drill 0.2) (layers "F.Cu" "B.Cu") (net 1))
  (via (at 111.64215 133.84215) (size 0.5) (drill 0.2) (layers "F.Cu" "B.Cu") (net 1))
  (via (at 115.6 122.95) (size 0.5) (drill 0.2) (layers "F.Cu" "B.Cu") (net 1))
  (via (at 110.7 133.55) (size 0.5) (drill 0.2) (layers "F.Cu" "B.Cu") (net 1))
  (via (at 79.35 67.05) (size 0.6) (drill 0.3) (layers "F.Cu" "B.Cu") (net 1))
  (via (at 64.538113 178.09999) (size 0.5) (drill 0.2) (layers "F.Cu" "B.Cu") (net 1))
  (via (at 106.78 149.8) (size 0.5) (drill 0.2) (layers "F.Cu" "B.Cu") (net 1))
  (via (at 119.569056 83.483104) (size 0.5) (drill 0.2) (layers "F.Cu" "B.Cu") (net 1))
  (via (at 80.685 127.355) (size 0.5) (drill 0.2) (layers "F.Cu" "B.Cu") (net 1))
  (via (at 102.8 111.75) (size 0.5) (drill 0.2) (layers "F.Cu" "B.Cu") (net 1))
  (via (at 86.8 96.1) (size 0.5) (drill 0.2) (layers "F.Cu" "B.Cu") (net 1))
  (via (at 142.1 86.8) (size 0.5) (drill 0.2) (layers "F.Cu" "B.Cu") (net 1))
  (via blind (at 98.8 114.95) (size 0.5) (drill 0.2) (layers "F.Cu" "In1.Cu") (net 1))
  (via (at 129.784068 60.15) (size 0.5) (drill 0.2) (layers "F.Cu" "B.Cu") (net 1))
  (via blind (at 102 129.35) (size 0.5) (drill 0.2) (layers "F.Cu" "In1.Cu") (net 1))
  (via (at 61.35 120.616) (size 0.5) (drill 0.2) (layers "F.Cu" "B.Cu") (net 1))
  (via (at 87.1 126.55) (size 0.5) (drill 0.2) (layers "F.Cu" "B.Cu") (net 1))
  (via blind (at 103.6 123.75) (size 0.5) (drill 0.2) (layers "F.Cu" "In1.Cu") (net 1))
  (via (at 99.9 134.05) (size 0.5) (drill 0.2) (layers "F.Cu" "B.Cu") (net 1))
  (via blind (at 92.4 126.95) (size 0.5) (drill 0.2) (layers "F.Cu" "In1.Cu") (net 1))
  (via (at 61.35 168.9888) (size 0.5) (drill 0.2) (layers "F.Cu" "B.Cu") (net 1))
  (via (at 106 122.95) (size 0.5) (drill 0.2) (layers "F.Cu" "B.Cu") (net 1))
  (via (at 138.257815 60.15) (size 0.5) (drill 0.2) (layers "F.Cu" "B.Cu") (net 1))
  (via (at 106.9 133.55) (size 0.5) (drill 0.2) (layers "F.Cu" "B.Cu") (net 1))
  (via (at 79.885 128.955) (size 0.5) (drill 0.2) (layers "F.Cu" "B.Cu") (net 1))
  (via (at 98.8 110.95) (size 0.5) (drill 0.2) (layers "F.Cu" "B.Cu") (net 1))
  (via (at 61.35 68.212133) (size 0.5) (drill 0.2) (layers "F.Cu" "B.Cu") (net 1))
  (via (at 139.64 148.27) (size 0.5) (drill 0.2) (layers "F.Cu" "B.Cu") (net 1))
  (via (at 104.25 87.02) (size 0.5) (drill 0.2) (layers "F.Cu" "B.Cu") (net 1))
  (via blind (at 107.6 118.95) (size 0.5) (drill 0.2) (layers "F.Cu" "In1.Cu") (net 1))
  (via (at 81.09 115.21) (size 0.5) (drill 0.2) (layers "F.Cu" "B.Cu") (net 1))
  (via (at 148.85 86.359045) (size 0.5) (drill 0.2) (layers "F.Cu" "B.Cu") (net 1))
  (via (at 116.1 77.95191) (size 0.5) (drill 0.2) (layers "F.Cu" "B.Cu") (net 1))
  (via (at 61.35 118.600467) (size 0.5) (drill 0.2) (layers "F.Cu" "B.Cu") (net 1))
  (via (at 102.8 121.35) (size 0.5) (drill 0.2) (layers "F.Cu" "B.Cu") (net 1))
  (via (at 79.5 64.2) (size 0.6) (drill 0.3) (layers "F.Cu" "B.Cu") (net 1))
  (via (at 127.75 131.275) (size 0.5) (drill 0.2) (layers "F.Cu" "B.Cu") (net 1))
  (via (at 61.35 152.864533) (size 0.5) (drill 0.2) (layers "F.Cu" "B.Cu") (net 1))
  (via (at 78.8 63.6) (size 0.6) (drill 0.3) (layers "F.Cu" "B.Cu") (net 1))
  (via (at 84.8 86.25) (size 0.5) (drill 0.2) (layers "F.Cu" "B.Cu") (net 1))
  (via (at 61.35 166.973267) (size 0.5) (drill 0.2) (layers "F.Cu" "B.Cu") (net 1))
  (via (at 61.35 88.367466) (size 0.5) (drill 0.2) (layers "F.Cu" "B.Cu") (net 1))
  (via (at 61.35 114.5694) (size 0.5) (drill 0.2) (layers "F.Cu" "B.Cu") (net 1))
  (via (at 86.8 101.1) (size 0.5) (drill 0.2) (layers "F.Cu" "B.Cu") (net 1))
  (via (at 82.125 175.375) (size 0.6) (drill 0.3) (layers "F.Cu" "B.Cu") (net 1))
  (via (at 94.45 73.45) (size 0.5) (drill 0.2) (layers "F.Cu" "B.Cu") (net 1))
  (via (at 135.1 87.83) (size 0.5) (drill 0.2) (layers "F.Cu" "B.Cu") (net 1))
  (via (at 121.25 61.65) (size 0.5) (drill 0.2) (layers "F.Cu" "B.Cu") (net 1))
  (via (at 116.47 147.25) (size 0.5) (drill 0.2) (layers "F.Cu" "B.Cu") (net 1))
  (via (at 61.35 158.911133) (size 0.5) (drill 0.2) (layers "F.Cu" "B.Cu") (net 1))
  (via (at 140.376252 60.15) (size 0.5) (drill 0.2) (layers "F.Cu" "B.Cu") (net 1))
  (via (at 103.6 115.75) (size 0.5) (drill 0.2) (layers "F.Cu" "B.Cu") (net 1))
  (via (at 64.6 145.75) (size 0.5) (drill 0.2) (layers "F.Cu" "B.Cu") (net 1))
  (via blind (at 106.8 118.95) (size 0.5) (drill 0.2) (layers "F.Cu" "In1.Cu") (net 1))
  (via (at 74.99 73.14) (size 0.5) (drill 0.2) (layers "F.Cu" "B.Cu") (net 1))
  (via (at 123.15 74.2) (size 0.5) (drill 0.2) (layers "F.Cu" "B.Cu") (net 1))
  (via (at 105.48 141.83) (size 0.5) (drill 0.2) (layers "F.Cu" "B.Cu") (net 1))
  (via (at 76.25 118.75) (size 0.5) (drill 0.2) (layers "F.Cu" "B.Cu") (net 1))
  (via (at 69.700123 178.048964) (size 0.5) (drill 0.2) (layers "F.Cu" "B.Cu") (net 1))
  (via (at 77.8 175.35) (size 0.6) (drill 0.3) (layers "F.Cu" "B.Cu") (net 1))
  (via (at 140.6 175.736465) (size 0.5) (drill 0.2) (layers "F.Cu" "B.Cu") (net 1))
  (via (at 102.75 93.95) (size 0.5) (drill 0.2) (layers "F.Cu" "B.Cu") (net 1))
  (via (at 102.8 125.35) (size 0.5) (drill 0.2) (layers "F.Cu" "B.Cu") (net 1))
  (via blind (at 105.2 117.35) (size 0.5) (drill 0.2) (layers "F.Cu" "In1.Cu") (net 1))
  (via (at 105.2 115.75) (size 0.5) (drill 0.2) (layers "F.Cu" "B.Cu") (net 1))
  (via (at 127.15 112.4) (size 0.5) (drill 0.2) (layers "F.Cu" "B.Cu") (net 1))
  (via (at 97.79 173.99) (size 0.5) (drill 0.2) (layers "F.Cu" "B.Cu") (net 1))
  (via blind (at 92.4 130.15) (size 0.5) (drill 0.2) (layers "F.Cu" "In1.Cu") (net 1))
  (via (at 142.494689 60.15) (size 0.5) (drill 0.2) (layers "F.Cu" "B.Cu") (net 1))
  (via (at 84.5 128.55) (size 0.5) (drill 0.2) (layers "F.Cu" "B.Cu") (net 1))
  (via (at 148.85 110.55201) (size 0.5) (drill 0.2) (layers "F.Cu" "B.Cu") (net 1))
  (via blind (at 108.4 132.55) (size 0.5) (drill 0.2) (layers "F.Cu" "In1.Cu") (net 1))
  (via blind (at 80.685 124.955) (size 0.5) (drill 0.2) (layers "F.Cu" "In1.Cu") (net 1))
  (via (at 92.297996 132.61944) (size 0.5) (drill 0.2) (layers "F.Cu" "B.Cu") (net 1))
  (via (at 61.35 64.181066) (size 0.5) (drill 0.2) (layers "F.Cu" "B.Cu") (net 1))
  (via blind (at 109.2 121.35) (size 0.5) (drill 0.2) (layers "F.Cu" "In1.Cu") (net 1))
  (via (at 100.7 96.15) (size 0.5) (drill 0.2) (layers "F.Cu" "B.Cu") (net 1))
  (via (at 71.9 137.4) (size 0.5) (drill 0.2) (layers "F.Cu" "B.Cu") (net 1))
  (via (at 90.8 85.35) (size 0.5) (drill 0.2) (layers "F.Cu" "B.Cu") (net 1))
  (via (at 148.85 62.16608) (size 0.5) (drill 0.2) (layers "F.Cu" "B.Cu") (net 1))
  (via (at 105.2 122.95) (size 0.5) (drill 0.2) (layers "F.Cu" "B.Cu") (net 1))
  (via (at 148.85 114.584171) (size 0.5) (drill 0.2) (layers "F.Cu" "B.Cu") (net 1))
  (via (at 132.92 105.45) (size 0.5) (drill 0.2) (layers "F.Cu" "B.Cu") (net 1))
  (via (at 148.85 175.066583) (size 0.5) (drill 0.2) (layers "F.Cu" "B.Cu") (net 1))
  (via (at 89.41 66.285) (size 0.6) (drill 0.3) (layers "F.Cu" "B.Cu") (net 1))
  (via (at 72.372364 171.579299) (size 0.5) (drill 0.2) (layers "F.Cu" "B.Cu") (net 1))
  (via (at 102.8 119.75) (size 0.5) (drill 0.2) (layers "F.Cu" "B.Cu") (net 1))
  (via (at 123.45 131.4) (size 0.5) (drill 0.2) (layers "F.Cu" "B.Cu") (net 1))
  (via (at 85 113.5) (size 0.5) (drill 0.2) (layers "F.Cu" "B.Cu") (net 1))
  (via (at 148.85 158.93794) (size 0.5) (drill 0.2) (layers "F.Cu" "B.Cu") (net 1))
  (via (at 148.85 134.744975) (size 0.5) (drill 0.2) (layers "F.Cu" "B.Cu") (net 1))
  (via (at 64.6 136.9) (size 0.5) (drill 0.2) (layers "F.Cu" "B.Cu") (net 1))
  (via (at 135.7 153.65) (size 0.5) (drill 0.2) (layers "F.Cu" "B.Cu") (net 1))
  (via (at 126.45 112.4) (size 0.5) (drill 0.2) (layers "F.Cu" "B.Cu") (net 1))
  (via (at 114 122.15) (size 0.5) (drill 0.2) (layers "F.Cu" "B.Cu") (net 1))
  (via blind (at 109.2 114.95) (size 0.5) (drill 0.2) (layers "F.Cu" "In1.Cu") (net 1))
  (via (at 86.15 68.1) (size 0.6) (drill 0.3) (layers "F.Cu" "B.Cu") (net 1))
  (via (at 118.879056 82.113104) (size 0.5) (drill 0.2) (layers "F.Cu" "B.Cu") (net 1))
  (via blind (at 106 115.75) (size 0.5) (drill 0.2) (layers "F.Cu" "In1.Cu") (net 1))
  (via blind (at 106.8 117.35) (size 0.5) (drill 0.2) (layers "F.Cu" "In1.Cu") (net 1))
  (via blind (at 102 130.15) (size 0.5) (drill 0.2) (layers "F.Cu" "In1.Cu") (net 1))
  (via blind (at 97.2 131.75) (size 0.5) (drill 0.2) (layers "F.Cu" "In1.Cu") (net 1))
  (via (at 117.073446 60.15) (size 0.5) (drill 0.2) (layers "F.Cu" "B.Cu") (free) (net 1))
  (via (at 110 132.55) (size 0.5) (drill 0.2) (layers "F.Cu" "B.Cu") (net 1))
  (via (at 101.2 122.95) (size 0.5) (drill 0.2) (layers "F.Cu" "B.Cu") (net 1))
  (via (at 121.55 114.5) (size 0.5) (drill 0.2) (layers "F.Cu" "B.Cu") (net 1))
  (via (at 127.59 105.31) (size 0.5) (drill 0.2) (layers "F.Cu" "B.Cu") (net 1))
  (via (at 115.6 83.4) (size 0.5) (drill 0.2) (layers "F.Cu" "B.Cu") (net 1))
  (via (at 99.6 116.55) (size 0.5) (drill 0.2) (layers "F.Cu" "B.Cu") (net 1))
  (via (at 61.35 102.4762) (size 0.5) (drill 0.2) (layers "F.Cu" "B.Cu") (net 1))
  (via (at 106 125.35) (size 0.5) (drill 0.2) (layers "F.Cu" "B.Cu") (net 1))
  (via (at 61.35 70.227666) (size 0.5) (drill 0.2) (layers "F.Cu" "B.Cu") (net 1))
  (via (at 71.43 120.82) (size 0.5) (drill 0.2) (layers "F.Cu" "B.Cu") (net 1))
  (via (at 61.35 98.445133) (size 0.5) (drill 0.2) (layers "F.Cu" "B.Cu") (net 1))
  (via (at 105.2 118.15) (size 0.5) (drill 0.2) (layers "F.Cu" "B.Cu") (net 1))
  (via (at 136.139378 60.15) (size 0.5) (drill 0.2) (layers "F.Cu" "B.Cu") (net 1))
  (via (at 109.2 122.95) (size 0.5) (drill 0.2) (layers "F.Cu" "B.Cu") (net 1))
  (via (at 100.7 94.9) (size 0.5) (drill 0.2) (layers "F.Cu" "B.Cu") (net 1))
  (via (at 106.36 87.04) (size 0.5) (drill 0.2) (layers "F.Cu" "B.Cu") (net 1))
  (via (at 82.5 100.7) (size 0.5) (drill 0.2) (layers "F.Cu" "B.Cu") (net 1))
  (via (at 114.95501 62.510199) (size 0.5) (drill 0.2) (layers "F.Cu" "B.Cu") (net 1))
  (via (at 148.85 177.082664) (size 0.5) (drill 0.2) (layers "F.Cu" "B.Cu") (net 1))
  (via (at 81.75 131.5) (size 0.5) (drill 0.2) (layers "F.Cu" "B.Cu") (net 1))
  (via (at 121.31032 60.15) (size 0.5) (drill 0.2) (layers "F.Cu" "B.Cu") (net 1))
  (via blind (at 103.6 121.35) (size 0.5) (drill 0.2) (layers "F.Cu" "In1.Cu") (net 1))
  (via (at 74.307107 172.192893) (size 0.5) (drill 0.2) (layers "F.Cu" "B.Cu") (net 1))
  (via (at 148.29047 178.09999) (size 0.5) (drill 0.2) (layers "F.Cu" "B.Cu") (net 1))
  (via (at 96.4 132.55) (size 0.5) (drill 0.2) (layers "F.Cu" "B.Cu") (net 1))
  (via blind (at 106.8 123.75) (size 0.5) (drill 0.2) (layers "F.Cu" "In1.Cu") (net 1))
  (via (at 109.3 175.425) (size 0.6) (drill 0.3) (layers "F.Cu" "B.Cu") (net 1))
  (via (at 122.38 100.71) (size 0.5) (drill 0.2) (layers "F.Cu" "B.Cu") (net 1))
  (via (at 61.35 142.786867) (size 0.5) (drill 0.2) (layers "F.Cu" "B.Cu") (net 1))
  (via (at 114 111.75) (size 0.5) (drill 0.2) (layers "F.Cu" "B.Cu") (net 1))
  (via (at 83.15 137.45) (size 0.5) (drill 0.2) (layers "F.Cu" "B.Cu") (net 1))
  (via (at 61.35 173.019867) (size 0.5) (drill 0.2) (layers "F.Cu" "B.Cu") (net 1))
  (via (at 122.05 129.975) (size 0.5) (drill 0.2) (layers "F.Cu" "B.Cu") (net 1))
  (via (at 144.32 133.8) (size 0.5) (drill 0.2) (layers "F.Cu" "B.Cu") (net 1))
  (via (at 65.63 167.03) (size 0.5) (drill 0.2) (layers "F.Cu" "B.Cu") (net 1))
  (via (at 70.420001 120.770001) (size 0.5) (drill 0.2) (layers "F.Cu" "B.Cu") (net 1))
  (via (at 95.6 122.15) (size 0.5) (drill 0.2) (layers "F.Cu" "B.Cu") (net 1))
  (via (at 114.95501 64.870398) (size 0.5) (drill 0.2) (layers "F.Cu" "B.Cu") (net 1))
  (via (at 141.09 105.37) (size 0.5) (drill 0.2) (layers "F.Cu" "B.Cu") (net 1))
  (via (at 61.35 160.926667) (size 0.5) (drill 0.2) (layers "F.Cu" "B.Cu") (net 1))
  (via (at 61.35 60.15) (size 0.5) (drill 0.2) (layers "F.Cu" "B.Cu") (net 1))
  (via (at 61.35 132.7092) (size 0.5) (drill 0.2) (layers "F.Cu" "B.Cu") (net 1))
  (via blind (at 96.4 130.15) (size 0.5) (drill 0.2) (layers "F.Cu" "In1.Cu") (net 1))
  (via (at 99.6 118.95) (size 0.5) (drill 0.2) (layers "F.Cu" "B.Cu") (net 1))
  (via blind (at 80.7 122.55) (size 0.5) (drill 0.2) (layers "F.Cu" "In1.Cu") (net 1))
  (via (at 106 118.15) (size 0.5) (drill 0.2) (layers "F.Cu" "B.Cu") (net 1))
  (via blind (at 87.4 124.15) (size 0.5) (drill 0.2) (layers "F.Cu" "In1.Cu") (net 1))
  (via (at 135.707634 172.801953) (size 0.5) (drill 0.2) (layers "F.Cu" "B.Cu") (net 1))
  (via (at 106.8 125.35) (size 0.5) (drill 0.2) (layers "F.Cu" "B.Cu") (net 1))
  (via (at 105 133.55) (size 0.5) (drill 0.2) (layers "F.Cu" "B.Cu") (net 1))
  (via (at 74.43 126.05) (size 0.5) (drill 0.2) (layers "F.Cu" "B.Cu") (net 1))
  (via (at 121.5 118.8) (size 0.5) (drill 0.2) (layers "F.Cu" "B.Cu") (net 1))
  (via (at 114.43 101.85) (size 0.5) (drill 0.2) (layers "F.Cu" "B.Cu") (net 1))
  (via (at 127.45 60.25) (size 0.5) (drill 0.2) (layers "F.Cu" "B.Cu") (net 1))
  (via (at 87.5 115.8) (size 0.5) (drill 0.2) (layers "F.Cu" "B.Cu") (net 1))
  (via blind (at 109.2 119.75) (size 0.5) (drill 0.2) (layers "F.Cu" "In1.Cu") (net 1))
  (via (at 116.1 73.555732) (size 0.5) (drill 0.2) (layers "F.Cu" "B.Cu") (net 1))
  (via (at 106 119.75) (size 0.5) (drill 0.2) (layers "F.Cu" "B.Cu") (net 1))
  (via (at 114.8 132.55) (size 0.5) (drill 0.2) (layers "F.Cu" "B.Cu") (net 1))
  (via (at 61.35 62.165533) (size 0.5) (drill 0.2) (layers "F.Cu" "B.Cu") (net 1))
  (via (at 76.3 136.85) (size 0.5) (drill 0.2) (layers "F.Cu" "B.Cu") (net 1))
  (via (at 115.27 150.24) (size 0.5) (drill 0.2) (layers "F.Cu" "B.Cu") (net 1))
  (via (at 93.98 173.99) (size 0.5) (drill 0.2) (layers "F.Cu" "B.Cu") (net 1))
  (via (at 115.6 82.5) (size 0.5) (drill 0.2) (layers "F.Cu" "B.Cu") (net 1))
  (via (at 139 87.8) (size 0.5) (drill 0.2) (layers "F.Cu" "B.Cu") (net 1))
  (via (at 103.6 129.35) (size 0.5) (drill 0.2) (layers "F.Cu" "B.Cu") (net 1))
  (via (at 148.85 173.050503) (size 0.5) (drill 0.2) (layers "F.Cu" "B.Cu") (net 1))
  (via blind (at 105.2 119.75) (size 0.5) (drill 0.2) (layers "F.Cu" "In1.Cu") (net 1))
  (via (at 148.85 68.214321) (size 0.5) (drill 0.2) (layers "F.Cu" "B.Cu") (net 1))
  (via (at 111.5 118.9) (size 0.5) (drill 0.2) (layers "F.Cu" "B.Cu") (net 1))
  (via (at 140.35 166.2) (size 0.5) (drill 0.2) (layers "F.Cu" "B.Cu") (net 1))
  (via (at 122.025 131.45) (size 0.5) (drill 0.2) (layers "F.Cu" "B.Cu") (net 1))
  (via (at 111.5 113.85) (size 0.5) (drill 0.2) (layers "F.Cu" "B.Cu") (net 1))
  (via blind (at 105.2 121.35) (size 0.5) (drill 0.2) (layers "F.Cu" "In1.Cu") (net 1))
  (via (at 102 125.35) (size 0.5) (drill 0.2) (layers "F.Cu" "B.Cu") (net 1))
  (via (at 148.85 132.728894) (size 0.5) (drill 0.2) (layers "F.Cu" "B.Cu") (net 1))
  (via (at 148.85 82.326884) (size 0.5) (drill 0.2) (layers "F.Cu" "B.Cu") (net 1))
  (via (at 130.48 148.43) (size 0.5) (drill 0.2) (layers "F.Cu" "B.Cu") (net 1))
  (via (at 61.35 175.0354) (size 0.5) (drill 0.2) (layers "F.Cu" "B.Cu") (net 1))
  (via (at 112.4 122.95) (size 0.5) (drill 0.2) (layers "F.Cu" "B.Cu") (net 1))
  (via (at 86.8 97.1) (size 0.5) (drill 0.2) (layers "F.Cu" "B.Cu") (net 1))
  (via (at 102.8 118.15) (size 0.5) (drill 0.2) (layers "F.Cu" "B.Cu") (net 1))
  (via (at 100.75 112.6) (size 0.5) (drill 0.2) (layers "F.Cu" "B.Cu") (net 1))
  (via (at 124.925 65.65) (size 0.5) (drill 0.2) (layers "F.Cu" "B.Cu") (net 1))
  (via (at 140.6 173.487145) (size 0.5) (drill 0.2) (layers "F.Cu" "B.Cu") (net 1))
  (via (at 148.85 118.616332) (size 0.5) (drill 0.2) (layers "F.Cu" "B.Cu") (net 1))
  (via (at 61.35 164.957733) (size 0.5) (drill 0.2) (layers "F.Cu" "B.Cu") (net 1))
  (via (at 148.85 70.230402) (size 0.5) (drill 0.2) (layers "F.Cu" "B.Cu") (net 1))
  (via (at 93.9 71.65) (size 0.5) (drill 0.2) (layers "F.Cu" "B.Cu") (net 1))
  (via (at 148.85 171.034422) (size 0.5) (drill 0.2) (layers "F.Cu" "B.Cu") (net 1))
  (via (at 112.575 175.325) (size 0.6) (drill 0.3) (layers "F.Cu" "B.Cu") (net 1))
  (via (at 145.765048 178.09999) (size 0.5) (drill 0.2) (layers "F.Cu" "B.Cu") (net 1))
  (via (at 130.375 175.75) (size 0.6) (drill 0.3) (layers "F.Cu" "B.Cu") (net 1))
  (via (at 61.35 140.771333) (size 0.5) (drill 0.2) (layers "F.Cu" "B.Cu") (net 1))
  (via (at 74.35 123.25) (size 0.5) (drill 0.2) (layers "F.Cu" "B.Cu") (net 1))
  (via blind (at 107.6 121.35) (size 0.5) (drill 0.2) (layers "F.Cu" "In1.Cu") (net 1))
  (via (at 113.2 119.75) (size 0.5) (drill 0.2) (layers "F.Cu" "B.Cu") (net 1))
  (via (at 99.6 130.95) (size 0.5) (drill 0.2) (layers "F.Cu" "B.Cu") (net 1))
  (via (at 61.35 112.553866) (size 0.5) (drill 0.2) (layers "F.Cu" "B.Cu") (net 1))
  (via (at 148.85 66.198241) (size 0.5) (drill 0.2) (layers "F.Cu" "B.Cu") (net 1))
  (via (at 148.85 84.342964) (size 0.5) (drill 0.2) (layers "F.Cu" "B.Cu") (net 1))
  (via (at 137 87.8) (size 0.5) (drill 0.2) (layers "F.Cu" "B.Cu") (net 1))
  (via (at 102.8 118.95) (size 0.5) (drill 0.2) (layers "F.Cu" "B.Cu") (net 1))
  (via (at 61.35 122.631533) (size 0.5) (drill 0.2) (layers "F.Cu" "B.Cu") (net 1))
  (via (at 146.32 148.27) (size 0.5) (drill 0.2) (layers "F.Cu" "B.Cu") (net 1))
  (via blind (at 105.2 131.75) (size 0.5) (drill 0.2) (layers "F.Cu" "In1.Cu") (net 1))
  (via (at 61.35 74.258733) (size 0.5) (drill 0.2) (layers "F.Cu" "B.Cu") (net 1))
  (via (at 64.12 159.05) (size 0.5) (drill 0.2) (layers "F.Cu" "B.Cu") (net 1))
  (via blind (at 104.4 129.35) (size 0.5) (drill 0.2) (layers "F.Cu" "In1.Cu") (net 1))
  (via (at 107.6 115.75) (size 0.5) (drill 0.2) (layers "F.Cu" "B.Cu") (net 1))
  (via (at 96.8 95.95) (size 0.5) (drill 0.2) (layers "F.Cu" "B.Cu") (net 1))
  (via (at 125.000002 115.8) (size 0.5) (drill 0.2) (layers "F.Cu" "B.Cu") (net 1))
  (via blind (at 106.8 122.15) (size 0.5) (drill 0.2) (layers "F.Cu" "In1.Cu") (net 1))
  (via (at 99.6 121.35) (size 0.5) (drill 0.2) (layers "F.Cu" "B.Cu") (net 1))
  (via (at 107.6 125.35) (size 0.5) (drill 0.2) (layers "F.Cu" "B.Cu") (net 1))
  (via (at 93.9 72.3) (size 0.5) (drill 0.2) (layers "F.Cu" "B.Cu") (net 1))
  (via (at 61.35 86.351933) (size 0.5) (drill 0.2) (layers "F.Cu" "B.Cu") (net 1))
  (via (at 79.885 125.755) (size 0.5) (drill 0.2) (layers "F.Cu" "B.Cu") (net 1))
  (via (at 125.88 140.86) (size 0.5) (drill 0.2) (layers "F.Cu" "B.Cu") (net 1))
  (via (at 122.28 90.87) (size 0.5) (drill 0.2) (layers "F.Cu" "B.Cu") (net 1))
  (via (at 139 92.4) (size 0.5) (drill 0.2) (layers "F.Cu" "B.Cu") (net 1))
  (via (at 106.8 129.35) (size 0.5) (drill 0.2) (layers "F.Cu" "B.Cu") (net 1))
  (via (at 101.2 128.55) (size 0.5) (drill 0.2) (layers "F.Cu" "B.Cu") (net 1))
  (via (at 107.6 123.75) (size 0.5) (drill 0.2) (layers "F.Cu" "B.Cu") (net 1))
  (via (at 61.35 106.507266) (size 0.5) (drill 0.2) (layers "F.Cu" "B.Cu") (net 1))
  (via (at 123.428757 60.15) (size 0.5) (drill 0.2) (layers "F.Cu" "B.Cu") (net 1))
  (via (at 140.6 177.985786) (size 0.5) (drill 0.2) (layers "F.Cu" "B.Cu") (net 1))
  (via (at 78.15 122.45) (size 0.5) (drill 0.2) (layers "F.Cu" "B.Cu") (net 1))
  (via (at 61.35 76.274266) (size 0.5) (drill 0.2) (layers "F.Cu" "B.Cu") (net 1))
  (via (at 148.85 124.664573) (size 0.5) (drill 0.2) (layers "F.Cu" "B.Cu") (net 1))
  (via blind (at 101.2 119.75) (size 0.5) (drill 0.2) (layers "F.Cu" "In1.Cu") (net 1))
  (via (at 84.8 85.35) (size 0.5) (drill 0.2) (layers "F.Cu" "B.Cu") (net 1))
  (via (at 119.25 74.225) (size 0.5) (drill 0.2) (layers "F.Cu" "B.Cu") (net 1))
  (via (at 61.35 96.4296) (size 0.5) (drill 0.2) (layers "F.Cu" "B.Cu") (net 1))
  (via (at 148.85 74.262562) (size 0.5) (drill 0.2) (layers "F.Cu" "B.Cu") (net 1))
  (via (at 81 110.16) (size 0.5) (drill 0.2) (layers "F.Cu" "B.Cu") (net 1))
  (via (at 96.4 126.95) (size 0.5) (drill 0.2) (layers "F.Cu" "B.Cu") (net 1))
  (via blind (at 101.2 125.35) (size 0.5) (drill 0.2) (layers "F.Cu" "In1.Cu") (net 1))
  (via (at 131.902505 60.15) (size 0.5) (drill 0.2) (layers "F.Cu" "B.Cu") (net 1))
  (via (at 148.85 150.873618) (size 0.5) (drill 0.2) (layers "F.Cu" "B.Cu") (net 1))
  (via blind (at 99.6 124.55) (size 0.5) (drill 0.2) (layers "F.Cu" "In1.Cu") (net 1))
  (via (at 114 109.35) (size 0.5) (drill 0.2) (layers "F.Cu" "B.Cu") (net 1))
  (via (at 101.2 110.95) (size 0.5) (drill 0.2) (layers "F.Cu" "B.Cu") (net 1))
  (via (at 114.55 116.9) (size 0.5) (drill 0.2) (layers "F.Cu" "B.Cu") (net 1))
  (via (at 72.7 86.2) (size 0.5) (drill 0.2) (layers "F.Cu" "B.Cu") (net 1))
  (via (at 139.631781 171.646985) (size 0.5) (drill 0.2) (layers "F.Cu" "B.Cu") (net 1))
  (via (at 72.7 83.5) (size 0.5) (drill 0.2) (layers "F.Cu" "B.Cu") (net 1))
  (via (at 61.35 92.398533) (size 0.5) (drill 0.2) (layers "F.Cu" "B.Cu") (net 1))
  (via (at 107.6 117.35) (size 0.5) (drill 0.2) (layers "F.Cu" "B.Cu") (net 1))
  (via (at 68.3 84.1) (size 0.5) (drill 0.2) (layers "F.Cu" "B.Cu") (net 1))
  (via (at 103.6 128.55) (size 0.5) (drill 0.2) (layers "F.Cu" "B.Cu") (net 1))
  (via blind (at 100.4 126.15) (size 0.5) (drill 0.2) (layers "F.Cu" "In1.Cu") (net 1))
  (via (at 137.389824 171.584891) (size 0.5) (drill 0.2) (layers "F.Cu" "B.Cu") (net 1))
  (via blind (at 101.2 117.35) (size 0.5) (drill 0.2) (layers "F.Cu" "In1.Cu") (net 1))
  (via (at 107.60001 111.72533) (size 0.5) (drill 0.2) (layers "F.Cu" "B.Cu") (net 1))
  (via (at 134.72 144.68) (size 0.5) (drill 0.2) (layers "F.Cu" "B.Cu") (net 1))
  (via (at 107.28501 100) (size 0.5) (drill 0.2) (layers "F.Cu" "B.Cu") (net 1))
  (via (at 86.8 99.1) (size 0.5) (drill 0.2) (layers "F.Cu" "B.Cu") (net 1))
  (via (at 61.35 90.383) (size 0.5) (drill 0.2) (layers "F.Cu" "B.Cu") (net 1))
  (via (at 148.85 116.600251) (size 0.5) (drill 0.2) (layers "F.Cu" "B.Cu") (net 1))
  (via (at 142.19 152.76) (size 0.5) (drill 0.2) (layers "F.Cu" "B.Cu") (net 1))
  (via (at 99.6 119.75) (size 0.5) (drill 0.2) (layers "F.Cu" "B.Cu") (net 1))
  (via (at 61.35 148.833467) (size 0.5) (drill 0.2) (layers "F.Cu" "B.Cu") (net 1))
  (via (at 148.85 92.407286) (size 0.5) (drill 0.2) (layers "F.Cu" "B.Cu") (net 1))
  (via (at 110.2 98.75) (size 0.5) (drill 0.2) (layers "F.Cu" "B.Cu") (net 1))
  (via (at 79.885 124.955) (size 0.5) (drill 0.2) (layers "F.Cu" "B.Cu") (net 1))
  (segment (start 86.8 94.115) (end 86.3 94.615) (width 0.25) (layer "B.Cu") (net 1))
  (segment (start 109.4 133.95) (end 109.4 133.2) (width 0.15) (layer "B.Cu") (net 1))
  (segment (start 76.3 94.3) (end 76.3 93.425) (width 0.3) (layer "B.Cu") (net 1))
  (segment (start 94.515 82.51) (end 93.64 82.51) (width 0.25) (layer "B.Cu") (net 1))
  (segment (start 94.515 83.51) (end 93.64 83.51) (width 0.25) (layer "B.Cu") (net 1))
  (segment (start 135.385 93.925) (end 135.385 94.81) (width 0.15) (layer "B.Cu") (net 1))
  (segment (start 135.385 94.81) (end 135.4 94.825) (width 0.15) (layer "B.Cu") (net 1))
  (segment (start 137.985 93.875) (end 137.985 94.86) (width 0.15) (layer "B.Cu") (net 1))
  (segment (start 137.985 94.86) (end 138 94.875) (width 0.15) (layer "B.Cu") (net 1))
  (segment (start 138.65 84.16) (end 138.65 84.775) (width 0.15) (layer "B.Cu") (net 1))
  (segment (start 138.65 84.775) (end 138.75 84.875) (width 0.15) (layer "B.Cu") (net 1))
  (segment (start 144.675 86.94) (end 144.675 86.125) (width 0.2) (layer "B.Cu") (net 1))
  (segment (start 131.9 89.025) (end 131.9 89.775) (width 0.2) (layer "B.Cu") (net 1))
  (segment (start 136.1 86.81) (end 135.185 86.81) (width 0.2) (layer "B.Cu") (net 1))
  (segment (start 135.1 86.81) (end 134.115 86.81) (width 0.2) (layer "B.Cu") (net 1))
  (segment (start 137.1 86.81) (end 138.085 86.81) (width 0.2) (layer "B.Cu") (net 1))
  (segment (start 139.1 86.81) (end 138.115 86.81) (width 0.2) (layer "B.Cu") (net 1))
  (segment (start 139.5 94.775) (end 139.5 93.925) (width 0.2) (layer "B.Cu") (net 1))
  (segment (start 140.8 84.125) (end 141.55 83.375) (width 0.2) (layer "B.Cu") (net 1))
  (segment (start 141.55 83.375) (end 141.55 82.575) (width 0.2) (layer "B.Cu") (net 1))
  (segment (start 110.2 98.75) (end 109.55 98.75) (width 0.2) (layer "B.Cu") (net 1))
  (segment (start 105.75 96.45) (end 105.75 97.6) (width 0.2) (layer "B.Cu") (net 1))
  (segment (start 96.815 95.2) (end 96.815 95.935) (width 0.3) (layer "B.Cu") (net 1))
  (segment (start 140.1 88.24) (end 139.965 88.375) (width 0.2) (layer "B.Cu") (net 1))
  (segment (start 112.4 119.75) (end 111.8 119.75) (width 0.15) (layer "B.Cu") (net 1))
  (segment (start 139 89.8) (end 139.905 89.8) (width 0.25) (layer "B.Cu") (net 1))
  (segment (start 136 86.91) (end 136.1 86.81) (width 0.25) (layer "B.Cu") (net 1))
  (segment (start 106 111.75) (end 106 112.75) (width 0.15) (layer "B.Cu") (net 1))
  (segment (start 121.965 122.45) (end 121.965 124.135) (width 0.2) (layer "B.Cu") (net 1))
  (segment (start 105.815 117.535) (end 106 117.35) (width 0.15) (layer "B.Cu") (net 1))
  (segment (start 86.65 120.5) (end 87.1 120.95) (width 0.15) (layer "B.Cu") (net 1))
  (segment (start 110.7 133.55) (end 110.7 132.8) (width 0.15) (layer "B.Cu") (net 1))
  (segment (start 99.7 133.85) (end 99.9 134.05) (width 0.15) (layer "B.Cu") (net 1))
  (segment (start 109.8 95.65) (end 110.2 96.05) (width 0.2) (layer "B.Cu") (net 1))
  (segment (start 100.75 112.6) (end 100.75 113.3) (width 0.15) (layer "B.Cu") (net 1))
  (segment (start 109.29 177.345) (end 109.29 175.435) (width 0.3) (layer "B.Cu") (net 1))
  (segment (start 86.3 126.6) (end 86.3 127.2) (width 0.15) (layer "B.Cu") (net 1))
  (segment (start 97.115 115.585) (end 97.65 115.05) (width 0.2) (layer "B.Cu") (net 1))
  (segment (start 106.685 115.635) (end 106.8 115.75) (width 0.15) (layer "B.Cu") (net 1))
  (segment (start 133.675 89.775) (end 131.9 89.775) (width 0.25) (layer "B.Cu") (net 1))
  (segment (start 79.885 125.755) (end 80.09 125.55) (width 0.15) (layer "B.Cu") (net 1))
  (segment (start 108.65 119.2) (end 108.65 119.6) (width 0.15) (layer "B.Cu") (net 1))
  (segment (start 98.5 132.7) (end 98.5 133.45) (width 0.15) (layer "B.Cu") (net 1))
  (segment (start 82.565 97.465) (end 82.55 97.45) (width 0.3) (layer "B.Cu") (net 1))
  (segment (start 111.685 117.1) (end 111.685 118.715) (width 0.15) (layer "B.Cu") (net 1))
  (segment (start 106.9 130.15) (end 107.45 130.15) (width 0.15) (layer "B.Cu") (net 1))
  (segment (start 97.115 126.65) (end 96.7 126.65) (width 0.15) (layer "B.Cu") (net 1))
  (segment (start 105.2 123.565) (end 105.815 123.565) (width 0.15) (layer "B.Cu") (net 1))
  (segment (start 128.585 177.37) (end 128.585 175.775) (width 0.2) (layer "B.Cu") (net 1))
  (segment (start 107.45 112.6) (end 108 113.15) (width 0.15) (layer "B.Cu") (net 1))
  (segment (start 81.69 177.345) (end 81.69 175.81) (width 0.3) (layer "B.Cu") (net 1))
  (segment (start 72.25 90.1) (end 71.35 90.1) (width 0.2) (layer "B.Cu") (net 1))
  (segment (start 84.8 120.925) (end 85.225 120.5) (width 0.15) (layer "B.Cu") (net 1))
  (segment (start 104.4 115.635) (end 105.085 115.635) (width 0.15) (layer "B.Cu") (net 1))
  (segment (start 130.385 175.76) (end 130.375 175.75) (width 0.2) (layer "B.Cu") (net 1))
  (segment (start 111.735 123.75) (end 112.4 123.75) (width 0.15) (layer "B.Cu") (net 1))
  (segment (start 97.115 125.65) (end 97.115 126.665) (width 0.15) (layer "B.Cu") (net 1))
  (segment (start 110.985 114.365) (end 111.5 113.85) (width 0.3) (layer "B.Cu") (net 1))
  (segment (start 93.89 174.08) (end 93.98 173.99) (width 0.3) (layer "B.Cu") (net 1))
  (segment (start 86.8 100.115) (end 86.3 100.615) (width 0.25) (layer "B.Cu") (net 1))
  (segment (start 93.2 122.15) (end 92.3 122.15) (width 0.2) (layer "B.Cu") (net 1))
  (segment (start 112.4 122.15) (end 112.2 122.15) (width 0.15) (layer "B.Cu") (net 1))
  (segment (start 108.885 117.035) (end 109.2 117.35) (width 0.15) (layer "B.Cu") (net 1))
  (segment (start 75.69 177.345) (end 75.69 175.41) (width 0.3) (layer "B.Cu") (net 1))
  (segment (start 127.75 131.275) (end 127.75 130.9) (width 0.2) (layer "B.Cu") (net 1))
  (segment (start 109.2 122.95) (end 109.2 122.45) (width 0.15) (layer "B.Cu") (net 1))
  (segment (start 95.9 128.75) (end 95.65 128.5) (width 0.15) (layer "B.Cu") (net 1))
  (segment (start 105.95 115.635) (end 106.685 115.635) (width 0.15) (layer "B.Cu") (net 1))
  (segment (start 106.85 123) (end 106.8 122.95) (width 0.15) (layer "B.Cu") (net 1))
  (segment (start 106.75 117.535) (end 106.75 118.1) (width 0.15) (layer "B.Cu") (net 1))
  (segment (start 100.7 94.9) (end 100.7 94.25) (width 0.2) (layer "B.Cu") (net 1))
  (segment (start 124.15 130.7) (end 123.45 131.4) (width 0.2) (layer "B.Cu") (net 1))
  (segment (start 108.23 125.5) (end 108.23 125.98) (width 0.15) (layer "B.Cu") (net 1))
  (segment (start 99.608716 129.34929) (end 99.609426 129.35) (width 0.15) (layer "B.Cu") (net 1))
  (segment (start 136.1 86.81) (end 137.1 86.81) (width 0.2) (layer "B.Cu") (net 1))
  (segment (start 105.085 115.635) (end 105.2 115.75) (width 0.15) (layer "B.Cu") (net 1))
  (segment (start 105.75 96.45) (end 105.75 95.7) (width 0.2) (layer "B.Cu") (net 1))
  (segment (start 105.55 127.885) (end 105.55 128.3) (width 0.15) (layer "B.Cu") (net 1))
  (segment (start 88 99.3) (end 87.8 99.1) (width 0.15) (layer "B.Cu") (net 1))
  (segment (start 110.2 96.05) (end 110.2 96.2) (width 0.2) (layer "B.Cu") (net 1))
  (segment (start 134.1 86.81) (end 134.1 89.35) (width 0.25) (layer "B.Cu") (net 1))
  (segment (start 112.765 130.485) (end 113.1 130.15) (width 0.15) (layer "B.Cu") (net 1))
  (segment (start 104.4 130.95) (end 104.4 130.25) (width 0.15) (layer "B.Cu") (net 1))
  (segment (start 122.04 130.7) (end 122.04 131.435) (width 0.2) (layer "B.Cu") (net 1))
  (segment (start 139 86.91) (end 139.1 86.81) (width 0.25) (layer "B.Cu") (net 1))
  (segment (start 78 125.2) (end 78 125.95) (width 0.15) (layer "B.Cu") (net 1))
  (segment (start 86.6 102.8) (end 87.43 102.8) (width 0.15) (layer "B.Cu") (net 1))
  (segment (start 111.6 132.55) (end 111.7 132.55) (width 0.15) (layer "B.Cu") (net 1))
  (segment (start 101.55 127.885) (end 101.55 128.2) (width 0.15) (layer "B.Cu") (net 1))
  (segment (start 96.4 131.75) (end 96.4 130.75) (width 0.15) (layer "B.Cu") (net 1))
  (segment (start 107.45 111.87534) (end 107.60001 111.72533) (width 0.15) (layer "B.Cu") (net 1))
  (segment (start 139.1 86.81) (end 140.1 86.81) (width 0.2) (layer "B.Cu") (net 1))
  (segment (start 108.23 125.98) (end 108.4 126.15) (width 0.15) (layer "B.Cu") (net 1))
  (segment (start 83.25 120.05) (end 83.25 120.45) (width 0.1) (layer "B.Cu") (net 1))
  (segment (start 112.2 122.15) (end 111.75 121.7) (width 0.15) (layer "B.Cu") (net 1))
  (segment (start 86.8 97.115) (end 86.3 97.615) (width 0.25) (layer "B.Cu") (net 1))
  (segment (start 104.3125 122.2375) (end 104.4875 122.2375) (width 0.15) (layer "B.Cu") (net 1))
  (segment (start 97.225 123.725) (end 97.5 124) (width 0.15) (layer "B.Cu") (net 1))
  (segment (start 68.3 90.05) (end 68.3 89.15) (width 0.3) (layer "B.Cu") (net 1))
  (segment (start 97.65 115.05) (end 98.765 115.05) (width 0.2) (layer "B.Cu") (net 1))
  (segment (start 88.7 99.3) (end 88 99.3) (width 0.15) (layer "B.Cu") (net 1))
  (segment (start 110.2 94.25) (end 110.2 93.7) (width 0.2) (layer "B.Cu") (net 1))
  (segment (start 112.4 120.55) (end 111.85 120.55) (width 0.15) (layer "B.Cu") (net 1))
  (segment (start 105.8 128.55) (end 106 128.55) (width 0.15) (layer "B.Cu") (net 1))
  (segment (start 114.69 177.345) (end 114.69 175.91) (width 0.3) (layer "B.Cu") (net 1))
  (segment (start 102 99) (end 101 99) (width 0.2) (layer "B.Cu") (net 1))
  (segment (start 105.2 93.95) (end 104.6 93.95) (width 0.2) (layer "B.Cu") (net 1))
  (segment (start 104.4 128.55) (end 104.4 128.035) (width 0.15) (layer "B.Cu") (net 1))
  (segment (start 106.665 119.885) (end 106.8 119.75) (width 0.15) (layer "B.Cu") (net 1))
  (segment (start 137 86.91) (end 137.1 86.81) (width 0.25) (layer "B.Cu") (net 1))
  (segment (start 105.2 90.15) (end 105.8 90.15) (width 0.2) (layer "B.Cu") (net 1))
  (segment (start 135.785 177.37) (end 135.785 175.725) (width 0.2) (layer "B.Cu") (net 1))
  (segment (start 98.8 113.35) (end 98.75 113.4) (width 0.15) (layer "B.Cu") (net 1))
  (segment (start 133.985 177.37) (end 133.985 175.725) (width 0.2) (layer "B.Cu") (net 1))
  (segment (start 98.5 133.45) (end 98.6 133.55) (width 0.15) (layer "B.Cu") (net 1))
  (segment (start 83.31 100.705) (end 82.505 100.705) (width 0.3) (layer "B.Cu") (net 1))
  (segment (start 114.8 83.4) (end 115.6 83.4) (width 0.25) (layer "B.Cu") (net 1))
  (segment (start 106.615 118.335) (end 106.8 118.15) (width 0.15) (layer "B.Cu") (net 1))
  (segment (start 111.735 125.8) (end 112.75 125.8) (width 0.15) (layer "B.Cu") (net 1))
  (segment (start 105 133.55) (end 105 132.8) (width 0.15) (layer "B.Cu") (net 1))
  (segment (start 68.05 94.2) (end 67.175 94.2) (width 0.3) (layer "B.Cu") (net 1))
  (segment (start 139.965 88.375) (end 139.965 89.74) (width 0.2) (layer "B.Cu") (net 1))
  (segment (start 93.115 122.95) (end 92.4 122.95) (width 0.15) (layer "B.Cu") (net 1))
  (segment (start 110.035 114.95) (end 110.9 114.95) (width 0.15) (layer "B.Cu") (net 1))
  (segment (start 97.3 119.75) (end 97.3 119.4) (width 0.1) (layer "B.Cu") (net 1))
  (segment (start 104.4 111.75) (end 104.4 112.75) (width 0.15) (layer "B.Cu") (net 1))
  (segment (start 101.95 117.535) (end 102.615 117.535) (width 0.15) (layer "B.Cu") (net 1))
  (segment (start 102 99) (end 102.95 99) (width 0.2) (layer "B.Cu") (net 1))
  (segment (start 103.6 130.15) (end 103 130.15) (width 0.15) (layer "B.Cu") (net 1))
  (segment (start 121.55 115.2) (end 121.55 114.5) (width 0.3) (layer "B.Cu") (net 1))
  (segment (start 106.8 130.15) (end 106.9 130.15) (width 0.15) (layer "B.Cu") (net 1))
  (segment (start 103.35 133.5) (end 102.95 133.1) (width 0.15) (layer "B.Cu") (net 1))
  (segment (start 106.8 128.55) (end 107.35 128.55) (width 0.15) (layer "B.Cu") (net 1))
  (segment (start 100.585 97.95) (end 100.585 96.265) (width 0.2) (layer "B.Cu") (net 1))
  (segment (start 102.635 93.835) (end 102.75 93.95) (width 0.2) (layer "B.Cu") (net 1))
  (segment (start 96.4 122.15) (end 96.55 122.3) (width 0.15) (layer "B.Cu") (net 1))
  (segment (start 107.45 112.6) (end 107.45 111.87534) (width 0.15) (layer "B.Cu") (net 1))
  (segment (start 102.8 111.75) (end 102.8 113.3) (width 0.15) (layer "B.Cu") (net 1))
  (segment (start 103.95 133.5) (end 103.95 132.75) (width 0.15) (layer "B.Cu") (net 1))
  (segment (start 101.55 128.2) (end 101.2 128.55) (width 0.15) (layer "B.Cu") (net 1))
  (segment (start 101.885 119.635) (end 102 119.75) (width 0.15) (layer "B.Cu") (net 1))
  (segment (start 102.55 128.3) (end 102.8 128.55) (width 0.15) (layer "B.Cu") (net 1))
  (segment (start 87.75 121.115) (end 87.265 121.115) (width 0.15) (layer "B.Cu") (net 1))
  (segment (start 85.225 120.5) (end 86.65 120.5) (width 0.15) (layer "B.Cu") (net 1))
  (segment (start 103.6 129.35) (end 102.9 129.35) (width 0.15) (layer "B.Cu") (net 1))
  (segment (start 98.75 113.4) (end 98.75 114.05) (width 0.15) (layer "B.Cu") (net 1))
  (segment (start 79.05 126.265) (end 79.375 126.265) (width 0.15) (layer "B.Cu") (net 1))
  (segment (start 86.8 99.115) (end 86.3 99.615) (width 0.25) (layer "B.Cu") (net 1))
  (segment (start 129.11 118.55) (end 129.85 118.55) (width 0.2) (layer "B.Cu") (net 1))
  (segment (start 79.885 128.955) (end 79.64 129.2) (width 0.15) (layer "B.Cu") (net 1))
  (segment (start 109.435 94.6) (end 109.85 94.6) (width 0.2) (layer "B.Cu") (net 1))
  (segment (start 121.95 124.15) (end 122.7 124.15) (width 0.2) (layer "B.Cu") (net 1))
  (segment (start 136 87.8) (end 136 86.91) (width 0.25) (layer "B.Cu") (net 1))
  (segment (start 122.04 131.435) (end 122.025 131.45) (width 0.2) (layer "B.Cu") (net 1))
  (segment (start 84.8 128.25) (end 85.415 128.25) (width 0.2) (layer "B.Cu") (net 1))
  (segment (start 108.615 118.15) (end 108.615 118.735) (width 0.15) (layer "B.Cu") (net 1))
  (segment (start 139.94 88.4) (end 139.965 88.375) (width 0.25) (layer "B.Cu") (net 1))
  (segment (start 104.05 99.05) (end 105.05 99.05) (width 0.2) (layer "B.Cu") (net 1))
  (segment (start 101.885 122.835) (end 102 122.95) (width 0.15) (layer "B.Cu") (net 1))
  (segment (start 78.15 122.45) (end 78.15 123.2) (width 0.15) (layer "B.Cu") (net 1))
  (segment (start 79.05 125.185) (end 78.015 125.185) (width 0.15) (layer "B.Cu") (net 1))
  (segment (start 105.2 90.15) (end 104.55 90.15) (width 0.2) (layer "B.Cu") (net 1))
  (segment (start 88.1 116.45784) (end 88.84216 116.45784) (width 0.15) (layer "B.Cu") (net 1))
  (segment (start 104 99) (end 104.05 99.05) (width 0.2) (layer "B.Cu") (net 1))
  (segment (start 82.115 131.135) (end 81.75 131.5) (width 0.3) (layer "B.Cu") (net 1))
  (segment (start 130.15 114.55) (end 130.15 114) (width 0.2) (layer "B.Cu") (net 1))
  (segment (start 106.8 129.35) (end 107.5 129.35) (width 0.15) (layer "B.Cu") (net 1))
  (segment (start 106.85 123.565) (end 106.85 123) (width 0.15) (layer "B.Cu") (net 1))
  (segment (start 90.99 97.9) (end 91.8 97.09) (width 0.15) (layer "B.Cu") (net 1))
  (segment (start 109.2 124.55) (end 108.415 124.55) (width 0.15) (layer "B.Cu") (net 1))
  (segment (start 104 99) (end 104 99.8) (width 0.2) (layer "B.Cu") (net 1))
  (segment (start 86.8 95.115) (end 86.3 95.615) (width 0.25) (layer "B.Cu") (net 1))
  (segment (start 102.95 133.1) (end 102.95 132.735) (width 0.15) (layer "B.Cu") (net 1))
  (segment (start 109.435 96.7) (end 109.8 96.7) (width 0.2) (layer "B.Cu") (net 1))
  (segment (start 103.02 99.065) (end 103.935 99.065) (width 0.2) (layer "B.Cu") (net 1))
  (segment (start 99.5 123.65) (end 99.6 123.75) (width 0.15) (layer "B.Cu") (net 1))
  (segment (start 78.965 116.95) (end 78.25 116.95) (width 0.15) (layer "B.Cu") (net 1))
  (segment (start 103.55 128.5) (end 103.6 128.55) (width 0.15) (layer "B.Cu") (net 1))
  (segment (start 96.365 129.8) (end 96.365 128.765) (width 0.15) (layer "B.Cu") (net 1))
  (segment (start 103.55 127.885) (end 103.55 128.5) (width 0.15) (layer "B.Cu") (net 1))
  (segment (start 83.15 138.28) (end 83.15 137.45) (width 0.2) (layer "B.Cu") (net 1))
  (segment (start 101.2 90.05) (end 101.85 90.05) (width 0.2) (layer "B.Cu") (net 1))
  (segment (start 112.75 125.8) (end 113.2 125.35) (width 0.15) (layer "B.Cu") (net 1))
  (segment (start 114.69 175.91) (end 115.225 175.375) (width 0.3) (layer "B.Cu") (net 1))
  (segment (start 104.4875 122.2375) (end 104.5125 122.2625) (width 0.15) (layer "B.Cu") (net 1))
  (segment (start 101.885 118.95) (end 101.885 119.635) (width 0.15) (layer "B.Cu") (net 1))
  (segment (start 102.63 123.58) (end 102.8 123.75) (width 0.15) (layer "B.Cu") (net 1))
  (segment (start 97.115 116.1) (end 97.115 115.585) (width 0.2) (layer "B.Cu") (net 1))
  (segment (start 105.815 123.565) (end 106 123.75) (width 0.15) (layer "B.Cu") (net 1))
  (segment (start 97.35 133.5) (end 97.35 132.75) (width 0.15) (layer "B.Cu") (net 1))
  (segment (start 139 87.8) (end 139 86.91) (width 0.25) (layer "B.Cu") (net 1))
  (segment (start 108.4 118.95) (end 108.65 119.2) (width 0.15) (layer "B.Cu") (net 1))
  (segment (start 111.685 118.715) (end 111.5 118.9) (width 0.15) (layer "B.Cu") (net 1))
  (segment (start 106.55 127.885) (end 106.55 128.3) (width 0.15) (layer "B.Cu") (net 1))
  (segment (start 111.95 133.5343) (end 111.64215 133.84215) (width 0.15) (layer "B.Cu") (net 1))
  (segment (start 107.05 132.735) (end 107.05 133.4) (width 0.15) (layer "B.Cu") (net 1))
  (segment (start 86.3 126.55) (end 86.3 126.6) (width 0.15) (layer "B.Cu") (net 1))
  (segment (start 83.31 97.465) (end 82.565 97.465) (width 0.3) (layer "B.Cu") (net 1))
  (segment (start 83.4 119.9) (end 83.25 120.05) (width 0.1) (layer "B.Cu") (net 1))
  (segment (start 102.55 127.885) (end 102.55 128.3) (width 0.15) (layer "B.Cu") (net 1))
  (segment (start 97.49 174.29) (end 97.79 173.99) (width 0.3) (layer "B.Cu") (net 1))
  (segment (start 97.225 124.275) (end 97.5 124) (width 0.15) (layer "B.Cu") (net 1))
  (segment (start 106.715 121.435) (end 106.8 121.35) (width 0.15) (layer "B.Cu") (net 1))
  (segment (start 139.93 89.775) (end 140.855 90.7) (width 0.2) (layer "B.Cu") (net 1))
  (segment (start 139.905 89.8) (end 139.93 89.775) (width 0.25) (layer "B.Cu") (net 1))
  (segment (start 112.45 130.485) (end 112.765 130.485) (width 0.15) (layer "B.Cu") (net 1))
  (segment (start 132.185 175.74) (end 132.2 175.725) (width 0.2) (layer "B.Cu") (net 1))
  (segment (start 84.5 128.55) (end 84.8 128.25) (width 0.2) (layer "B.Cu") (net 1))
  (segment (start 106.95 113.1) (end 107.45 112.6) (width 0.15) (layer "B.Cu") (net 1))
  (segment (start 80.09 125.55) (end 81.7 125.55) (width 0.15) (layer "B.Cu") (net 1))
  (segment (start 98.8 115.75) (end 98.8 114.985) (width 0.15) (layer "B.Cu") (net 1))
  (segment (start 122.465 112.45) (end 121.65 112.45) (width 0.2) (layer "B.Cu") (net 1))
  (segment (start 101.2 90.05) (end 100.55 90.05) (width 0.2) (layer "B.Cu") (net 1))
  (segment (start 101.2 123.75) (end 100.45 123.75) (width 0.15) (layer "B.Cu") (net 1))
  (segment (start 130.135 116.525) (end 130.135 115.515) (width 0.2) (layer "B.Cu") (net 1))
  (segment (start 97.115 117.135714) (end 97.115 118.171428) (width 0.2) (layer "B.Cu") (net 1))
  (segment (start 71.9 138.33) (end 71.9 137.4) (width 0.2) (layer "B.Cu") (net 1))
  (segment (start 139 88.4) (end 139.94 88.4) (width 0.25) (layer "B.Cu") (net 1))
  (segment (start 109.29 175.435) (end 109.3 175.425) (width 0.3) (layer "B.Cu") (net 1))
  (segment (start 112.4 122.95) (end 112 122.95) (width 0.15) (layer "B.Cu") (net 1))
  (segment (start 101.95 93.835) (end 102.635 93.835) (width 0.2) (layer "B.Cu") (net 1))
  (segment (start 104.4 122.15) (end 104.5125 122.2625) (width 0.15) (layer "B.Cu") (net 1))
  (segment (start 85.85 133.185) (end 85.85 134) (width 0.15) (layer "B.Cu") (net 1))
  (segment (start 95.69 177.345) (end 95.69 174.599994) (width 0.3) (layer "B.Cu") (net 1))
  (segment (start 110.2 96.3) (end 110.2 96.2) (width 0.2) (layer "B.Cu") (net 1))
  (segment (start 107.55 128.35) (end 107.55 127.9) (width 0.15) (layer "B.Cu") (net 1))
  (segment (start 130.385 177.37) (end 130.385 175.76) (width 0.2) (layer "B.Cu") (net 1))
  (segment (start 109.2 128.55) (end 108.55 127.9) (width 0.15) (layer "B.Cu") (net 1))
  (segment (start 100.9 133.55) (end 100.9 132.8) (width 0.15) (layer "B.Cu") (net 1))
  (segment (start 99.609426 129.35) (end 100.45 129.35) (width 0.15) (layer "B.Cu") (net 1))
  (segment (start 112.175 124.775) (end 112.4 124.55) (width 0.15) (layer "B.Cu") (net 1))
  (segment (start 129.1 118.575) (end 129.1 119.43) (width 0.2) (layer "B.Cu") (net 1))
  (segment (start 79.375 126.265) (end 79.885 125.755) (width 0.15) (layer "B.Cu") (net 1))
  (segment (start 127.575 130.725) (end 127.175 130.725) (width 0.2) (layer "B.Cu") (net 1))
  (segment (start 129.9 114.8) (end 130.15 115.05) (width 0.2) (layer "B.Cu") (net 1))
  (segment (start 129.9 114.8) (end 130.15 114.55) (width 0.2) (layer "B.Cu") (net 1))
  (segment (start 129.85 118.55) (end 130.135 118.265) (width 0.2) (layer "B.Cu") (net 1))
  (segment (start 109.8 96.7) (end 110.2 96.3) (width 0.2) (layer "B.Cu") (net 1))
  (segment (start 85.4 130.55) (end 85.415 130.535) (width 0.15) (layer "B.Cu") (net 1))
  (segment (start 72.25 94.25) (end 72.25 95.0943) (width 0.3) (layer "B.Cu") (net 1))
  (segment (start 106.05 99.815) (end 107.10001 99.815) (width 0.2) (layer "B.Cu") (net 1))
  (segment (start 130.15 115.05) (end 130.15 115.55) (width 0.2) (layer "B.Cu") (net 1))
  (segment (start 114.8 82.5) (end 115.6 82.5) (width 0.25) (layer "B.Cu") (net 1))
  (segment (start 139 92.4) (end 139.805 92.4) (width 0.25) (layer "B.Cu") (net 1))
  (segment (start 106.55 128.3) (end 106.8 128.55) (width 0.15) (layer "B.Cu") (net 1))
  (segment (start 111.7 132.55) (end 112.4 133.25) (width 0.15) (layer "B.Cu") (net 1))
  (segment (start 130.135 118.265) (end 130.135 117.541666) (width 0.2) (layer "B.Cu") (net 1))
  (segment (start 100.5 116.515) (end 100.5 115.85) (width 0.15) (layer "B.Cu") (net 1))
  (segment (start 142.09 86.81) (end 142.1 86.8) (width 0.2) (layer "B.Cu") (net 1))
  (segment (start 111.735 124.775) (end 112.175 124.775) (width 0.15) (layer "B.Cu") (net 1))
  (segment (start 106.75 118.1) (end 106.8 118.15) (width 0.15) (layer "B.Cu") (net 1))
  (segment (start 96.55 122.3) (end 97.1 122.3) (width 0.15) (layer "B.Cu") (net 1))
  (segment (start 102.615 117.535) (end 102.8 117.35) (width 0.15) (layer "B.Cu") (net 1))
  (segment (start 103.6 122.95) (end 104.3125 122.2375) (width 0.15) (layer "B.Cu") (net 1))
  (segment (start 140.855 90.7) (end 142.05 90.7) (width 0.2) (layer "B.Cu") (net 1))
  (segment (start 81.69 175.81) (end 82.125 175.375) (width 0.3) (layer "B.Cu") (net 1))
  (segment (start 88.83807 118.89307) (end 88.935 118.99) (width 0.1) (layer "B.Cu") (net 1))
  (segment (start 105.55 128.3) (end 105.8 128.55) (width 0.15) (layer "B.Cu") (net 1))
  (segment (start 128.6 124.115) (end 128.6 123.4) (width 0.2) (layer "B.Cu") (net 1))
  (segment (start 105.2 93.95) (end 105.8 93.95) (width 0.2) (layer "B.Cu") (net 1))
  (segment (start 76.29 175.61) (end 76.3 175.6) (width 0.3) (layer "B.Cu") (net 1))
  (segment (start 127.75 130.9) (end 127.575 130.725) (width 0.2) (layer "B.Cu") (net 1))
  (segment (start 99.29 177.345) (end 99.29 174.014) (width 0.3) (layer "B.Cu") (net 1))
  (segment (start 71.35 90.1) (end 70.9 90.55) (width 0.2) (layer "B.Cu") (net 1))
  (segment (start 95.65 128.5) (end 95.85 128.3) (width 0.15) (layer "B.Cu") (net 1))
  (segment (start 96.7 126.65) (end 96.4 126.95) (width 0.15) (layer "B.Cu") (net 1))
  (segment (start 75.69 175.41) (end 76.3 174.8) (width 0.3) (layer "B.Cu") (net 1))
  (segment (start 139.965 89.74) (end 139.93 89.775) (width 0.2) (layer "B.Cu") (net 1))
  (segment (start 107.05 133.4) (end 106.9 133.55) (width 0.15) (layer "B.Cu") (net 1))
  (segment (start 97.115 121.3) (end 97.115 122.335) (width 0.15) (layer "B.Cu") (net 1))
  (segment (start 134.1 89.35) (end 133.675 89.775) (width 0.25) (layer "B.Cu") (net 1))
  (segment (start 85.415 130.535) (end 85.415 129.75) (width 0.15) (layer "B.Cu") (net 1))
  (segment (start 103.935 99.065) (end 104 99) (width 0.2) (layer "B.Cu") (net 1))
  (segment (start 97.3 119.75) (end 97.3 120) (width 0.1) (layer "B.Cu") (net 1))
  (segment (start 95.69 174.599994) (end 96.3 173.989994) (width 0.3) (layer "B.Cu") (net 1))
  (segment (start 107.10001 99.815) (end 107.28501 100) (width 0.2) (layer "B.Cu") (net 1))
  (segment (start 82.115 130.55) (end 82.115 131.135) (width 0.3) (layer "B.Cu") (net 1))
  (segment (start 97.115 118.171428) (end 95.621428 118.171428) (width 0.15) (layer "B.Cu") (net 1))
  (segment (start 135.1 87.83) (end 135.1 86.81) (width 0.25) (layer "B.Cu") (net 1))
  (segment (start 106.05 133.55) (end 106.05 132.8) (width 0.15) (layer "B.Cu") (net 1))
  (segment (start 132.185 177.37) (end 132.185 175.74) (width 0.2) (layer "B.Cu") (net 1))
  (segment (start 72.25 95.0943) (end 72.23465 95.10965) (width 0.3) (layer "B.Cu") (net 1))
  (segment (start 97.225 124.575) (end 97.225 124.275) (width 0.15) (layer "B.Cu") (net 1))
  (segment (start 140.1 86.81) (end 142.09 86.81) (width 0.2) (layer "B.Cu") (net 1))
  (segment (start 100.5 115.85) (end 100.4 115.75) (width 0.15) (layer "B.Cu") (net 1))
  (segment (start 76.29 177.345) (end 76.29 175.61) (width 0.3) (layer "B.Cu") (net 1))
  (segment (start 111.5 113.85) (end 110.05 113.85) (width 0.15) (layer "B.Cu") (net 1))
  (segment (start 99.5 123.085) (end 99.5 123.65) (width 0.15) (layer "B.Cu") (net 1))
  (segment (start 138 86.91) (end 138.1 86.81) (width 0.25) (layer "B.Cu") (net 1))
  (segment (start 79.065 125.18) (end 79.66 125.18) (width 0.15) (layer "B.Cu") (net 1))
  (segment (start 102 123.58) (end 102.63 123.58) (width 0.15) (layer "B.Cu") (net 1))
  (segment (start 101.95 133.55) (end 101.95 132.8) (width 0.15) (layer "B.Cu") (net 1))
  (segment (start 79.66 125.18) (end 79.885 124.955) (width 0.15) (layer "B.Cu") (net 1))
  (segment (start 104.5125 122.2625) (end 105.2 122.95) (width 0.15) (layer "B.Cu") (net 1))
  (segment (start 88.935 118.99) (end 88.935 119.395) (width 0.1) (layer "B.Cu") (net 1))
  (segment (start 137 87.8) (end 137 86.91) (width 0.25) (layer "B.Cu") (net 1))
  (segment (start 129.1 119.43) (end 129.11 119.44) (width 0.2) (layer "B.Cu") (net 1))
  (segment (start 122.05 129.975) (end 122.05 128.25) (width 0.2) (layer "B.Cu") (net 1))
  (segment (start 108.615 118.735) (end 108.4 118.95) (width 0.15) (layer "B.Cu") (net 1))
  (segment (start 104.4 128.55) (end 104.4 129.2) (width 0.15) (layer "B.Cu") (net 1))
  (segment (start 96.815 94.15) (end 96.815 95.2) (width 0.3) (layer "B.Cu") (net 1))
  (segment (start 101.885 122.15) (end 101.885 122.835) (width 0.15) (layer "B.Cu") (net 1))
  (segment (start 97.49 177.345) (end 97.49 174.29) (width 0.3) (layer "B.Cu") (net 1))
  (segment (start 110.9 114.95) (end 110.985 115.035) (width 0.15) (layer "B.Cu") (net 1))
  (segment (start 95.85 128.3) (end 95.85 127.7) (width 0.15) (layer "B.Cu") (net 1))
  (segment (start 96.815 95.935) (end 96.8 95.95) (width 0.3) (layer "B.Cu") (net 1))
  (segment (start 87.265 121.115) (end 87.1 120.95) (width 0.15) (layer "B.Cu") (net 1))
  (segment (start 121.5 118.8) (end 123.35 118.8) (width 0.3) (layer "B.Cu") (net 1))
  (segment (start 104.3125 122.2375) (end 104.4 122.15) (width 0.15) (layer "B.Cu") (net 1))
  (segment (start 121.965 124.135) (end 121.95 124.15) (width 0.2) (layer "B.Cu") (net 1))
  (segment (start 95.621428 118.171428) (end 94.8 117.35) (width 0.15) (layer "B.Cu") (net 1))
  (segment (start 87.44307 118.89307) (end 88.83807 118.89307) (width 0.1) (layer "B.Cu") (net 1))
  (segment (start 104.4 121.645) (end 104.4 122.15) (width 0.15) (layer "B.Cu") (net 1))
  (segment (start 106.715 122) (end 106.715 121.435) (width 0.15) (layer "B.Cu") (net 1))
  (segment (start 86.8 101.115) (end 86.3 101.615) (width 0.25) (layer "B.Cu") (net 1))
  (segment (start 109.435 95.65) (end 109.8 95.65) (width 0.2) (layer "B.Cu") (net 1))
  (segment (start 87.1 126.55) (end 87.35 126.8) (width 0.15) (layer "B.Cu") (net 1))
  (segment (start 139.805 92.4) (end 139.93 92.525) (width 0.25) (layer "B.Cu") (net 1))
  (segment (start 86.8 98.115) (end 86.3 98.615) (width 0.25) (layer "B.Cu") (net 1))
  (segment (start 100.585 96.265) (end 100.7 96.15) (width 0.2) (layer "B.Cu") (net 1))
  (segment (start 140.1 86.81) (end 140.1 88.24) (width 0.2) (layer "B.Cu") (net 1))
  (segment (start 79.885 129.755) (end 79.885 130.535) (width 0.15) (layer "B.Cu") (net 1))
  (segment (start 106.665 120.45) (end 106.665 119.885) (width 0.15) (layer "B.Cu") (net 1))
  (segment (start 109.85 94.6) (end 110.2 94.25) (width 0.2) (layer "B.Cu") (net 1))
  (segment (start 103.6 123.58) (end 103.6 122.95) (width 0.15) (layer "B.Cu") (net 1))
  (segment (start 86.8 96.115) (end 86.3 96.615) (width 0.25) (layer "B.Cu") (net 1))
  (segment (start 105.15 117.535) (end 105.815 117.535) (width 0.15) (layer "B.Cu") (net 1))
  (segment (start 99.6 123.75) (end 99.6 124.45) (width 0.15) (layer "B.Cu") (net 1))
  (segment (start 66.2 84.1) (end 70.2 84.1) (width 0.3) (layer "B.Cu") (net 1))
  (segment (start 107.35 128.55) (end 107.55 128.35) (width 0.15) (layer "B.Cu") (net 1))
  (segment (start 101.885 121.235) (end 102 121.35) (width 0.15) (layer "B.Cu") (net 1))
  (segment (start 101.885 120.5) (end 101.885 121.235) (width 0.15) (layer "B.Cu") (net 1))
  (segment (start 99.29 174.014) (end 99.314 173.99) (width 0.3) (layer "B.Cu") (net 1))
  (segment (start 101.75 113.315) (end 101.75 112.8) (width 0.15) (layer "B.Cu") (net 1))
  (segment (start 106.615 118.85) (end 106.615 118.335) (width 0.15) (layer "B.Cu") (net 1))
  (segment (start 70.915 130.65) (end 70.1 130.65) (width 0.3) (layer "B.Cu") (net 1))
  (segment (start 82.505 100.705) (end 82.5 100.7) (width 0.3) (layer "B.Cu") (net 1))
  (segment (start 110 130.15) (end 110 129.25) (width 0.15) (layer "B.Cu") (net 1))
  (segment (start 93.89 177.345) (end 93.89 174.08) (width 0.3) (layer "B.Cu") (net 1))
  (segment (start 110.985 115.035) (end 110.985 114.365) (width 0.3) (layer "B.Cu") (net 1))
  (segment (start 103.6 118.15) (end 103.6 117.5) (width 0.15) (layer "B.Cu") (net 1))
  (segment (start 87.35 126.8) (end 87.35 127.25) (width 0.15) (layer "B.Cu") (net 1))
  (segment (start 101.75 112.8) (end 102 112.55) (width 0.15) (layer "B.Cu") (net 1))
  (segment (start 96.35 128.75) (end 95.9 128.75) (width 0.15) (layer "B.Cu") (net 1))
  (segment (start 99.7 133.25) (end 99.7 133.85) (width 0.15) (layer "B.Cu") (net 1))
  (segment (start 110.2 97.85) (end 109.55 97.85) (width 0.2) (layer "B.Cu") (net 1))
  (segment (start 97.225 123.425) (end 97.225 123.725) (width 0.15) (layer "B.Cu") (net 1))
  (segment (start 110.985 116.05) (end 110.985 115.035) (width 0.3) (layer "B.Cu") (net 1))
  (segment (start 108.1 133.55) (end 108.1 132.8) (width 0.15) (layer "B.Cu") (net 1))
  (segment (start 108.35 117.035) (end 108.885 117.035) (width 0.15) (layer "B.Cu") (net 1))
  (segment (start 79.64 129.2) (end 79.05 129.2) (width 0.15) (layer "B.Cu") (net 1))
  (segment (start 138 87.8) (end 138 86.91) (width 0.25) (layer "B.Cu") (net 1))
  (segment (start 87.1 118.55) (end 87.44307 118.89307) (width 0.1) (layer "B.Cu") (net 1))
  (segment (start 127.66 129.7) (end 128.425 129.7) (width 0.2) (layer "B.Cu") (net 1))
  (segment (start 102 99) (end 102 99.7) (width 0.2) (layer "B.Cu") (net 1))
  (segment (start 98.85 95.2) (end 98.8 95.15) (width 0.2) (layer "F.Cu") (net 2))
  (segment (start 99.772851 95.2) (end 98.85 95.2) (width 0.2) (layer "F.Cu") (net 2))
  (segment (start 127.42 118.035) (end 127.485 118.1) (width 0.15) (layer "F.Cu") (net 2))
  (segment (start 124.235 113.365) (end 124.235 112.45) (width 0.15) (layer "F.Cu") (net 2))
  (segment (start 124.235 112.45) (end 124.285 112.4) (width 0.15) (layer "F.Cu") (net 2))
  (segment (start 127.42 117.55) (end 127.42 118.035) (width 0.15) (layer "F.Cu") (net 2))
  (segment (start 87.3 100.6) (end 87.8 100.1) (width 0.15) (layer "F.Cu") (net 2))
  (segment (start 108 115.35) (end 108.4 114.95) (width 0.15) (layer "F.Cu") (net 2))
  (segment (start 109.6 120.95) (end 110 120.55) (width 0.15) (layer "F.Cu") (net 2))
  (segment (start 99.2 118.55) (end 98.8 118.15) (width 0.15) (layer "F.Cu") (net 2))
  (segment (start 109.6 125.75) (end 110 126.15) (width 0.15) (layer "F.Cu") (net 2))
  (segment (start 109.6 124.95) (end 110 124.55) (width 0.15) (layer "F.Cu") (net 2))
  (segment (start 90.29 94.6) (end 90.79 94.1) (width 0.15) (layer "F.Cu") (net 2))
  (segment (start 71.8899 132.205) (end 71.8899 131.4601) (width 0.3) (layer "F.Cu") (net 2))
  (segment (start 142.2 64.735) (end 142.2 65.55) (width 0.25) (layer "F.Cu") (net 2))
  (segment (start 140.6875 89.775) (end 141.65 89.775) (width 0.15) (layer "F.Cu") (net 2))
  (segment (start 140.6875 92.775) (end 141.45 92.775) (width 0.15) (layer "F.Cu") (net 2))
  (segment (start 141.45 92.775) (end 141.6 92.925) (width 0.15) (layer "F.Cu") (net 2))
  (segment (start 132.8125 87.275) (end 131.9 87.275) (width 0.15) (layer "F.Cu") (net 2))
  (segment (start 137 93.9625) (end 137 94.925) (width 0.15) (layer "F.Cu") (net 2))
  (segment (start 145.725 88.675) (end 144.675 88.675) (width 0.2) (layer "F.Cu") (net 2))
  (segment (start 143.425 88.675) (end 144.675 88.675) (width 0.2) (layer "F.Cu") (net 2))
  (segment (start 122.95 123.239723) (end 123.205 123.494723) (width 0.15) (layer "F.Cu") (net 2))
  (segment (start 93.95 94.95) (end 93.95 94.25) (width 0.15) (layer "F.Cu") (net 2))
  (segment (start 66.25 89.174998) (end 67.275002 89.174998) (width 0.3) (layer "F.Cu") (net 2))
  (segment (start 71.9 140.15) (end 71.9 141.0949) (width 0.25) (layer "F.Cu") (net 2))
  (segment (start 138.1 64.735) (end 138.1 65.55) (width 0.25) (layer "F.Cu") (net 2))
  (segment (start 85.3 99.6) (end 84.8 99.1) (width 0.25) (layer "F.Cu") (net 2))
  (segment (start 68.57 151.730021) (end 68.850021 151.45) (width 0.15) (layer "F.Cu") (net 2))
  (segment (start 105 104.485) (end 105 105.65) (width 0.15) (layer "F.Cu") (net 2))
  (segment (start 133.85 155.4) (end 134.725 155.4) (width 0.2) (layer "F.Cu") (net 2))
  (segment (start 121.935 117.55) (end 122.55 117.55) (width 0.15) (layer "F.Cu") (net 2))
  (segment (start 71.45 119.1) (end 71.45 118.05) (width 0.15) (layer "F.Cu") (net 2))
  (segment (start 102 104.9) (end 102.5 105.4) (width 0.15) (layer "F.Cu") (net 2))
  (segment (start 66.95 84.2) (end 66.4 84.2) (width 0.3) (layer "F.Cu") (net 2))
  (segment (start 136.05 157.325) (end 136.05 155.75) (width 0.25) (layer "F.Cu") (net 2))
  (segment (start 109.6 121.75) (end 110 121.35) (width 0.15) (layer "F.Cu") (net 2))
  (segment (start 110.2 97.15) (end 111.25 97.15) (width 0.2) (layer "F.Cu") (net 2))
  (segment (start 89.3 111.4) (end 87.715 111.4) (width 0.2) (layer "F.Cu") (net 2))
  (segment (start 66.25 87.533332) (end 66.25 89.2) (width 0.3) (layer "F.Cu") (net 2))
  (segment (start 87.715 111.4) (end 87.6 111.515) (width 0.2) (layer "F.Cu") (net 2))
  (segment (start 83.1399 141.105) (end 83.1399 140.2101) (width 0.2) (layer "F.Cu") (net 2))
  (segment (start 73.285 161.02) (end 73.285 162.765002) (width 0.2) (layer "F.Cu") (net 2))
  (segment (start 136.4 155.4) (end 135.7 155.4) (width 0.2) (layer "F.Cu") (net 2))
  (segment (start 101 104.9) (end 101.5 105.4) (width 0.15) (layer "F.Cu") (net 2))
  (segment (start 138.55 155.9) (end 138.05 155.4) (width 0.25) (layer "F.Cu") (net 2))
  (segment (start 66.25 84.35) (end 66.25 85.891666) (width 0.3) (layer "F.Cu") (net 2))
  (segment (start 109.6 122.55) (end 110 122.15) (width 0.15) (layer "F.Cu") (net 2))
  (segment (start 83.1399 132.205) (end 83.1399 131.4601) (width 0.3) (layer "F.Cu") (net 2))
  (segment (start 123.205 123.494723) (end 123.205 124.18) (width 0.15) (layer "F.Cu") (net 2))
  (segment (start 90.3 96.6) (end 89.8 97.1) (width 0.15) (layer "F.Cu") (net 2))
  (segment (start 111.25 96.003) (end 111.25 97.15) (width 0.2) (layer "F.Cu") (net 2))
  (segment (start 102 104.485) (end 102 104.9) (width 0.15) (layer "F.Cu") (net 2))
  (segment (start 93.3 95.6) (end 93.95 94.95) (width 0.15) (layer "F.Cu") (net 2))
  (segment (start 125.95 129.9) (end 125.705 129.655) (width 0.15) (layer "F.Cu") (net 2))
  (segment (start 126.1 153.815) (end 126.1 153.04) (width 0.3) (layer "F.Cu") (net 2))
  (segment (start 104 105.2) (end 104.5 105.7) (width 0.15) (layer "F.Cu") (net 2))
  (segment (start 109.6 124.15) (end 110 123.75) (width 0.15) (layer "F.Cu") (net 2))
  (segment (start 104.8 115.35) (end 105.2 114.95) (width 0.15) (layer "F.Cu") (net 2))
  (segment (start 120.55 157.325) (end 120.55 155.785) (width 0.25) (layer "F.Cu") (net 2))
  (segment (start 135.55 157.325) (end 135.55 155.4) (width 0.25) (layer "F.Cu") (net 2))
  (segment (start 126.205 129.67) (end 126.205 129.05) (width 0.15) (layer "F.Cu") (net 2))
  (segment (start 128.015002 114.55) (end 128.265002 114.8) (width 0.15) (layer "F.Cu") (net 2))
  (segment (start 131.49 118.15) (end 129.59 118.15) (width 0.2) (layer "F.Cu") (net 2))
  (segment (start 128.265002 114.8) (end 128.015002 115.05) (width 0.15) (layer "F.Cu") (net 2))
  (segment (start 103.2 115.35) (end 102.8 114.95) (width 0.15) (layer "F.Cu") (net 2))
  (segment (start 127.42 114.55) (end 128.015002 114.55) (width 0.15) (layer "F.Cu") (net 2))
  (segment (start 72.2 119.1) (end 72.75 119.1) (width 0.15) (layer "F.Cu") (net 2))
  (segment (start 71.37 163.23) (end 71.09 162.95) (width 0.2) (layer "F.Cu") (net 2))
  (segment (start 83.1399 140.2101) (end 83.15 140.2) (width 0.2) (layer "F.Cu") (net 2))
  (segment (start 121.55 155.785) (end 121.05 155.285) (width 0.3) (layer "F.Cu") (net 2))
  (segment (start 89.3 111.4) (end 89.3 112.3) (width 0.2) (layer "F.Cu") (net 2))
  (segment (start 86.1 112.615) (end 87.185 112.615) (width 0.25) (layer "F.Cu") (net 2))
  (segment (start 131.49 118.15) (end 131.49 119.66) (width 0.2) (layer "F.Cu") (net 2))
  (segment (start 138.05 157.325) (end 138.05 155.4) (width 0.25) (layer "F.Cu") (net 2))
  (segment (start 85.3 94.6) (end 84.8 94.1) (width 0.25) (layer "F.Cu") (net 2))
  (segment (start 121.05 158.38999) (end 120.79999 158.64) (width 0.3) (layer "F.Cu") (net 2))
  (segment (start 108.685 104.485) (end 108.7 104.5) (width 0.15) (layer "F.Cu") (net 2))
  (segment (start 72.2 119.1) (end 71.45 119.1) (width 0.15) (layer "F.Cu") (net 2))
  (segment (start 111.25 96.003) (end 112.223 96.003) (width 0.2) (layer "F.Cu") (net 2))
  (segment (start 123.96 134.23) (end 123.49 133.76) (width 0.2) (layer "F.Cu") (net 2))
  (segment (start 124.69 134.23) (end 126.59 134.23) (width 0.2) (layer "F.Cu") (net 2))
  (segment (start 121.5 117.85) (end 121.635 117.85) (width 0.15) (layer "F.Cu") (net 2))
  (segment (start 121.05 157.325) (end 121.05 155.285) (width 0.25) (layer "F.Cu") (net 2))
  (segment (start 136.05 155.75) (end 135.75 155.45) (width 0.25) (layer "F.Cu") (net 2))
  (segment (start 106.4 115.35) (end 106.8 114.95) (width 0.15) (layer "F.Cu") (net 2))
  (segment (start 121.635 117.85) (end 121.935 117.55) (width 0.15) (layer "F.Cu") (net 2))
  (segment (start 85.3 95.6) (end 84.8 95.1) (width 0.25) (layer "F.Cu") (net 2))
  (segment (start 125.705 129.655) (end 125.705 129.05) (width 0.15) (layer "F.Cu") (net 2))
  (segment (start 134.55 157.325) (end 134.55 155.635) (width 0.25) (layer "F.Cu") (net 2))
  (segment (start 72.265 161.02) (end 73.285 161.02) (width 0.2) (layer "F.Cu") (net 2))
  (segment (start 121.05 157.325) (end 121.05 158.38999) (width 0.3) (layer "F.Cu") (net 2))
  (segment (start 106 104.485) (end 106 104.9) (width 0.15) (layer "F.Cu") (net 2))
  (segment (start 101 104.485) (end 101 104.9) (width 0.15) (layer "F.Cu") (net 2))
  (segment (start 120.55 155.785) (end 121.05 155.285) (width 0.25) (layer "F.Cu") (net 2))
  (segment (start 143.2 167.265) (end 143.2 166.4) (width 0.15) (layer "F.Cu") (net 2))
  (segment (start 109.435 99.45) (end 110.2 99.45) (width 0.2) (layer "F.Cu") (net 2))
  (segment (start 93.3 100.6) (end 92.8 100.1) (width 0.15) (layer "F.Cu") (net 2))
  (segment (start 104.95 100.9) (end 105 100.95) (width 0.2) (layer "F.Cu") (net 2))
  (segment (start 105.6 115.35) (end 105.2 114.95) (width 0.15) (layer "F.Cu") (net 2))
  (segment (start 124.69 134.23) (end 123.96 134.23) (width 0.2) (layer "F.Cu") (net 2))
  (segment (start 128.015002 115.05) (end 127.42 115.05) (width 0.15) (layer "F.Cu") (net 2))
  (segment (start 67.35 83.45) (end 67.35 83.8) (width 0.3) (layer "F.Cu") (net 2))
  (segment (start 127.1 153.815) (end 127.1 153.04) (width 0.3) (layer "F.Cu") (net 2))
  (segment (start 103 104.9) (end 103.5 105.4) (width 0.15) (layer "F.Cu") (net 2))
  (segment (start 70.345 166.975) (end 70.32 166.95) (width 0.15) (layer "F.Cu") (net 2))
  (segment (start 104 104.485) (end 104 105.2) (width 0.15) (layer "F.Cu") (net 2))
  (segment (start 73.285 162.765002) (end 72.820002 163.23) (width 0.2) (layer "F.Cu") (net 2))
  (segment (start 106.627149 97.7) (end 107.55 97.7) (width 0.2) (layer "F.Cu") (net 2))
  (segment (start 104.95 99.877149) (end 104.95 100.9) (width 0.2) (layer "F.Cu") (net 2))
  (segment (start 125.95 129.925) (end 125.95 129.9) (width 0.15) (layer "F.Cu") (net 2))
  (segment (start 126.59 134.23) (end 128.235 134.23) (width 0.2) (layer "F.Cu") (net 2))
  (segment (start 85.3 97.6) (end 84.8 97.1) (width 0.25) (layer "F.Cu") (net 2))
  (segment (start 67.35 83.8) (end 66.95 84.2) (width 0.3) (layer "F.Cu") (net 2))
  (segment (start 128.4 125.915) (end 128.35 125.865) (width 0.15) (layer "F.Cu") (net 2))
  (segment (start 75.49 165.36) (end 75.49 166.11) (width 0.15) (layer "F.Cu") (net 2))
  (segment (start 127.485 118.1) (end 129.54 118.1) (width 0.2) (layer "F.Cu") (net 2))
  (segment (start 135.05 155.75) (end 134.7 155.4) (width 0.25) (layer "F.Cu") (net 2))
  (segment (start 107.55 97.7) (end 107.550003 97.699997) (width 0.2) (layer "F.Cu") (net 2))
  (segment (start 68.07 154.35) (end 68.07 155.72) (width 0.15) (layer "F.Cu") (net 2))
  (segment (start 68.57 154.35) (end 68.57 151.730021) (width 0.15) (layer "F.Cu") (net 2))
  (segment (start 72.820002 163.23) (end 71.37 163.23) (width 0.2) (layer "F.Cu") (net 2))
  (segment (start 99.2 124.95) (end 98.8 125.35) (width 0.15) (layer "F.Cu") (net 2))
  (segment (start 85.3 96.6) (end 84.8 96.1) (width 0.25) (layer "F.Cu") (net 2))
  (segment (start 102.4 115.35) (end 102 114.95) (width 0.15) (layer "F.Cu") (net 2))
  (segment (start 119.945 157.325) (end 119.94 157.32) (width 0.3) (layer "F.Cu") (net 2))
  (segment (start 138.05 155.4) (end 137.15 155.4) (width 0.2) (layer "F.Cu") (net 2))
  (segment (start 104 115.35) (end 103.6 114.95) (width 0.15) (layer "F.Cu") (net 2))
  (segment (start 121.55 157.325) (end 121.55 155.785) (width 0.3) (layer "F.Cu") (net 2))
  (segment (start 103 104.485) (end 103 104.9) (width 0.15) (layer "F.Cu") (net 2))
  (segment (start 120.55 157.325) (end 119.945 157.325) (width 0.3) (layer "F.Cu") (net 2))
  (segment (start 140.15 64.735) (end 140.15 65.55) (width 0.25) (layer "F.Cu") (net 2))
  (segment (start 90.3 101.6) (end 90.8 101.1) (width 0.15) (layer "F.Cu") (net 2))
  (segment (start 66.25 90.816664) (end 66.25 95.55) (width 0.3) (layer "F.Cu") (net 2))
  (segment (start 125.95 129.925) (end 126.205 129.67) (width 0.15) (layer "F.Cu") (net 2))
  (segment (start 67.275002 89.174998) (end 67.3 89.15) (width 0.3) (layer "F.Cu") (net 2))
  (segment (start 85.3 101.6) (end 84.8 101.1) (width 0.25) (layer "F.Cu") (net 2))
  (segment (start 100.8 115.35) (end 100.4 114.95) (width 0.15) (layer "F.Cu") (net 2))
  (segment (start 86.6 87.95) (end 86.6 90.2) (width 0.7) (layer "F.Cu") (net 2))
  (segment (start 85.3 100.6) (end 84.8 100.1) (width 0.25) (layer "F.Cu") (net 2))
  (segment (start 83.1399 131.4601) (end 83.15 131.45) (width 0.3) (layer "F.Cu") (net 2))
  (segment (start 135.05 157.325) (end 135.05 155.75) (width 0.25) (layer "F.Cu") (net 2))
  (segment (start 109.435 97.15) (end 110.2 97.15) (width 0.2) (layer "F.Cu") (net 2))
  (segment (start 99.2 119.35) (end 98.8 118.95) (width 0.15) (layer "F.Cu") (net 2))
  (segment (start 106 104.9) (end 105.5 105.4) (width 0.15) (layer "F.Cu") (net 2))
  (segment (start 99.2 116.95) (end 98.8 116.55) (width 0.15) (layer "F.Cu") (net 2))
  (segment (start 123.205 129.52) (end 123.205 129.05) (width 0.15) (layer "F.Cu") (net 2))
  (segment (start 99.2 125.75) (end 98.8 126.15) (width 0.15) (layer "F.Cu") (net 2))
  (segment (start 122.75 129.975) (end 123.205 129.52) (width 0.15) (layer "F.Cu") (net 2))
  (segment (start 70.345 167.87) (end 70.345 166.975) (width 0.15) (layer "F.Cu") (net 2))
  (segment (start 109.435 96.15) (end 109.435 97.135) (width 0.2) (layer "F.Cu") (net 2))
  (segment (start 105 105.65) (end 105.5 106.15) (width 0.15) (layer "F.Cu") (net 2))
  (segment (start 87.29 95.6) (end 87.79 95.1) (width 0.15) (layer "F.Cu") (net 2))
  (segment (start 85.3 98.6) (end 84.8 98.1) (width 0.25) (layer "F.Cu") (net 2))
  (segment (start 68.07 155.72) (end 68.075 155.725) (width 0.15) (layer "F.Cu") (net 2))
  (segment (start 138.55 157.325) (end 138.55 155.9) (width 0.25) (layer "F.Cu") (net 2))
  (segment (start 107 104.485) (end 108.685 104.485) (width 0.15) (layer "F.Cu") (net 2))
  (segment (start 99.2 120.15) (end 98.8 119.75) (width 0.15) (layer "F.Cu") (net 2))
  (segment (start 87.6 111.515) (end 87.6 112.4) (width 0.2) (layer "F.Cu") (net 2))
  (segment (start 90.3 99.6) (end 90.8 100.1) (width 0.15) (layer "F.Cu") (net 2))
  (segment (start 128.35 125.865) (end 127.39 125.865) (width 0.15) (layer "F.Cu") (net 2))
  (via (at 98.8 95.15) (size 0.5) (drill 0.2) (layers "F.Cu" "B.Cu") (net 2))
  (via (at 105 100.95) (size 0.5) (drill 0.2) (layers "F.Cu" "B.Cu") (net 2))
  (via (at 124.285 112.4) (size 0.5) (drill 0.2) (layers "F.Cu" "B.Cu") (net 2))
  (via (at 127.485 118.1) (size 0.5) (drill 0.2) (layers "F.Cu" "B.Cu") (net 2))
  (via (at 83.15 140.2) (size 0.5) (drill 0.2) (layers "F.Cu" "B.Cu") (net 2))
  (via (at 89.8 98.1) (size 0.5) (drill 0.2) (layers "F.Cu" "B.Cu") (net 2))
  (via (at 87.8 100.1) (size 0.5) (drill 0.2) (layers "F.Cu" "B.Cu") (net 2))
  (via (at 110 120.55) (size 0.5) (drill 0.2) (layers "F.Cu" "B.Cu") (net 2))
  (via (at 98.8 118.15) (size 0.5) (drill 0.2) (layers "F.Cu" "B.Cu") (net 2))
  (via (at 110 126.15) (size 0.5) (drill 0.2) (layers "F.Cu" "B.Cu") (net 2))
  (via (at 86.6 90.2) (size 0.6) (drill 0.3) (layers "F.Cu" "B.Cu") (net 2))
  (via (at 103.6 114.95) (size 0.5) (drill 0.2) (layers "F.Cu" "B.Cu") (net 2))
  (via (at 95.8 100.8) (size 0.5) (drill 0.2) (layers "F.Cu" "B.Cu") (net 2))
  (via (at 90.79 94.1) (size 0.5) (drill 0.2) (layers "F.Cu" "B.Cu") (net 2))
  (via (at 71.9 131.45) (size 0.5) (drill 0.2) (layers "F.Cu" "B.Cu") (net 2))
  (via (at 142.2 65.55) (size 0.5) (drill 0.2) (layers "F.Cu" "B.Cu") (net 2))
  (via (at 141.65 89.775) (size 0.5) (drill 0.2) (layers "F.Cu" "B.Cu") (net 2))
  (via (at 141.6 92.925) (size 0.5) (drill 0.2) (layers "F.Cu" "B.Cu") (net 2))
  (via (at 131.9 87.275) (size 0.5) (drill 0.2) (layers "F.Cu" "B.Cu") (net 2))
  (via (at 137 94.775) (size 0.5) (drill 0.2) (layers "F.Cu" "B.Cu") (net 2))
  (via (at 144.675 88.675) (size 0.5) (drill 0.2) (layers "F.Cu" "B.Cu") (net 2))
  (via (at 137.5 82.5) (size 0.5) (drill 0.2) (layers "F.Cu" "B.Cu") (net 2))
  (via (at 95.775 98.1) (size 0.5) (drill 0.2) (layers "F.Cu" "B.Cu") (net 2))
  (via (at 95.825 95.05) (size 0.5) (drill 0.2) (layers "F.Cu" "B.Cu") (net 2))
  (via (at 84.8 96.1) (size 0.5) (drill 0.2) (layers "F.Cu" "B.Cu") (net 2))
  (via (at 70.15 140.6) (size 0.5) (drill 0.2) (layers "F.Cu" "B.Cu") (net 2))
  (via (at 110 123.75) (size 0.5) (drill 0.2) (layers "F.Cu" "B.Cu") (net 2))
  (via (at 68.65 149.25) (size 0.5) (drill 0.2) (layers "F.Cu" "B.Cu") (net 2))
  (via (at 120.79999 158.64) (size 0.5) (drill 0.2) (layers "F.Cu" "B.Cu") (net 2))
  (via (at 66.25 149.2) (size 0.5) (drill 0.2) (layers "F.Cu" "B.Cu") (net 2))
  (via (at 90.8 100.1) (size 0.5) (drill 0.2) (layers "F.Cu" "B.Cu") (net 2))
  (via (at 98.85 90.05) (size 0.5) (drill 0.2) (layers "F.Cu" "B.Cu") (net 2))
  (via (at 68.850021 151.45) (size 0.5) (drill 0.2) (layers "F.Cu" "B.Cu") (net 2))
  (via (at 102.8 114.95) (size 0.5) (drill 0.2) (layers "F.Cu" "B.Cu") (net 2))
  (via (at 89.3 111.4) (size 0.5) (drill 0.2) (layers "F.Cu" "B.Cu") (net 2))
  (via (at 110 122.15) (size 0.5) (drill 0.2) (layers "F.Cu" "B.Cu") (net 2))
  (via (at 78 140.3) (size 0.5) (drill 0.2) (layers "F.Cu" "B.Cu") (net 2))
  (via (at 125.95 129.925) (size 0.5) (drill 0.2) (layers "F.Cu" "B.Cu") (net 2))
  (via (at 66.25 95.55) (size 0.5) (drill 0.2) (layers "F.Cu" "B.Cu") (net 2))
  (via (at 84.8 99.1) (size 0.5) (drill 0.2) (layers "F.Cu" "B.Cu") (net 2))
  (via (at 90.8 101.1) (size 0.5) (drill 0.2) (layers "F.Cu" "B.Cu") (net 2))
  (via (at 81.55 140.15) (size 0.5) (drill 0.2) (layers "F.Cu" "B.Cu") (net 2))
  (via (at 143.2 166.4) (size 0.5) (drill 0.2) (layers "F.Cu" "B.Cu") (net 2))
  (via (at 122.75 129.975) (size 0.5) (drill 0.2) (layers "F.Cu" "B.Cu") (net 2))
  (via (at 100.4 114.95) (size 0.5) (drill 0.2) (layers "F.Cu" "B.Cu") (net 2))
  (via (at 127.1 153.04) (size 0.5) (drill 0.2) (layers "F.Cu" "B.Cu") (net 2))
  (via (at 122.95 123.239723) (size 0.5) (drill 0.2) (layers "F.Cu" "B.Cu") (net 2))
  (via (at 79.95 149.15) (size 0.5) (drill 0.2) (layers "F.Cu" "B.Cu") (net 2))
  (via (at 128.4 125.915) (size 0.5) (drill 0.2) (layers "F.Cu" "B.Cu") (net 2))
  (via (at 106.8 114.95) (size 0.5) (drill 0.2) (layers "F.Cu" "B.Cu") (net 2))
  (via (at 68.2 140.3) (size 0.5) (drill 0.2) (layers "F.Cu" "B.Cu") (net 2))
  (via (at 84.8 98.1) (size 0.5) (drill 0.2) (layers "F.Cu" "B.Cu") (net 2))
  (via (at 69.5 149.25) (size 0.5) (drill 0.2) (layers "F.Cu" "B.Cu") (net 2))
  (via (at 121.5 117.85) (size 0.5) (drill 0.2) (layers "F.Cu" "B.Cu") (net 2))
  (via (at 77.65 95.250011) (size 0.5) (drill 0.2) (layers "F.Cu" "B.Cu") (net 2))
  (via (at 67.3 89.15) (size 0.5) (drill 0.2) (layers "F.Cu" "B.Cu") (net 2))
  (via (at 103.5 105.4) (size 0.5) (drill 0.2) (layers "F.Cu" "B.Cu") (net 2))
  (via (at 75.490009 166.110009) (size 0.5) (drill 0.2) (layers "F.Cu" "B.Cu") (net 2))
  (via (at 84.4 102.8) (size 0.5) (drill 0.2) (layers "F.Cu" "B.Cu") (net 2))
  (via (at 135.7 83.675) (size 0.5) (drill 0.2) (layers "F.Cu" "B.Cu") (net 2))
  (via (at 98.8 119.75) (size 0.5) (drill 0.2) (layers "F.Cu" "B.Cu") (net 2))
  (via (at 84.75 134.05) (size 0.5) (drill 0.2) (layers "F.Cu" "B.Cu") (net 2))
  (via (at 84.8 94.1) (size 0.5) (drill 0.2) (layers "F.Cu" "B.Cu") (net 2))
  (via (at 110 124.55) (size 0.5) (drill 0.2) (layers "F.Cu" "B.Cu") (net 2))
  (via (at 107.550003 97.699997) (size 0.5) (drill 0.2) (layers "F.Cu" "B.Cu") (net 2))
  (via (at 110 121.35) (size 0.5) (drill 0.2) (layers "F.Cu" "B.Cu") (net 2))
  (via (at 80.3 140.2) (size 0.5) (drill 0.2) (layers "F.Cu" "B.Cu") (net 2))
  (via (at 108.7 104.5) (size 0.5) (drill 0.2) (layers "F.Cu" "B.Cu") (net 2))
  (via (at 138.1 65.55) (size 0.5) (drill 0.2) (layers "F.Cu" "B.Cu") (net 2))
  (via (at 110.2 99.45) (size 0.5) (drill 0.2) (layers "F.Cu" "B.Cu") (net 2))
  (via (at 128.265002 114.8) (size 0.5) (drill 0.2) (layers "F.Cu" "B.Cu") (net 2))
  (via (at 123.49 133.76) (size 0.5) (drill 0.2) (layers "F.Cu" "B.Cu") (net 2))
  (via (at 71.09 162.95) (size 0.5) (drill 0.2) (layers "F.Cu" "B.Cu") (net 2))
  (via (at 98.6 93.35) (size 0.5) (drill 0.2) (layers "F.Cu" "B.Cu") (net 2))
  (via (at 84.8 95.1) (size 0.5) (drill 0.2) (layers "F.Cu" "B.Cu") (net 2))
  (via (at 110.2 97.15) (size 0.5) (drill 0.2) (layers "F.Cu" "B.Cu") (net 2))
  (via (at 84.8 101.1) (size 0.5) (drill 0.2) (layers "F.Cu" "B.Cu") (net 2))
  (via (at 77.7 149.15) (size 0.5) (drill 0.2) (layers "F.Cu" "B.Cu") (net 2))
  (via (at 81.4 149.2) (size 0.5) (drill 0.2) (layers "F.Cu" "B.Cu") (net 2))
  (via (at 67.35 83.45) (size 0.5) (drill 0.2) (layers "F.Cu" "B.Cu") (net 2))
  (via (at 84.8 97.1) (size 0.5) (drill 0.2) (layers "F.Cu" "B.Cu") (net 2))
  (via (at 92.47 141.17) (size 0.5) (drill 0.2) (layers "F.Cu" "B.Cu") (net 2))
  (via (at 105.5 106.15) (size 0.5) (drill 0.2) (layers "F.Cu" "B.Cu") (net 2))
  (via (at 98.8 125.35) (size 0.5) (drill 0.2) (layers "F.Cu" "B.Cu") (net 2))
  (via (at 140.15 65.55) (size 0.5) (drill 0.2) (layers "F.Cu" "B.Cu") (net 2))
  (via (at 83.15 131.45) (size 0.5) (drill 0.2) (layers "F.Cu" "B.Cu") (net 2))
  (via (at 86.6 88.8) (size 0.6) (drill 0.3) (layers "F.Cu" "B.Cu") (net 2))
  (via (at 87.79 95.1) (size 0.5) (drill 0.2) (layers "F.Cu" "B.Cu") (net 2))
  (via (at 95.825 96.075) (size 0.5) (drill 0.2) (layers "F.Cu" "B.Cu") (net 2))
  (via (at 93.95 94.25) (size 0.5) (drill 0.2) (layers "F.Cu" "B.Cu") (net 2))
  (via (at 105.5 105.4) (size 0.5) (drill 0.2) (layers "F.Cu" "B.Cu") (net 2))
  (via (at 92.8 100.1) (size 0.5) (drill 0.2) (layers "F.Cu" "B.Cu") (net 2))
  (via (at 70.32 166.95) (size 0.5) (drill 0.2) (layers "F.Cu" "B.Cu") (net 2))
  (via (at 71.9 140.15) (size 0.5) (drill 0.2) (layers "F.Cu" "B.Cu") (net 2))
  (via (at 68.075 155.725) (size 0.5) (drill 0.2) (layers "F.Cu" "B.Cu") (net 2))
  (via (at 95.8 99.85) (size 0.5) (drill 0.2) (layers "F.Cu" "B.Cu") (net 2))
  (via (at 108.4 114.95) (size 0.5) (drill 0.2) (layers "F.Cu" "B.Cu") (net 2))
  (via (at 102 114.95) (size 0.5) (drill 0.2) (layers "F.Cu" "B.Cu") (net 2))
  (via (at 126.1 153.04) (size 0.5) (drill 0.2) (layers "F.Cu" "B.Cu") (net 2))
  (via (at 66.2 140.25) (size 0.5) (drill 0.2) (layers "F.Cu" "B.Cu") (net 2))
  (via (at 105.2 114.95) (size 0.5) (drill 0.2) (layers "F.Cu" "B.Cu") (net 2))
  (via (at 102.5 105.4) (size 0.5) (drill 0.2) (layers "F.Cu" "B.Cu") (net 2))
  (via (at 133.85 155.4) (size 0.6) (drill 0.3) (layers "F.Cu" "B.Cu") (net 2))
  (via (at 90.15 149.9) (size 0.5) (drill 0.2) (layers "F.Cu" "B.Cu") (net 2))
  (via (at 119.94 157.32) (size 0.5) (drill 0.2) (layers "F.Cu" "B.Cu") (net 2))
  (via (at 98.8 118.95) (size 0.5) (drill 0.2) (layers "F.Cu" "B.Cu") (net 2))
  (via (at 104.5 105.7) (size 0.5) (drill 0.2) (layers "F.Cu" "B.Cu") (net 2))
  (via (at 84.8 100.1) (size 0.5) (drill 0.2) (layers "F.Cu" "B.Cu") (net 2))
  (via (at 101.5 105.4) (size 0.5) (drill 0.2) (layers "F.Cu" "B.Cu") (net 2))
  (via (at 136.4 155.4) (size 0.6) (drill 0.3) (layers "F.Cu" "B.Cu") (net 2))
  (via (at 138.05 155.4) (size 0.6) (drill 0.3) (layers "F.Cu" "B.Cu") (net 2))
  (via (at 95.05 90.6) (size 0.5) (drill 0.2) (layers "F.Cu" "B.Cu") (net 2))
  (via (at 98.8 126.15) (size 0.5) (drill 0.2) (layers "F.Cu" "B.Cu") (net 2))
  (via (at 89.8 97.1) (size 0.5) (drill 0.2) (layers "F.Cu" "B.Cu") (net 2))
  (via (at 72.2 119.1) (size 0.5) (drill 0.2) (layers "F.Cu" "B.Cu") (net 2))
  (via (at 98.8 116.55) (size 0.5) (drill 0.2) (layers "F.Cu" "B.Cu") (net 2))
  (via (at 86.6 89.5) (size 0.6) (drill 0.3) (layers "F.Cu" "B.Cu") (net 2))
  (segment (start 98.8 95.15) (end 97.835 95.15) (width 0.2) (layer "B.Cu") (net 2))
  (segment (start 105 100.035) (end 105 100.95) (width 0.2) (layer "B.Cu") (net 2))
  (segment (start 95.035 100.8) (end 95.8 100.8) (width 0.15) (layer "B.Cu") (net 2))
  (segment (start 71.9 131.45) (end 71.9 130.65) (width 0.3) (layer "B.Cu") (net 2))
  (segment (start 144.675 87.91) (end 144.675 88.675) (width 0.2) (layer "B.Cu") (net 2))
  (segment (start 131.9 88.04) (end 131.9 87.275) (width 0.2) (layer "B.Cu") (net 2))
  (segment (start 131.9 87.275) (end 132.35 86.825) (width 0.2) (layer "B.Cu") (net 2))
  (segment (start 132.35 86.825) (end 133.1 86.825) (width 0.2) (layer "B.Cu") (net 2))
  (segment (start 141.6 92.925) (end 141.3 92.925) (width 0.2) (layer "B.Cu") (net 2))
  (segment (start 141.3 92.925) (end 140.9 92.525) (width 0.2) (layer "B.Cu") (net 2))
  (segment (start 141.65 89.775) (end 140.9 89.775) (width 0.2) (layer "B.Cu") (net 2))
  (segment (start 137.015 94.76) (end 137 94.775) (width 0.2) (layer "B.Cu") (net 2))
  (segment (start 137.015 93.875) (end 137.015 94.76) (width 0.2) (layer "B.Cu") (net 2))
  (segment (start 137.5 82.5) (end 137.5 83.19) (width 0.2) (layer "B.Cu") (net 2))
  (segment (start 95.775 98.1) (end 95.025 98.1) (width 0.15) (layer "B.Cu") (net 2))
  (segment (start 95.06 95.05) (end 95.825 95.05) (width 0.15) (layer "B.Cu") (net 2))
  (segment (start 78.95 148.8) (end 78.95 148.35) (width 0.2) (layer "B.Cu") (net 2))
  (segment (start 108.4 114.95) (end 109.065 114.95) (width 0.15) (layer "B.Cu") (net 2))
  (segment (start 89.8 98.1) (end 89.6 97.9) (width 0.2) (layer "B.Cu") (net 2))
  (segment (start 98.1 93) (end 98.1 92.45) (width 0.2) (layer "B.Cu") (net 2))
  (segment (start 68.65 149.25) (end 68.1 149.25) (width 0.2) (layer "B.Cu") (net 2))
  (segment (start 78.45 140.3) (end 78.95 139.8) (width 0.2) (layer "B.Cu") (net 2))
  (segment (start 110.35 121.8) (end 110.6 121.8) (width 0.15) (layer "B.Cu") (net 2))
  (segment (start 84.815 100.1) (end 85.315 100.6) (width 0.25) (layer "B.Cu") (net 2))
  (segment (start 81.975 139.285) (end 81.975 139.725) (width 0.2) (layer "B.Cu") (net 2))
  (segment (start 98.35 116.1) (end 98.8 116.55) (width 0.15) (layer "B.Cu") (net 2))
  (segment (start 84.815 98.1) (end 85.315 98.6) (width 0.25) (layer "B.Cu") (net 2))
  (segment (start 107.55 97.7) (end 107.550003 97.699997) (width 0.2) (layer "B.Cu") (net 2))
  (segment (start 98.135 119.15) (end 98.6 119.15) (width 0.15) (layer "B.Cu") (net 2))
  (segment (start 88.1 96.9) (end 88.1 95.6) (width 0.15) (layer "B.Cu") (net 2))
  (segment (start 69.5 149.25) (end 70.35 149.25) (width 0.2) (layer "B.Cu") (net 2))
  (segment (start 77.3 149.15) (end 76.95 148.8) (width 0.2) (layer "B.Cu") (net 2))
  (segment (start 84.815 94.1) (end 85.315 94.6) (width 0.25) (layer "B.Cu") (net 2))
  (segment (start 98.135 116.1) (end 98.35 116.1) (width 0.15) (layer "B.Cu") (net 2))
  (segment (start 68.725 149.175) (end 68.65 149.25) (width 0.2) (layer "B.Cu") (net 2))
  (segment (start 105 100.95) (end 105.85 100.95) (width 0.2) (layer "B.Cu") (net 2))
  (segment (start 83.15 140.2) (end 83.15 139.35) (width 0.2) (layer "B.Cu") (net 2))
  (segment (start 67.725 139.335) (end 67.725 139.825) (width 0.2) (layer "B.Cu") (net 2))
  (segment (start 95.8 99.45) (end 95.8 99.85) (width 0.15) (layer "B.Cu") (net 2))
  (segment (start 68.1 149.25) (end 67.75 148.9) (width 0.2) (layer "B.Cu") (net 2))
  (segment (start 110 120.55) (end 110 120.45) (width 0.15) (layer "B.Cu") (net 2))
  (segment (start 79.975 148.285) (end 79.975 149.125) (width 0.2) (layer "B.Cu") (net 2))
  (segment (start 98.3 120.25) (end 98.8 119.75) (width 0.15) (layer "B.Cu") (net 2))
  (segment (start 71.9 139.3) (end 71.9 140.15) (width 0.2) (layer "B.Cu") (net 2))
  (segment (start 110 121.35) (end 110.05 121.35) (width 0.15) (layer "B.Cu") (net 2))
  (segment (start 84.815 97.1) (end 85.315 97.6) (width 0.25) (layer "B.Cu") (net 2))
  (segment (start 110.25 124.8) (end 110 124.55) (width 0.15) (layer "B.Cu") (net 2))
  (segment (start 77.7 149.15) (end 78.6 149.15) (width 0.2) (layer "B.Cu") (net 2))
  (segment (start 128.265002 114.8) (end 128.85 114.8) (width 0.2) (layer "B.Cu") (net 2))
  (segment (start 84.815 96.1) (end 85.315 96.6) (width 0.25) (layer "B.Cu") (net 2))
  (segment (start 97.985 89.75) (end 98.55 89.75) (width 0.2) (layer "B.Cu") (net 2))
  (segment (start 110.765 124.8) (end 110.25 124.8) (width 0.15) (layer "B.Cu") (net 2))
  (segment (start 95.065 90.585) (end 95.05 90.6) (width 0.2) (layer "B.Cu") (net 2))
  (segment (start 87.79 95.1) (end 88.05 95.36) (width 0.15) (layer "B.Cu") (net 2))
  (segment (start 122.95 123.239723) (end 122.95 122.45) (width 0.2) (layer "B.Cu") (net 2))
  (segment (start 106.95 114.8) (end 106.8 114.95) (width 0.15) (layer "B.Cu") (net 2))
  (segment (start 77.4 140.3) (end 76.95 139.85) (width 0.2) (layer "B.Cu") (net 2))
  (segment (start 78.95 139.8) (end 78.95 139.3) (width 0.2) (layer "B.Cu") (net 2))
  (segment (start 95.5 99.15) (end 95.8 99.45) (width 0.15) (layer "B.Cu") (net 2))
  (segment (start 95.065 89.75) (end 95.065 90.585) (width 0.2) (layer "B.Cu") (net 2))
  (segment (start 101.75 114.285) (end 101.75 114.7) (width 0.15) (layer "B.Cu") (net 2))
  (segment (start 98.55 89.75) (end 98.85 90.05) (width 0.2) (layer "B.Cu") (net 2))
  (segment (start 81.45 140.15) (end 81.55 140.15) (width 0.2) (layer "B.Cu") (net 2))
  (segment (start 123 129.725) (end 122.75 129.975) (width 0.2) (layer "B.Cu") (net 2))
  (segment (start 90.15 149.9) (end 90.164 149.886) (width 0.2) (layer "B.Cu") (net 2))
  (segment (start 104.915 114.665) (end 105.2 114.95) (width 0.15) (layer "B.Cu") (net 2))
  (segment (start 80.975 139.675) (end 81.45 140.15) (width 0.2) (layer "B.Cu") (net 2))
  (segment (start 110 122.15) (end 110.35 121.8) (width 0.15) (layer "B.Cu") (net 2))
  (segment (start 98.085 126.65) (end 98.39 126.65) (width 0.15) (layer "B.Cu") (net 2))
  (segment (start 123 128.17) (end 123 129.725) (width 0.2) (layer "B.Cu") (net 2))
  (segment (start 70.35 149.25) (end 70.7 148.9) (width 0.2) (layer "B.Cu") (net 2))
  (segment (start 66.725 148.285) (end 66.725 148.725) (width 0.2) (layer "B.Cu") (net 2))
  (segment (start 98.39 126.65) (end 98.8 126.24) (width 0.15) (layer "B.Cu") (net 2))
  (segment (start 81.975 148.725) (end 81.5 149.2) (width 0.2) (layer "B.Cu") (net 2))
  (segment (start 84.815 95.1) (end 85.315 95.6) (width 0.25) (layer "B.Cu") (net 2))
  (segment (start 98.8 126.24) (end 98.8 126.15) (width 0.15) (layer "B.Cu") (net 2))
  (segment (start 107.550006 97.7) (end 107.550003 97.699997) (width 0.2) (layer "B.Cu") (net 2))
  (segment (start 84.815 101.1) (end 85.315 101.6) (width 0.25) (layer "B.Cu") (net 2))
  (segment (start 65.725 139.335) (end 65.725 139.775) (width 0.2) (layer "B.Cu") (net 2))
  (segment (start 109.065 113.9) (end 109.065 114.95) (width 0.15) (layer "B.Cu") (net 2))
  (segment (start 90.164 141.486) (end 90.5 141.15) (width 0.2) (layer "B.Cu") (net 2))
  (segment (start 90.5 141.15) (end 92.25 141.15) (width 0.2) (layer "B.Cu") (net 2))
  (segment (start 79.975 139.285) (end 79.975 139.875) (width 0.2) (layer "B.Cu") (net 2))
  (segment (start 69.5 149.25) (end 69.6 149.15) (width 0.2) (layer "B.Cu") (net 2))
  (segment (start 79.975 139.875) (end 80.3 140.2) (width 0.2) (layer "B.Cu") (net 2))
  (segment (start 110.05 121.35) (end 110.75 120.65) (width 0.15) (layer "B.Cu") (net 2))
  (segment (start 127.485 118.26) (end 127.485 118.1) (width 0.15) (layer "B.Cu") (net 2))
  (segment (start 98.6 93.35) (end 98.45 93.35) (width 0.2) (layer "B.Cu") (net 2))
  (segment (start 135.7 83.675) (end 136.185 83.19) (width 0.15) (layer "B.Cu") (net 2))
  (segment (start 66.725 148.725) (end 66.25 149.2) (width 0.2) (layer "B.Cu") (net 2))
  (segment (start 124.235 112.45) (end 124.285 112.4) (width 0.2) (layer "B.Cu") (net 2))
  (segment (start 77.965 148.285) (end 77.965 148.885) (width 0.2) (layer "B.Cu") (net 2))
  (segment (start 70.7 140.05) (end 70.7 139.3) (width 0.2) (layer "B.Cu") (net 2))
  (segment (start 90.8 100.1) (end 90.8 99.3) (width 0.15) (layer "B.Cu") (net 2))
  (segment (start 88.7 97.5) (end 88.1 96.9) (width 0.15) (layer "B.Cu") (net 2))
  (segment (start 110 123.75) (end 110.8 123.75) (width 0.15) (layer "B.Cu") (net 2))
  (segment (start 126.715 129.7) (end 126.175 129.7) (width 0.2) (layer "B.Cu") (net 2))
  (segment (start 81.5 149.2) (end 81.4 149.2) (width 0.2) (layer "B.Cu") (net 2))
  (segment (start 84.815 99.1) (end 85.315 99.6) (width 0.25) (layer "B.Cu") (net 2))
  (segment (start 128.14 118.55) (end 127.775 118.55) (width 0.15) (layer "B.Cu") (net 2))
  (segment (start 128.6 125.715) (end 128.6 125.1) (width 0.2) (layer "B.Cu") (net 2))
  (segment (start 90.164 149.886) (end 90.164 146.0742) (width 0.2) (layer "B.Cu") (net 2))
  (segment (start 95.06 96.075) (end 95.825 96.075) (width 0.15) (layer "B.Cu") (net 2))
  (segment (start 78 140.3) (end 77.4 140.3) (width 0.2) (layer "B.Cu") (net 2))
  (segment (start 104.4 113.685) (end 104.4 114.7) (width 0.15) (layer "B.Cu") (net 2))
  (segment (start 105.485 114.665) (end 105.2 114.95) (width 0.15) (layer "B.Cu") (net 2))
  (segment (start 108.465 97.7) (end 107.550006 97.7) (width 0.2) (layer "B.Cu") (net 2))
  (segment (start 67.75 148.9) (end 67.75 148.3) (width 0.2) (layer "B.Cu") (net 2))
  (segment (start 101.75 114.7) (end 102 114.95) (width 0.15) (layer "B.Cu") (net 2))
  (segment (start 110.765 125.8) (end 110.35 125.8) (width 0.15) (layer "B.Cu") (net 2))
  (segment (start 98.5 125.65) (end 98.8 125.35) (width 0.15) (layer "B.Cu") (net 2))
  (segment (start 88.7 97.9) (end 88.7 97.5) (width 0.15) (layer "B.Cu") (net 2))
  (segment (start 110.35 125.8) (end 110 126.15) (width 0.15) (layer "B.Cu") (net 2))
  (segment (start 69.6 149.15) (end 69.6 148.41) (width 0.2) (layer "B.Cu") (net 2))
  (segment (start 85.2 102.8) (end 84.4 102.8) (width 0.3) (layer "B.Cu") (net 2))
  (segment (start 83.15 131.45) (end 83.15 130.65) (width 0.3) (layer "B.Cu") (net 2))
  (segment (start 95.035 101.8) (end 95.035 100.815) (width 0.15) (layer "B.Cu") (net 2))
  (segment (start 65.725 139.775) (end 66.2 140.25) (width 0.2) (layer "B.Cu") (net 2))
  (segment (start 78 140.3) (end 78.45 140.3) (width 0.2) (layer "B.Cu") (net 2))
  (segment (start 89.6 97.9) (end 88.7 97.9) (width 0.2) (layer "B.Cu") (net 2))
  (segment (start 106.8 97.7) (end 107.55 97.7) (width 0.2) (layer "B.Cu") (net 2))
  (segment (start 110 120.45) (end 110.75 119.7) (width 0.15) (layer "B.Cu") (net 2))
  (segment (start 84.75 133.185) (end 84.75 134.05) (width 0.15) (layer "B.Cu") (net 2))
  (segment (start 76.95 148.8) (end 76.95 148.3) (width 0.2) (layer "B.Cu") (net 2))
  (segment (start 68.725 139.775) (end 68.2 140.3) (width 0.2) (layer "B.Cu") (net 2))
  (segment (start 69.725 139.335) (end 69.725 140.175) (width 0.2) (layer "B.Cu") (net 2))
  (segment (start 99.735 114.05) (end 99.735 114.99) (width 0.2) (layer "B.Cu") (net 2))
  (segment (start 78.6 149.15) (end 78.95 148.8) (width 0.2) (layer "B.Cu") (net 2))
  (segment (start 84.8 101.1) (end 84.815 101.1) (width 0.25) (layer "B.Cu") (net 2))
  (segment (start 81.975 148.285) (end 81.975 148.725) (width 0.2) (layer "B.Cu") (net 2))
  (segment (start 76.95 139.85) (end 76.95 139.3) (width 0.2) (layer "B.Cu") (net 2))
  (segment (start 128.85 114.8) (end 129.15 114.5) (width 0.2) (layer "B.Cu") (net 2))
  (segment (start 65.75 148.7) (end 65.75 148.3) (width 0.2) (layer "B.Cu") (net 2))
  (segment (start 88.115 100.415) (end 87.8 100.1) (width 0.15) (layer "B.Cu") (net 2))
  (segment (start 90.164 145.0742) (end 90.164 141.486) (width 0.2) (layer "B.Cu") (net 2))
  (segment (start 98.45 93.35) (end 98.1 93) (width 0.2) (layer "B.Cu") (net 2))
  (segment (start 77.965 148.885) (end 77.7 149.15) (width 0.2) (layer "B.Cu") (net 2))
  (segment (start 129.15 114.5) (end 129.15 113.95) (width 0.2) (layer "B.Cu") (net 2))
  (segment (start 66.725 139.335) (end 66.725 139.725) (width 0.2) (layer "B.Cu") (net 2))
  (segment (start 98.75 118.1) (end 98.8 118.15) (width 0.15) (layer "B.Cu") (net 2))
  (segment (start 98.085 125.65) (end 98.5 125.65) (width 0.15) (layer "B.Cu") (net 2))
  (segment (start 80.975 148.285) (end 80.975 148.775) (width 0.2) (layer "B.Cu") (net 2))
  (segment (start 105.95 114.665) (end 105.95 113.685) (width 0.15) (layer "B.Cu") (net 2))
  (segment (start 88.115 101.6) (end 88.115 100.415) (width 0.15) (layer "B.Cu") (net 2))
  (segment (start 89.6 97.3) (end 89.6 97.9) (width 0.2) (layer "B.Cu") (net 2))
  (segment (start 105.95 114.665) (end 105.485 114.665) (width 0.15) (layer "B.Cu") (net 2))
  (segment (start 106.95 114.25) (end 106.95 114.8) (width 0.15) (layer "B.Cu") (net 2))
  (segment (start 79.975 149.125) (end 79.95 149.15) (width 0.2) (layer "B.Cu") (net 2))
  (segment (start 98.15 118.1) (end 98.75 118.1) (width 0.15) (layer "B.Cu") (net 2))
  (segment (start 95.035 99.15) (end 95.5 99.15) (width 0.15) (layer "B.Cu") (net 2))
  (segment (start 68.725 139.335) (end 68.725 139.775) (width 0.2) (layer "B.Cu") (net 2))
  (segment (start 70.15 140.6) (end 70.7 140.05) (width 0.2) (layer "B.Cu") (net 2))
  (segment (start 70.7 148.9) (end 70.7 148.3) (width 0.2) (layer "B.Cu") (net 2))
  (segment (start 81.975 139.725) (end 81.55 140.15) (width 0.2) (layer "B.Cu") (net 2))
  (segment (start 80.975 139.285) (end 80.975 139.675) (width 0.2) (layer "B.Cu") (net 2))
  (segment (start 77.7 149.15) (end 77.3 149.15) (width 0.2) (layer "B.Cu") (net 2))
  (segment (start 104.4 114.665) (end 104.915 114.665) (width 0.15) (layer "B.Cu") (net 2))
  (segment (start 126.175 129.7) (end 125.95 129.925) (width 0.2) (layer "B.Cu") (net 2))
  (segment (start 89.8 97.1) (end 89.6 97.3) (width 0.2) (layer "B.Cu") (net 2))
  (segment (start 98.6 119.15) (end 98.8 118.95) (width 0.15) (layer "B.Cu") (net 2))
  (segment (start 77.975 140.275) (end 78 140.3) (width 0.2) (layer "B.Cu") (net 2))
  (segment (start 127.775 118.55) (end 127.485 118.26) (width 0.15) (layer "B.Cu") (net 2))
  (segment (start 80.975 148.775) (end 81.4 149.2) (width 0.2) (layer "B.Cu") (net 2))
  (segment (start 66.725 139.725) (end 66.2 140.25) (width 0.2) (layer "B.Cu") (net 2))
  (segment (start 99.735 114.95) (end 100.4 114.95) (width 0.15) (layer "B.Cu") (net 2))
  (segment (start 77.65 94.235) (end 77.65 95.250011) (width 0.15) (layer "B.Cu") (net 2))
  (segment (start 69.725 140.175) (end 70.15 140.6) (width 0.2) (layer "B.Cu") (net 2))
  (segment (start 66.25 149.2) (end 65.75 148.7) (width 0.2) (layer "B.Cu") (net 2))
  (segment (start 67.725 139.825) (end 68.2 140.3) (width 0.2) (layer "B.Cu") (net 2))
  (segment (start 102.75 114.285) (end 102.75 114.9) (width 0.15) (layer "B.Cu") (net 2))
  (segment (start 68.725 148.285) (end 68.725 149.175) (width 0.2) (layer "B.Cu") (net 2))
  (segment (start 128.4 125.915) (end 128.6 125.715) (width 0.2) (layer "B.Cu") (net 2))
  (segment (start 77.975 139.285) (end 77.975 140.275) (width 0.2) (layer "B.Cu") (net 2))
  (segment (start 121.5 117.85) (end 123.35 117.85) (width 0.3) (layer "B.Cu") (net 2))
  (segment (start 102.75 114.9) (end 102.8 114.95) (width 0.15) (layer "B.Cu") (net 2))
  (segment (start 123.435 112.45) (end 124.235 112.45) (width 0.2) (layer "B.Cu") (net 2))
  (segment (start 73.42 124.185) (end 72.42 124.185) (width 0.2) (layer "F.Cu") (net 3))
  (segment (start 86.7 119.75) (end 87.1 119.35) (width 0.15) (layer "F.Cu") (net 3))
  (segment (start 81.1 122.15) (end 81.5 121.75) (width 0.15) (layer "F.Cu") (net 3))
  (segment (start 86.7 125.35) (end 87.1 125.75) (width 0.15) (layer "F.Cu") (net 3))
  (segment (start 86.7 127.75) (end 87.1 128.15) (width 0.15) (layer "F.Cu") (net 3))
  (segment (start 85.9 128.55) (end 86.3 128.95) (width 0.15) (layer "F.Cu") (net 3))
  (segment (start 80.65 88) (end 80.65 90.25) (width 0.7) (layer "F.Cu") (net 3))
  (segment (start 80.285 127.755) (end 79.885 128.155) (width 0.15) (layer "F.Cu") (net 3))
  (segment (start 99.2 122.55) (end 98.8 122.95) (width 0.15) (layer "F.Cu") (net 3))
  (segment (start 82.5 124.55) (end 82.505 124.55) (width 0.15) (layer "F.Cu") (net 3))
  (segment (start 99.2 124.15) (end 98.8 124.55) (width 0.15) (layer "F.Cu") (net 3))
  (segment (start 82.505 124.55) (end 83.680001 123.374999) (width 0.15) (layer "F.Cu") (net 3))
  (segment (start 87.4 118.15) (end 88.1 117.45) (width 0.1) (layer "F.Cu") (net 3))
  (segment (start 79.025 119.75) (end 79.01 119.765) (width 0.15) (layer "F.Cu") (net 3))
  (segment (start 86.7 129.35) (end 86.3 128.95) (width 0.15) (layer "F.Cu") (net 3))
  (segment (start 85.9 123.75) (end 85.524999 123.374999) (width 0.15) (layer "F.Cu") (net 3))
  (segment (start 85.9 122.15) (end 85.5 121.75) (width 0.15) (layer "F.Cu") (net 3))
  (segment (start 98.8 121.35) (end 98.875 121.275) (width 0.25) (layer "F.Cu") (net 3))
  (segment (start 72.25 126.775) (end 71.4 125.925) (width 0.2) (layer "F.Cu") (net 3))
  (segment (start 85.9 126.95) (end 85.5 126.55) (width 0.15) (layer "F.Cu") (net 3))
  (segment (start 72.4 123.35) (end 72.4 124.15) (width 0.2) (layer "F.Cu") (net 3))
  (segment (start 72.425 126.775) (end 72.25 126.775) (width 0.2) (layer "F.Cu") (net 3))
  (segment (start 85.524999 123.374999) (end 83.680001 123.374999) (width 0.15) (layer "F.Cu") (net 3))
  (segment (start 81.085 129.355) (end 80.685 129.755) (width 0.15) (layer "F.Cu") (net 3))
  (segment (start 71.4 125.925) (end 71.4 125.175) (width 0.2) (layer "F.Cu") (net 3))
  (segment (start 73.32 122.3075) (end 73.32 124.18) (width 0.2) (layer "F.Cu") (net 3))
  (segment (start 80.285 123.755) (end 79.885 124.155) (width 0.15) (layer "F.Cu") (net 3))
  (segment (start 80.3 119.75) (end 79.025 119.75) (width 0.15) (layer "F.Cu") (net 3))
  (segment (start 80.3 118.15) (end 80.7 117.75) (width 0.15) (layer "F.Cu") (net 3))
  (segment (start 86.7 118.15) (end 87.4 118.15) (width 0.1) (layer "F.Cu") (net 3))
  (segment (start 99.2 121.75) (end 98.8 122.15) (width 0.15) (layer "F.Cu") (net 3))
  (segment (start 82.5 124.55) (end 81.9 124.55) (width 0.15) (layer "F.Cu") (net 3))
  (segment (start 80.285 126.155) (end 79.885 126.555) (width 0.15) (layer "F.Cu") (net 3))
  (segment (start 80.285 126.955) (end 79.885 127.355) (width 0.15) (layer "F.Cu") (net 3))
  (segment (start 99.2 120.95) (end 98.875 121.275) (width 0.15) (layer "F.Cu") (net 3))
  (via (at 87.1 119.35) (size 0.5) (drill 0.2) (layers "F.Cu" "B.Cu") (net 3))
  (via (at 81.5 121.75) (size 0.5) (drill 0.2) (layers "F.Cu" "B.Cu") (net 3))
  (via (at 87.1 125.75) (size 0.5) (drill 0.2) (layers "F.Cu" "B.Cu") (net 3))
  (via (at 87.1 128.15) (size 0.5) (drill 0.2) (layers "F.Cu" "B.Cu") (net 3))
  (via (at 80.65 89.55) (size 0.6) (drill 0.3) (layers "F.Cu" "B.Cu") (net 3))
  (via (at 80.65 90.25) (size 0.6) (drill 0.3) (layers "F.Cu" "B.Cu") (net 3))
  (via (at 80.65 88.85) (size 0.6) (drill 0.3) (layers "F.Cu" "B.Cu") (net 3))
  (via (at 77.2 124.2) (size 0.5) (drill 0.2) (layers "F.Cu" "B.Cu") (net 3))
  (via (at 72.4 123.35) (size 0.5) (drill 0.2) (layers "F.Cu" "B.Cu") (net 3))
  (via (at 79.885 126.555) (size 0.5) (drill 0.2) (layers "F.Cu" "B.Cu") (net 3))
  (via (at 72.425 126.775) (size 0.5) (drill 0.2) (layers "F.Cu" "B.Cu") (net 3))
  (via (at 98.8 124.55) (size 0.5) (drill 0.2) (layers "F.Cu" "B.Cu") (net 3))
  (via (at 79.885 128.155) (size 0.5) (drill 0.2) (layers "F.Cu" "B.Cu") (net 3))
  (via (at 86.3 128.95) (size 0.5) (drill 0.2) (layers "F.Cu" "B.Cu") (net 3))
  (via (at 79.885 127.355) (size 0.5) (drill 0.2) (layers "F.Cu" "B.Cu") (net 3))
  (via (at 98.8 122.95) (size 0.5) (drill 0.2) (layers "F.Cu" "B.Cu") (net 3))
  (via (at 98.8 121.35) (size 0.5) (drill 0.2) (layers "F.Cu" "B.Cu") (net 3))
  (via (at 79.01 119.765) (size 0.5) (drill 0.2) (layers "F.Cu" "B.Cu") (net 3))
  (via (at 98.8 122.15) (size 0.5) (drill 0.2) (layers "F.Cu" "B.Cu") (net 3))
  (via (at 85.5 121.75) (size 0.5) (drill 0.2) (layers "F.Cu" "B.Cu") (net 3))
  (via (at 79.885 124.155) (size 0.5) (drill 0.2) (layers "F.Cu" "B.Cu") (net 3))
  (via (at 88.1 117.45) (size 0.5) (drill 0.2) (layers "F.Cu" "B.Cu") (net 3))
  (via (at 87.85 126.55) (size 0.5) (drill 0.2) (layers "F.Cu" "B.Cu") (net 3))
  (via (at 80.685 129.755) (size 0.5) (drill 0.2) (layers "F.Cu" "B.Cu") (net 3))
  (via (at 82.5 124.55) (size 0.5) (drill 0.2) (layers "F.Cu" "B.Cu") (net 3))
  (via (at 80.7 117.75) (size 0.5) (drill 0.2) (layers "F.Cu" "B.Cu") (net 3))
  (via (at 85.5 126.55) (size 0.5) (drill 0.2) (layers "F.Cu" "B.Cu") (net 3))
  (segment (start 87.095 128.145) (end 87.1 128.15) (width 0.15) (layer "B.Cu") (net 3))
  (segment (start 79.765 127.235) (end 79.885 127.355) (width 0.15) (layer "B.Cu") (net 3))
  (segment (start 85.5 126.55) (end 85.5 127.3) (width 0.15) (layer "B.Cu") (net 3))
  (segment (start 80.05 117.1) (end 80.7 117.75) (width 0.15) (layer "B.Cu") (net 3))
  (segment (start 88.35 126.8) (end 88.35 127.2) (width 0.15) (layer "B.Cu") (net 3))
  (segment (start 80.775 130.545) (end 80.775 129.845) (width 0.15) (layer "B.Cu") (net 3))
  (segment (start 88.1 126.55) (end 88.35 126.8) (width 0.15) (layer "B.Cu") (net 3))
  (segment (start 87.85 126.55) (end 88.1 126.55) (width 0.15) (layer "B.Cu") (net 3))
  (segment (start 77.2 124.2) (end 79.1 124.2) (width 0.3) (layer "B.Cu") (net 3))
  (segment (start 98.8 122.15) (end 99.45 122.15) (width 0.15) (layer "B.Cu") (net 3))
  (segment (start 87.1 119.35) (end 87.85 119.35) (width 0.15) (layer "B.Cu") (net 3))
  (segment (start 82.44 124.61) (end 81.715 124.61) (width 0.15) (layer "B.Cu") (net 3))
  (segment (start 79.83 124.21) (end 79.885 124.155) (width 0.15) (layer "B.Cu") (net 3))
  (segment (start 79.805 128.235) (end 79.885 128.155) (width 0.15) (layer "B.Cu") (net 3))
  (segment (start 79.065 124.21) (end 79.83 124.21) (width 0.15) (layer "B.Cu") (net 3))
  (segment (start 98.7 124.65) (end 98.8 124.55) (width 0.15) (layer "B.Cu") (net 3))
  (segment (start 98.085 124.65) (end 98.7 124.65) (width 0.15) (layer "B.Cu") (net 3))
  (segment (start 80.685 129.755) (end 80.775 129.845) (width 0.15) (layer "B.Cu") (net 3))
  (segment (start 88.1 117.45) (end 88.8 117.45) (width 0.1) (layer "B.Cu") (net 3))
  (segment (start 86.375 128.145) (end 87.095 128.145) (width 0.15) (layer "B.Cu") (net 3))
  (segment (start 79.04 128.235) (end 79.805 128.235) (width 0.15) (layer "B.Cu") (net 3))
  (segment (start 82.5 124.55) (end 82.44 124.61) (width 0.15) (layer "B.Cu") (net 3))
  (segment (start 84.8 122.085) (end 85.135 121.75) (width 0.15) (layer "B.Cu") (net 3))
  (segment (start 98.8 121.35) (end 98.135 121.35) (width 0.15) (layer "B.Cu") (net 3))
  (segment (start 86.3 128.95) (end 86.3 129.85) (width 0.15) (layer "B.Cu") (net 3))
  (segment (start 85.135 121.75) (end 85.5 121.75) (width 0.15) (layer "B.Cu") (net 3))
  (segment (start 98.2 122.35) (end 98.8 122.95) (width 0.15) (layer "B.Cu") (net 3))
  (segment (start 79.05 127.235) (end 79.765 127.235) (width 0.15) (layer "B.Cu") (net 3))
  (segment (start 100.45 93.022851) (end 100.45 92) (width 0.2) (layer "F.Cu") (net 4))
  (segment (start 105.95 92) (end 106 91.95) (width 0.2) (layer "F.Cu") (net 4))
  (segment (start 105.95 93.022851) (end 105.95 92) (width 0.2) (layer "F.Cu") (net 4))
  (segment (start 100.45 92) (end 100.5 91.95) (width 0.2) (layer "F.Cu") (net 4))
  (via (at 100.5 91.95) (size 0.5) (drill 0.2) (layers "F.Cu" "B.Cu") (free) (net 4))
  (via (at 106 91.95) (size 0.5) (drill 0.2) (layers "F.Cu" "B.Cu") (net 4))
  (segment (start 105.4 92.55) (end 101.1 92.55) (width 0.3) (layer "In5.Cu") (net 4))
  (segment (start 101.1 92.55) (end 100.5 91.95) (width 0.3) (layer "In5.Cu") (net 4))
  (segment (start 106 91.95) (end 105.4 92.55) (width 0.3) (layer "In5.Cu") (net 4))
  (segment (start 105.95 92.865) (end 105.95 92) (width 0.2) (layer "B.Cu") (net 4))
  (segment (start 105.95 92) (end 106 91.95) (width 0.2) (layer "B.Cu") (net 4))
  (segment (start 106 91.95) (end 106 91.035) (width 0.2) (layer "B.Cu") (net 4))
  (segment (start 100.5 91.95) (end 100.5 91.085) (width 0.2) (layer "B.Cu") (net 4))
  (segment (start 100.45 91.035) (end 98.165 91.035) (width 0.2) (layer "B.Cu") (net 4))
  (segment (start 104.8 125.75) (end 105.2 126.15) (width 0.15) (layer "F.Cu") (net 5))
  (segment (start 101.6 125.75) (end 101.2 126.15) (width 0.15) (layer "F.Cu") (net 5))
  (via (at 105.2 126.15) (size 0.5) (drill 0.2) (layers "F.Cu" "B.Cu") (net 5))
  (via (at 101.2 126.15) (size 0.5) (drill 0.2) (layers "F.Cu" "B.Cu") (net 5))
  (segment (start 105.2 126.15) (end 104.7 125.65) (width 0.3) (layer "In2.Cu") (net 5))
  (segment (start 103 126.7) (end 101.75 126.7) (width 0.3) (layer "In2.Cu") (net 5))
  (segment (start 101.75 126.7) (end 101.2 126.15) (width 0.3) (layer "In2.Cu") (net 5))
  (segment (start 104.7 125.65) (end 104.05 125.65) (width 0.3) (layer "In2.Cu") (net 5))
  (segment (start 104.05 125.65) (end 103 126.7) (width 0.3) (layer "In2.Cu") (net 5))
  (segment (start 101.55 126.915) (end 100.585 126.915) (width 0.15) (layer "B.Cu") (net 5))
  (segment (start 101.55 126.5) (end 101.2 126.15) (width 0.15) (layer "B.Cu") (net 5))
  (segment (start 105.55 126.5) (end 105.2 126.15) (width 0.15) (layer "B.Cu") (net 5))
  (segment (start 100.5 127.1) (end 100.5 128.3) (width 0.15) (layer "B.Cu") (net 5))
  (segment (start 105.55 126.915) (end 105.55 126.5) (width 0.15) (layer "B.Cu") (net 5))
  (segment (start 101.55 126.915) (end 101.55 126.5) (width 0.15) (layer "B.Cu") (net 5))
  (segment (start 104 125.75) (end 104.4 126.15) (width 0.15) (layer "F.Cu") (net 6))
  (segment (start 107.2 125.75) (end 107.6 126.15) (width 0.15) (layer "F.Cu") (net 6))
  (via (at 104.4 126.15) (size 0.5) (drill 0.2) (layers "F.Cu" "B.Cu") (net 6))
  (via (at 107.6 126.15) (size 0.5) (drill 0.2) (layers "F.Cu" "B.Cu") (net 6))
  (segment (start 104.95 126.7) (end 107.05 126.7) (width 0.3) (layer "In2.Cu") (net 6))
  (segment (start 107.05 126.7) (end 107.6 126.15) (width 0.3) (layer "In2.Cu") (net 6))
  (segment (start 104.4 126.15) (end 104.95 126.7) (width 0.3) (layer "In2.Cu") (net 6))
  (segment (start 104.4 126.15) (end 104.55 126.3) (width 0.15) (layer "B.Cu") (net 6))
  (segment (start 108.55 126.915) (end 109.915 126.915) (width 0.15) (layer "B.Cu") (net 6))
  (segment (start 107.6 126.15) (end 107.785 126.15) (width 0.15) (layer "B.Cu") (net 6))
  (segment (start 104.55 126.3) (end 104.55 126.85) (width 0.15) (layer "B.Cu") (net 6))
  (segment (start 109.95 128.315) (end 109.95 127) (width 0.15) (layer "B.Cu") (net 6))
  (segment (start 107.785 126.15) (end 108.55 126.915) (width 0.15) (layer "B.Cu") (net 6))
  (segment (start 113.8 83.45) (end 111.186 83.45) (width 0.15) (layer "B.Cu") (net 7))
  (segment (start 113.8 82.4) (end 112.9 82.4) (width 0.15) (layer "B.Cu") (net 8))
  (segment (start 112.9 82.4) (end 111.34 80.84) (width 0.15) (layer "B.Cu") (net 8))
  (segment (start 111.34 80.84) (end 110.1 80.84) (width 0.15) (layer "B.Cu") (net 8))
  (segment (start 101.95 92) (end 102 91.95) (width 0.2) (layer "F.Cu") (net 9))
  (segment (start 101.95 93.022851) (end 101.95 92) (width 0.2) (layer "F.Cu") (net 9))
  (segment (start 104.45 92) (end 104.4 91.95) (width 0.2) (layer "F.Cu") (net 9))
  (segment (start 104.45 93.022851) (end 104.45 92) (width 0.2) (layer "F.Cu") (net 9))
  (via (at 102 91.95) (size 0.5) (drill 0.2) (layers "F.Cu" "B.Cu") (net 9))
  (via (at 104.4 91.95) (size 0.5) (drill 0.2) (layers "F.Cu" "B.Cu") (net 9))
  (segment (start 104.4 92.865) (end 104.4 91.95) (width 0.2) (layer "B.Cu") (net 9))
  (segment (start 104.4 91.95) (end 104.4 91.085) (width 0.2) (layer "B.Cu") (net 9))
  (segment (start 102 91.95) (end 102 91.085) (width 0.2) (layer "B.Cu") (net 9))
  (segment (start 101.95 92.865) (end 101.95 92) (width 0.2) (layer "B.Cu") (net 9))
  (segment (start 101.95 92) (end 102 91.95) (width 0.2) (layer "B.Cu") (net 9))
  (segment (start 101.95 91.035) (end 104.485 91.035) (width 0.2) (layer "B.Cu") (net 9))
  (segment (start 107.55 95.7) (end 107.6 95.75) (width 0.2) (layer "F.Cu") (net 10))
  (segment (start 106.627149 95.7) (end 107.55 95.7) (width 0.2) (layer "F.Cu") (net 10))
  (via (at 107.6 95.75) (size 0.5) (drill 0.2) (layers "F.Cu" "B.Cu") (net 10))
  (segment (start 108.515 95.7) (end 108.515 94.65) (width 0.2) (layer "B.Cu") (net 10))
  (segment (start 108.515 95.7) (end 107.65 95.7) (width 0.2) (layer "B.Cu") (net 10))
  (segment (start 107.65 95.7) (end 107.6 95.75) (width 0.2) (layer "B.Cu") (net 10))
  (segment (start 106.785 95.7) (end 107.55 95.7) (width 0.2) (layer "B.Cu") (net 10))
  (segment (start 107.55 95.7) (end 107.6 95.75) (width 0.2) (layer "B.Cu") (net 10))
  (segment (start 108.465 94.6) (end 108.465 93.635) (width 0.2) (layer "B.Cu") (net 10))
  (segment (start 90.75 61.25) (end 90.75 61.9) (width 0.25) (layer "F.Cu") (net 11))
  (segment (start 89.95 61.25) (end 89.95 62.05) (width 0.25) (layer "F.Cu") (net 11))
  (segment (start 89.95 61.25) (end 89.95 60.55) (width 0.25) (layer "F.Cu") (net 11))
  (segment (start 90.75 61.25) (end 90.75 60.5) (width 0.25) (layer "F.Cu") (net 11))
  (segment (start 92.1 60.7) (end 90.75 60.7) (width 0.25) (layer "F.Cu") (net 11))
  (segment (start 92.15 60.65) (end 92.1 60.7) (width 0.25) (layer "F.Cu") (net 11))
  (segment (start 92.15 59.85) (end 92.15 60.65) (width 0.25) (layer "F.Cu") (net 11))
  (segment (start 91.45 59.85) (end 90.5 59.85) (width 0.25) (layer "F.Cu") (net 11))
  (segment (start 91.275001 63.275001) (end 90.55 62.55) (width 0.25) (layer "F.Cu") (net 11))
  (segment (start 91.275001 64.550001) (end 91.275001 63.275001) (width 0.25) (layer "F.Cu") (net 11))
  (segment (start 90.624999 64.550001) (end 90.624999 62.624999) (width 0.25) (layer "F.Cu") (net 11))
  (segment (start 89.975001 64.550001) (end 89.975001 62.475001) (width 0.25) (layer "F.Cu") (net 11))
  (segment (start 86.485 78.9) (end 86.485 80.015) (width 0.5) (layer "F.Cu") (net 11))
  (segment (start 81.05 73.035) (end 81.05 71.4) (width 0.3) (layer "F.Cu") (net 11))
  (segment (start 77.25 73.15) (end 80.935 73.15) (width 0.3) (layer "F.Cu") (net 11))
  (segment (start 80.935 73.15) (end 81.05 73.035) (width 0.3) (layer "F.Cu") (net 11))
  (segment (start 79.050857 77.475) (end 80.925 77.475) (width 0.3) (layer "F.Cu") (net 11))
  (via (at 116.814056 81.268104) (size 0.5) (drill 0.2) (layers "F.Cu" "B.Cu") (net 11))
  (via (at 116.814056 82.018104) (size 0.5) (drill 0.2) (layers "F.Cu" "B.Cu") (net 11))
  (via (at 117.514056 79.218104) (size 0.5) (drill 0.2) (layers "F.Cu" "B.Cu") (net 11))
  (via (at 117.514056 80.268104) (size 0.5) (drill 0.2) (layers "F.Cu" "B.Cu") (net 11))
  (via (at 116.814056 80.268104) (size 0.5) (drill 0.2) (layers "F.Cu" "B.Cu") (net 11))
  (via (at 116.814056 79.218104) (size 0.5) (drill 0.2) (layers "F.Cu" "B.Cu") (net 11))
  (via (at 81.875 79.05) (size 0.6) (drill 0.3) (layers "F.Cu" "B.Cu") (net 11))
  (via (at 83.075 79.05) (size 0.6) (drill 0.3) (layers "F.Cu" "B.Cu") (net 11))
  (via (at 91.45 59.85) (size 0.6) (drill 0.3) (layers "F.Cu" "B.Cu") (net 11))
  (via (at 92.15 59.85) (size 0.6) (drill 0.3) (layers "F.Cu" "B.Cu") (net 11))
  (via (at 89.95 61.25) (size 0.6) (drill 0.3) (layers "F.Cu" "B.Cu") (net 11))
  (via (at 90.75 61.25) (size 0.6) (drill 0.3) (layers "F.Cu" "B.Cu") (net 11))
  (via (at 81.275 78.6) (size 0.6) (drill 0.3) (layers "F.Cu" "B.Cu") (net 11))
  (via (at 81.275 79.65) (size 0.6) (drill 0.3) (layers "F.Cu" "B.Cu") (net 11))
  (via (at 84.025 71.3) (size 0.6) (drill 0.3) (layers "F.Cu" "B.Cu") (net 11))
  (via (at 82.475 79.65) (size 0.6) (drill 0.3) (layers "F.Cu" "B.Cu") (net 11))
  (via (at 87.99 83.72) (size 0.5) (drill 0.2) (layers "F.Cu" "B.Cu") (net 11))
  (via (at 83.525 71.9) (size 0.6) (drill 0.3) (layers "F.Cu" "B.Cu") (net 11))
  (via (at 83.525 70.725) (size 0.6) (drill 0.3) (layers "F.Cu" "B.Cu") (net 11))
  (via (at 81.875 78.1) (size 0.6) (drill 0.3) (layers "F.Cu" "B.Cu") (net 11))
  (via (at 82.475 78.6) (size 0.6) (drill 0.3) (layers "F.Cu" "B.Cu") (net 11))
  (via (at 84.925 71.3) (size 0.6) (drill 0.3) (layers "F.Cu" "B.Cu") (net 11))
  (via (at 123.35 84.4) (size 0.5) (drill 0.2) (layers "F.Cu" "B.Cu") (net 11))
  (via (at 85.425 70.7) (size 0.6) (drill 0.3) (layers "F.Cu" "B.Cu") (net 11))
  (via (at 84.475 70.7) (size 0.6) (drill 0.3) (layers "F.Cu" "B.Cu") (net 11))
  (via (at 75.775 84.189479) (size 0.5) (drill 0.2) (layers "F.Cu" "B.Cu") (net 11))
  (via (at 83.075 78.1) (size 0.6) (drill 0.3) (layers "F.Cu" "B.Cu") (net 11))
  (segment (start 74.685 87.55) (end 74.98 87.55) (width 0.2) (layer "B.Cu") (net 11))
  (segment (start 118.394056 83.598104) (end 116.814056 82.018104) (width 0.15) (layer "B.Cu") (net 11))
  (segment (start 87.2 84.51) (end 87.99 83.72) (width 0.2) (layer "B.Cu") (net 11))
  (segment (start 89.635 84.52) (end 88.835 83.72) (width 0.2) (layer "B.Cu") (net 11))
  (segment (start 75.98 86.55) (end 75.98 84.394479) (width 0.2) (layer "B.Cu") (net 11))
  (segment (start 118.394056 89.493104) (end 118.394056 83.598104) (width 0.15) (layer "B.Cu") (net 11))
  (segment (start 127.425 124.15) (end 125.7 122.425) (width 0.5) (layer "B.Cu") (net 11))
  (segment (start 87.866002 87.55) (end 88.200001 87.216001) (width 0.2) (layer "B.Cu") (net 11))
  (segment (start 83.535 87.55) (end 87.866002 87.55) (width 0.2) (layer "B.Cu") (net 11))
  (segment (start 89.635 87.55) (end 89.635 84.52) (width 0.2) (layer "B.Cu") (net 11))
  (segment (start 125.7 122.425) (end 125.7 105.95) (width 0.5) (layer "B.Cu") (net 11))
  (segment (start 74.98 87.55) (end 75.98 86.55) (width 0.2) (layer "B.Cu") (net 11))
  (segment (start 123.85 104.1) (end 123.85 84.9) (width 0.5) (layer "B.Cu") (net 11))
  (segment (start 87.2 85.67) (end 87.2 84.51) (width 0.2) (layer "B.Cu") (net 11))
  (segment (start 88.200001 87.216001) (end 88.200001 86.670001) (width 0.2) (layer "B.Cu") (net 11))
  (segment (start 88.835 83.72) (end 87.99 83.72) (width 0.2) (layer "B.Cu") (net 11))
  (segment (start 88.200001 86.670001) (end 87.2 85.67) (width 0.2) (layer "B.Cu") (net 11))
  (segment (start 123.85 84.9) (end 123.35 84.4) (width 0.5) (layer "B.Cu") (net 11))
  (segment (start 75.98 84.394479) (end 75.775 84.189479) (width 0.2) (layer "B.Cu") (net 11))
  (segment (start 125.7 105.95) (end 123.85 104.1) (width 0.5) (layer "B.Cu") (net 11))
  (segment (start 87.4 143.535) (end 86.685 143.535) (width 0.15) (layer "F.Cu") (net 12))
  (segment (start 89.715 143.6) (end 87.35 143.6) (width 0.2) (layer "F.Cu") (net 12))
  (segment (start 74.55 87.95) (end 74.55 89.5) (width 0.7) (layer "F.Cu") (net 12))
  (segment (start 86.685 143.535) (end 86.65 143.5) (width 0.15) (layer "F.Cu") (net 12))
  (via (at 74.55 89.5) (size 0.6) (drill 0.3) (layers "F.Cu" "B.Cu") (net 12))
  (via (at 74.55 88.8) (size 0.6) (drill 0.3) (layers "F.Cu" "B.Cu") (net 12))
  (via (at 86.65 143.5) (size 0.5) (drill 0.2) (layers "F.Cu" "B.Cu") (net 12))
  (segment (start 75.55 118.1) (end 79.45 114.2) (width 0.5) (layer "B.Cu") (net 12))
  (segment (start 79.45 92.45) (end 76.5 89.5) (width 0.5) (layer "B.Cu") (net 12))
  (segment (start 74.55 88.8) (end 74.55 89.5) (width 0.5) (layer "B.Cu") (net 12))
  (segment (start 76.15 140.95) (end 75.55 140.35) (width 0.5) (layer "B.Cu") (net 12))
  (segment (start 79.45 114.2) (end 79.45 92.45) (width 0.5) (layer "B.Cu") (net 12))
  (segment (start 84.1 140.95) (end 76.15 140.95) (width 0.5) (layer "B.Cu") (net 12))
  (segment (start 86.65 143.5) (end 84.1 140.95) (width 0.5) (layer "B.Cu") (net 12))
  (segment (start 76.5 89.5) (end 74.55 89.5) (width 0.5) (layer "B.Cu") (net 12))
  (segment (start 75.55 140.35) (end 75.55 118.1) (width 0.5) (layer "B.Cu") (net 12))
  (segment (start 97 82.5) (end 98.66 80.84) (width 0.15) (layer "B.Cu") (net 13))
  (segment (start 98.66 80.84) (end 99.94 80.84) (width 0.15) (layer "B.Cu") (net 13))
  (segment (start 95.485 82.5) (end 97 82.5) (width 0.15) (layer "B.Cu") (net 13))
  (segment (start 95.485 83.5) (end 98.804 83.5) (width 0.15) (layer "B.Cu") (net 14))
  (segment (start 86.35 65.8) (end 80.8 65.8) (width 0.5) (layer "F.Cu") (net 15))
  (segment (start 126.93 166.167501) (end 126.93 167.446) (width 0.15) (layer "F.Cu") (net 16))
  (segment (start 126.805 164.88) (end 126.805 166.042501) (width 0.15) (layer "F.Cu") (net 16))
  (segment (start 126.805 166.042501) (end 126.93 166.167501) (width 0.15) (layer "F.Cu") (net 16))
  (segment (start 126.93 167.446) (end 126.55 167.826) (width 0.15) (layer "F.Cu") (net 16))
  (segment (start 129.805 164.88) (end 129.805 166.042501) (width 0.15) (layer "F.Cu") (net 17))
  (segment (start 129.93 166.167501) (end 129.93 167.446) (width 0.15) (layer "F.Cu") (net 17))
  (segment (start 129.93 167.446) (end 129.55 167.826) (width 0.15) (layer "F.Cu") (net 17))
  (segment (start 129.805 166.042501) (end 129.93 166.167501) (width 0.15) (layer "F.Cu") (net 17))
  (segment (start 132.93 166.167501) (end 132.93 167.446) (width 0.15) (layer "F.Cu") (net 18))
  (segment (start 132.805 166.042501) (end 132.93 166.167501) (width 0.15) (layer "F.Cu") (net 18))
  (segment (start 132.93 167.446) (end 132.55 167.826) (width 0.15) (layer "F.Cu") (net 18))
  (segment (start 132.805 164.88) (end 132.805 166.042501) (width 0.15) (layer "F.Cu") (net 18))
  (segment (start 116 142.75) (end 121.2 142.75) (width 0.15) (layer "F.Cu") (net 19))
  (segment (start 95.68 131.03) (end 95.68 134.236432) (width 0.1) (layer "F.Cu") (net 19))
  (segment (start 131.375 85.65) (end 131.925 85.1) (width 0.15) (layer "F.Cu") (net 19))
  (segment (start 136.025 75.905) (end 136.025 71.955) (width 0.15) (layer "F.Cu") (net 19))
  (segment (start 95.68 134.236432) (end 95.300022 134.61641) (width 0.1) (layer "F.Cu") (net 19))
  (segment (start 137.175 79.05) (end 136.025 77.9) (width 0.15) (layer "F.Cu") (net 19))
  (segment (start 133.775 85.1) (end 134 85.325) (width 0.15) (layer "F.Cu") (net 19))
  (segment (start 136.025 71.955) (end 134.625 70.555) (width 0.15) (layer "F.Cu") (net 19))
  (segment (start 95.300022 134.61641) (end 95.300022 137.852886) (width 0.1) (layer "F.Cu") (net 19))
  (segment (start 95.2 130.55) (end 95.68 131.03) (width 0.1) (layer "F.Cu") (net 19))
  (segment (start 121.2 142.75) (end 126.45 137.5) (width 0.15) (layer "F.Cu") (net 19))
  (segment (start 134 85.325) (end 134 86.0875) (width 0.15) (layer "F.Cu") (net 19))
  (segment (start 131.925 85.1) (end 133.775 85.1) (width 0.15) (layer "F.Cu") (net 19))
  (segment (start 136.025 77.9) (end 136.025 75.905) (width 0.15) (layer "F.Cu") (net 19))
  (segment (start 98.697132 141.249996) (end 100.5 141.249996) (width 0.1) (layer "F.Cu") (net 19))
  (segment (start 95.300022 137.852886) (end 98.697132 141.249996) (width 0.1) (layer "F.Cu") (net 19))
  (via (at 131.375 85.65) (size 0.5) (drill 0.2) (layers "F.Cu" "B.Cu") (net 19))
  (via (at 137.175 79.05) (size 0.5) (drill 0.2) (layers "F.Cu" "B.Cu") (net 19))
  (via (at 116 142.75) (size 0.5) (drill 0.2) (layers "F.Cu" "B.Cu") (net 19))
  (via (at 100.5 141.249996) (size 0.5) (drill 0.2) (layers "F.Cu" "B.Cu") (net 19))
  (via (at 126.45 137.5) (size 0.5) (drill 0.2) (layers "F.Cu" "B.Cu") (net 19))
  (segment (start 137.175 80.325) (end 132.375 85.125) (width 0.15) (layer "In2.Cu") (net 19))
  (segment (start 132.375 85.125) (end 131.9 85.125) (width 0.15) (layer "In2.Cu") (net 19))
  (segment (start 137.175 79.05) (end 137.175 80.325) (width 0.15) (layer "In2.Cu") (net 19))
  (segment (start 131.9 85.125) (end 131.375 85.65) (width 0.15) (layer "In2.Cu") (net 19))
  (segment (start 131.375 85.65) (end 131.375 86.525) (width 0.15) (layer "B.Cu") (net 19))
  (segment (start 100.5 152.714278) (end 100.5 141.249996) (width 0.15) (layer "B.Cu") (net 19))
  (segment (start 111.500022 138.250022) (end 116 142.75) (width 0.15) (layer "B.Cu") (net 19))
  (segment (start 102.04641 138.250022) (end 111.500022 138.250022) (width 0.15) (layer "B.Cu") (net 19))
  (segment (start 130.875 104.711856) (end 136.295838 110.132694) (width 0.15) (layer "B.Cu") (net 19))
  (segment (start 100.5 141.249996) (end 100.5 139.796432) (width 0.15) (layer "B.Cu") (net 19))
  (segment (start 136.295838 129.544162) (end 128.34 137.5) (width 0.15) (layer "B.Cu") (net 19))
  (segment (start 111.09 177.345) (end 111.09 163.304278) (width 0.15) (layer "B.Cu") (net 19))
  (segment (start 100.5 139.796432) (end 102.04641 138.250022) (width 0.15) (layer "B.Cu") (net 19))
  (segment (start 130.875 87.025) (end 130.875 104.711856) (width 0.15) (layer "B.Cu") (net 19))
  (segment (start 111.09 163.304278) (end 100.5 152.714278) (width 0.15) (layer "B.Cu") (net 19))
  (segment (start 131.375 86.525) (end 130.875 87.025) (width 0.15) (layer "B.Cu") (net 19))
  (segment (start 128.34 137.5) (end 126.45 137.5) (width 0.15) (layer "B.Cu") (net 19))
  (segment (start 136.295838 110.132694) (end 136.295838 129.544162) (width 0.15) (layer "B.Cu") (net 19))
  (segment (start 133.5 85.525) (end 133.5 86.0875) (width 0.15) (layer "F.Cu") (net 20))
  (segment (start 96 134.27) (end 95.550033 134.719967) (width 0.1) (layer "F.Cu") (net 20))
  (segment (start 98.350704 140.55) (end 101.1 140.55) (width 0.1) (layer "F.Cu") (net 20))
  (segment (start 136.525 75.905) (end 136.525 77.525) (width 0.15) (layer "F.Cu") (net 20))
  (segment (start 95.550033 134.719967) (end 95.550033 137.749329) (width 0.1) (layer "F.Cu") (net 20))
  (segment (start 136.525 77.525) (end 137.65 78.65) (width 0.15) (layer "F.Cu") (net 20))
  (segment (start 95.2 128.95) (end 96 129.75) (width 0.1) (layer "F.Cu") (net 20))
  (segment (start 132.375 85.375) (end 133.35 85.375) (width 0.15) (layer "F.Cu") (net 20))
  (segment (start 132.075 85.675) (end 132.375 85.375) (width 0.15) (layer "F.Cu") (net 20))
  (segment (start 95.550033 137.749329) (end 98.350704 140.55) (width 0.1) (layer "F.Cu") (net 20))
  (segment (start 121.25715 143.45) (end 126.45 138.25715) (width 0.15) (layer "F.Cu") (net 20))
  (segment (start 115.7 143.45) (end 121.25715 143.45) (width 0.15) (layer "F.Cu") (net 20))
  (segment (start 96 129.75) (end 96 134.27) (width 0.1) (layer "F.Cu") (net 20))
  (segment (start 133.35 85.375) (end 133.5 85.525) (width 0.15) (layer "F.Cu") (net 20))
  (segment (start 136.525 70.655) (end 136.525 75.925) (width 0.15) (layer "F.Cu") (net 20))
  (via (at 137.65 78.65) (size 0.5) (drill 0.2) (layers "F.Cu" "B.Cu") (net 20))
  (via (at 101.1 140.55) (size 0.5) (drill 0.2) (layers "F.Cu" "B.Cu") (net 20))
  (via (at 115.7 143.45) (size 0.5) (drill 0.2) (layers "F.Cu" "B.Cu") (net 20))
  (via (at 126.45 138.25715) (size 0.5) (drill 0.2) (layers "F.Cu" "B.Cu") (net 20))
  (via (at 132.075 85.675) (size 0.5) (drill 0.2) (layers "F.Cu" "B.Cu") (net 20))
  (segment (start 132.075 85.675) (end 132.275 85.675) (width 0.15) (layer "In2.Cu") (net 20))
  (segment (start 132.275 85.675) (end 137.65 80.3) (width 0.15) (layer "In2.Cu") (net 20))
  (segment (start 137.65 80.3) (end 137.65 78.65) (width 0.15) (layer "In2.Cu") (net 20))
  (segment (start 110.750033 138.500033) (end 115.7 143.45) (width 0.15) (layer "B.Cu") (net 20))
  (segment (start 136.649394 129.640606) (end 128.03285 138.25715) (width 0.15) (layer "B.Cu") (net 20))
  (segment (start 101.1 152.85) (end 101.1 140.55) (width 0.15) (layer "B.Cu") (net 20))
  (segment (start 131.2 87.15) (end 131.2 104.506522) (width 0.15) (layer "B.Cu") (net 20))
  (segment (start 102.179967 138.500033) (end 110.750033 138.500033) (width 0.15) (layer "B.Cu") (net 20))
  (segment (start 101.1 140.55) (end 101.1 139.58) (width 0.15) (layer "B.Cu") (net 20))
  (segment (start 128.03285 138.25715) (end 126.45 138.25715) (width 0.15) (layer "B.Cu") (net 20))
  (segment (start 111.69 177.345) (end 111.69 163.44) (width 0.15) (layer "B.Cu") (net 20))
  (segment (start 111.69 163.44) (end 101.1 152.85) (width 0.15) (layer "B.Cu") (net 20))
  (segment (start 101.1 139.58) (end 102.179967 138.500033) (width 0.15) (layer "B.Cu") (net 20))
  (segment (start 131.2 104.506522) (end 136.649394 109.955916) (width 0.15) (layer "B.Cu") (net 20))
  (segment (start 136.649394 109.955916) (end 136.649394 129.640606) (width 0.15) (layer "B.Cu") (net 20))
  (segment (start 132.075 85.675) (end 132.075 86.275) (width 0.15) (layer "B.Cu") (net 20))
  (segment (start 132.075 86.275) (end 131.2 87.15) (width 0.15) (layer "B.Cu") (net 20))
  (segment (start 131.5 84.825) (end 134.15 84.825) (width 0.15) (layer "F.Cu") (net 21))
  (segment (start 138.525 77.35) (end 137.975 77.9) (width 0.15) (layer "F.Cu") (net 21))
  (segment (start 95.195 131.335) (end 94.795 131.735) (width 0.15) (layer "F.Cu") (net 21))
  (segment (start 130.65 85.675) (end 131.5 84.825) (width 0.15) (layer "F.Cu") (net 21))
  (segment (start 120.474999 141.975001) (end 126.45 136) (width 0.15) (layer "F.Cu") (net 21))
  (segment (start 94.8 138.149996) (end 99.2 142.549996) (width 0.1) (layer "F.Cu") (net 21))
  (segment (start 138.525 70.655) (end 138.525 75.9) (width 0.15) (layer "F.Cu") (net 21))
  (segment (start 117.125001 141.975001) (end 120.474999 141.975001) (width 0.15) (layer "F.Cu") (net 21))
  (segment (start 134.5 85.175) (end 134.5 86.0875) (width 0.15) (layer "F.Cu") (net 21))
  (segment (start 134.15 84.825) (end 134.5 85.175) (width 0.15) (layer "F.Cu") (net 21))
  (segment (start 116.6 141.45) (end 117.125001 141.975001) (width 0.15) (layer "F.Cu") (net 21))
  (segment (start 138.525 75.905) (end 138.525 77.35) (width 0.15) (layer "F.Cu") (net 21))
  (segment (start 94.8 133.65) (end 94.8 138.149996) (width 0.1) (layer "F.Cu") (net 21))
  (via (at 126.45 136) (size 0.5) (drill 0.2) (layers "F.Cu" "B.Cu") (net 21))
  (via (at 137.975 77.9) (size 0.5) (drill 0.2) (layers "F.Cu" "B.Cu") (net 21))
  (via (at 116.6 141.45) (size 0.5) (drill 0.2) (layers "F.Cu" "B.Cu") (net 21))
  (via (at 130.65 85.675) (size 0.5) (drill 0.2) (layers "F.Cu" "B.Cu") (net 21))
  (via (at 99.2 142.549996) (size 0.5) (drill 0.2) (layers "F.Cu" "B.Cu") (net 21))
  (via (at 94.795 131.735) (size 0.5) (drill 0.2) (layers "F.Cu" "B.Cu") (net 21))
  (via (at 94.8 133.65) (size 0.5) (drill 0.2) (layers "F.Cu" "B.Cu") (net 21))
  (segment (start 136.675 80.35) (end 136.675 78.675) (width 0.15) (layer "In2.Cu") (net 21))
  (segment (start 131.5 84.825) (end 132.2 84.825) (width 0.15) (layer "In2.Cu") (net 21))
  (segment (start 130.65 85.675) (end 131.5 84.825) (width 0.15) (layer "In2.Cu") (net 21))
  (segment (start 136.675 78.675) (end 137.45 77.9) (width 0.15) (layer "In2.Cu") (net 21))
  (segment (start 137.45 77.9) (end 137.975 77.9) (width 0.15) (layer "In2.Cu") (net 21))
  (segment (start 132.2 84.825) (end 136.675 80.35) (width 0.15) (layer "In2.Cu") (net 21))
  (segment (start 95.25 132.19) (end 95.25 133.2) (width 0.1) (layer "B.Cu") (net 21))
  (segment (start 94.795 131.735) (end 95.25 132.19) (width 0.1) (layer "B.Cu") (net 21))
  (segment (start 130.65 85.675) (end 130.65 85.7) (width 0.15) (layer "B.Cu") (net 21))
  (segment (start 116.146447 141.45) (end 116.6 141.45) (width 0.15) (layer "B.Cu") (net 21))
  (segment (start 130.2 105.097524) (end 135.588726 110.48625) (width 0.15) (layer "B.Cu") (net 21))
  (segment (start 99.2 152.262836) (end 99.2 142.85) (width 0.15) (layer "B.Cu") (net 21))
  (segment (start 109.89 177.345) (end 109.89 162.952836) (width 0.15) (layer "B.Cu") (net 21))
  (segment (start 135.588726 129.301274) (end 128.89 136) (width 0.15) (layer "B.Cu") (net 21))
  (segment (start 99.2 142.549996) (end 99.2 140.389296) (width 0.15) (layer "B.Cu") (net 21))
  (segment (start 130.2 86.15) (end 130.2 105.097524) (width 0.15) (layer "B.Cu") (net 21))
  (segment (start 99.2 140.389296) (end 101.839296 137.75) (width 0.15) (layer "B.Cu") (net 21))
  (segment (start 128.89 136) (end 126.45 136) (width 0.15) (layer "B.Cu") (net 21))
  (segment (start 95.25 133.2) (end 94.8 133.65) (width 0.1) (layer "B.Cu") (net 21))
  (segment (start 99.2 142.85) (end 99.2 142.549996) (width 0.15) (layer "B.Cu") (net 21))
  (segment (start 101.839296 137.75) (end 112.446447 137.75) (width 0.15) (layer "B.Cu") (net 21))
  (segment (start 130.65 85.7) (end 130.2 86.15) (width 0.15) (layer "B.Cu") (net 21))
  (segment (start 112.446447 137.75) (end 116.146447 141.45) (width 0.15) (layer "B.Cu") (net 21))
  (segment (start 109.89 162.952836) (end 99.2 152.262836) (width 0.15) (layer "B.Cu") (net 21))
  (segment (start 135.588726 110.48625) (end 135.588726 129.301274) (width 0.15) (layer "B.Cu") (net 21))
  (segment (start 131.3 86.775) (end 132.8125 86.775) (width 0.15) (layer "F.Cu") (net 22))
  (segment (start 120.800001 142.399999) (end 126.45 136.75) (width 0.15) (layer "F.Cu") (net 22))
  (segment (start 116.3 142.15) (end 116.549999 142.399999) (width 0.15) (layer "F.Cu") (net 22))
  (segment (start 138.3 78.65) (end 139.025 77.925) (width 0.15) (layer "F.Cu") (net 22))
  (segment (start 95.050011 134.299989) (end 95.050011 137.956443) (width 0.1) (layer "F.Cu") (net 22))
  (segment (start 140.625 70.555) (end 139.025 72.155) (width 0.15) (layer "F.Cu") (net 22))
  (segment (start 139.025 72.155) (end 139.025 75.875) (width 0.15) (layer "F.Cu") (net 22))
  (segment (start 95.2 132.95) (end 95.2 134.15) (width 0.1) (layer "F.Cu") (net 22))
  (segment (start 95.050011 137.956443) (end 98.943568 141.85) (width 0.1) (layer "F.Cu") (net 22))
  (segment (start 139.025 77.925) (end 139.025 75.975) (width 0.15) (layer "F.Cu") (net 22))
  (segment (start 130.9 86.375) (end 131.3 86.775) (width 0.15) (layer "F.Cu") (net 22))
  (segment (start 95.2 134.15) (end 95.050011 134.299989) (width 0.1) (layer "F.Cu") (net 22))
  (segment (start 98.943568 141.85) (end 99.8 141.85) (width 0.1) (layer "F.Cu") (net 22))
  (segment (start 116.549999 142.399999) (end 120.800001 142.399999) (width 0.15) (layer "F.Cu") (net 22))
  (via (at 99.8 141.85) (size 0.5) (drill 0.2) (layers "F.Cu" "B.Cu") (net 22))
  (via (at 116.3 142.15) (size 0.5) (drill 0.2) (layers "F.Cu" "B.Cu") (net 22))
  (via (at 138.3 78.65) (size 0.5) (drill 0.2) (layers "F.Cu" "B.Cu") (net 22))
  (via (at 130.9 86.375) (size 0.5) (drill 0.2) (layers "F.Cu" "B.Cu") (net 22))
  (via (at 126.45 136.75) (size 0.5) (drill 0.2) (layers "F.Cu" "B.Cu") (net 22))
  (segment (start 132.175 86.225) (end 138.3 80.1) (width 0.15) (layer "In2.Cu") (net 22))
  (segment (start 131.05 86.225) (end 132.175 86.225) (width 0.15) (layer "In2.Cu") (net 22))
  (segment (start 130.9 86.375) (end 131.05 86.225) (width 0.15) (layer "In2.Cu") (net 22))
  (segment (start 138.3 80.1) (end 138.3 78.65) (width 0.15) (layer "In2.Cu") (net 22))
  (segment (start 135.942282 129.397718) (end 128.59 136.75) (width 0.15) (layer "B.Cu") (net 22))
  (segment (start 130.55 86.725) (end 130.55 104.91719) (width 0.15) (layer "B.Cu") (net 22))
  (segment (start 99.8 152.438557) (end 99.8 141.85) (width 0.15) (layer "B.Cu") (net 22))
  (segment (start 112.150011 138.000011) (end 116.3 142.15) (width 0.15) (layer "B.Cu") (net 22))
  (segment (start 135.942282 110.309472) (end 135.942282 129.397718) (width 0.15) (layer "B.Cu") (net 22))
  (segment (start 130.55 104.91719) (end 135.942282 110.309472) (width 0.15) (layer "B.Cu") (net 22))
  (segment (start 110.49 177.345) (end 110.49 163.128557) (width 0.15) (layer "B.Cu") (net 22))
  (segment (start 110.49 163.128557) (end 99.8 152.438557) (width 0.15) (layer "B.Cu") (net 22))
  (segment (start 128.59 136.75) (end 126.45 136.75) (width 0.15) (layer "B.Cu") (net 22))
  (segment (start 99.8 141.85) (end 99.8 140.142864) (width 0.15) (layer "B.Cu") (net 22))
  (segment (start 130.9 86.375) (end 130.55 86.725) (width 0.15) (layer "B.Cu") (net 22))
  (segment (start 99.8 140.142864) (end 101.942853 138.000011) (width 0.15) (layer "B.Cu") (net 22))
  (segment (start 101.942853 138.000011) (end 112.150011 138.000011) (width 0.15) (layer "B.Cu") (net 22))
  (segment (start 115.2 108.95) (end 115.6 108.55) (width 0.15) (layer "F.Cu") (net 23))
  (via (at 115.6 108.55) (size 0.5) (drill 0.2) (layers "F.Cu" "B.Cu") (net 23))
  (via (at 94.107 169.2275) (size 0.5) (drill 0.2) (layers "F.Cu" "B.Cu") (net 23))
  (segment (start 102.1715 162.7505) (end 95.6945 169.2275) (width 0.1) (layer "In5.Cu") (net 23))
  (segment (start 135.95 135.648488) (end 108.847988 162.7505) (width 0.1) (layer "In5.Cu") (net 23))
  (segment (start 108.847988 162.7505) (end 102.1715 162.7505) (width 0.1) (layer "In5.Cu") (net 23))
  (segment (start 95.6945 169.2275) (end 94.170512 169.2275) (width 0.1) (layer "In5.Cu") (net 23))
  (segment (start 115.6 108.55) (end 117.6 108.55) (width 0.1) (layer "In5.Cu") (net 23))
  (segment (start 119.353772 108.5) (end 133.2 108.5) (width 0.1) (layer "In5.Cu") (net 23))
  (segment (start 117.6 108.55) (end 118.1 109.05) (width 0.1) (layer "In5.Cu") (net 23))
  (segment (start 94.170512 169.2275) (end 94.107012 169.291) (width 0.1) (layer "In5.Cu") (net 23))
  (segment (start 135.95 111.25) (end 135.95 135.648488) (width 0.1) (layer "In5.Cu") (net 23))
  (segment (start 133.2 108.5) (end 135.95 111.25) (width 0.1) (layer "In5.Cu") (net 23))
  (segment (start 118.1 109.05) (end 118.803772 109.05) (width 0.1) (layer "In5.Cu") (net 23))
  (segment (start 118.803772 109.05) (end 119.353772 108.5) (width 0.1) (layer "In5.Cu") (net 23))
  (segment (start 92.289999 169.838001) (end 92.9005 169.2275) (width 0.1) (layer "B.Cu") (net 23))
  (segment (start 93.29 177.145) (end 93.29 174.697) (width 0.1) (layer "B.Cu") (net 23))
  (segment (start 92.9005 169.2275) (end 94.043512 169.2275) (width 0.1) (layer "B.Cu") (net 23))
  (segment (start 93.29 174.697) (end 92.289999 173.696999) (width 0.1) (layer "B.Cu") (net 23))
  (segment (start 92.289999 173.696999) (end 92.289999 169.838001) (width 0.1) (layer "B.Cu") (net 23))
  (segment (start 116.95 108.15) (end 117.6 108.8) (width 0.1) (layer "F.Cu") (net 24))
  (segment (start 116 108.15) (end 116.95 108.15) (width 0.1) (layer "F.Cu") (net 24))
  (segment (start 117.6 108.8) (end 117.6 109.15) (width 0.1) (layer "F.Cu") (net 24))
  (via (at 117.6 109.15) (size 0.5) (drill 0.2) (layers "F.Cu" "B.Cu") (net 24))
  (via (at 94.69566 168.783) (size 0.5) (drill 0.2) (layers "F.Cu" "B.Cu") (net 24))
  (segment (start 117.6 109.15) (end 117.75 109.3) (width 0.1) (layer "In5.Cu") (net 24))
  (segment (start 108.748432 162.4965) (end 102.0445 162.4965) (width 0.1) (layer "In5.Cu") (net 24))
  (segment (start 94.870548 168.783) (end 94.69566 168.957888) (width 0.1) (layer "In5.Cu") (net 24))
  (segment (start 133.05 108.75) (end 135.7 111.4) (width 0.1) (layer "In5.Cu") (net 24))
  (segment (start 102.0445 162.4965) (end 95.758 168.783) (width 0.1) (layer "In5.Cu") (net 24))
  (segment (start 117.75 109.3) (end 118.987878 109.3) (width 0.1) (layer "In5.Cu") (net 24))
  (segment (start 118.987878 109.3) (end 119.537878 108.75) (width 0.1) (layer "In5.Cu") (net 24))
  (segment (start 119.537878 108.75) (end 133.05 108.75) (width 0.1) (layer "In5.Cu") (net 24))
  (segment (start 135.7 135.544932) (end 108.748432 162.4965) (width 0.1) (layer "In5.Cu") (net 24))
  (segment (start 95.758 168.783) (end 94.870548 168.783) (width 0.1) (layer "In5.Cu") (net 24))
  (segment (start 135.7 111.4) (end 135.7 135.544932) (width 0.1) (layer "In5.Cu") (net 24))
  (segment (start 92.837 168.783) (end 94.520772 168.783) (width 0.1) (layer "B.Cu") (net 24))
  (segment (start 92.98 175.895) (end 92.98 174.895) (width 0.1) (layer "B.Cu") (net 24))
  (segment (start 92.075 169.545) (end 92.837 168.783) (width 0.1) (layer "B.Cu") (net 24))
  (segment (start 92.075 173.99) (end 92.075 169.545) (width 0.1) (layer "B.Cu") (net 24))
  (segment (start 92.98 174.895) (end 92.075 173.99) (width 0.1) (layer "B.Cu") (net 24))
  (segment (start 92.69 176.185) (end 92.98 175.895) (width 0.1) (layer "B.Cu") (net 24))
  (segment (start 94.520772 168.783) (end 94.69566 168.957888) (width 0.1) (layer "B.Cu") (net 24))
  (segment (start 92.69 177.145) (end 92.69 176.185) (width 0.1) (layer "B.Cu") (net 24))
  (segment (start 111.2 110.55) (end 111.6 110.15) (width 0.15) (layer "F.Cu") (net 25))
  (via (at 93.6763 166.573) (size 0.5) (drill 0.2) (layers "F.Cu" "B.Cu") (net 25))
  (via (at 111.6 110.15) (size 0.5) (drill 0.2) (layers "F.Cu" "B.Cu") (net 25))
  (segment (start 101.613144 161.5) (end 96.540144 166.573) (width 0.1) (layer "In5.Cu") (net 25))
  (segment (start 134.7 112.05) (end 134.7 135.130708) (width 0.1) (layer "In5.Cu") (net 25))
  (segment (start 134.7 135.130708) (end 108.330708 161.5) (width 0.1) (layer "In5.Cu") (net 25))
  (segment (start 119.952102 109.75) (end 132.4 109.75) (width 0.1) (layer "In5.Cu") (net 25))
  (segment (start 119.302103 110.399999) (end 119.952102 109.75) (width 0.1) (layer "In5.Cu") (net 25))
  (segment (start 111.849999 110.399999) (end 119.302103 110.399999) (width 0.1) (layer "In5.Cu") (net 25))
  (segment (start 96.540144 166.573) (end 93.6763 166.573) (width 0.1) (layer "In5.Cu") (net 25))
  (segment (start 132.4 109.75) (end 134.7 112.05) (width 0.1) (layer "In5.Cu") (net 25))
  (segment (start 111.6 110.15) (end 111.849999 110.399999) (width 0.1) (layer "In5.Cu") (net 25))
  (segment (start 108.330708 161.5) (end 101.613144 161.5) (width 0.1) (layer "In5.Cu") (net 25))
  (segment (start 90.295 168.6081) (end 92.3301 166.573) (width 0.1) (layer "B.Cu") (net 25))
  (segment (start 92.3301 166.573) (end 93.6763 166.573) (width 0.1) (layer "B.Cu") (net 25))
  (segment (start 90.295 168.6081) (end 90.295 177.345) (width 0.1) (layer "B.Cu") (net 25))
  (segment (start 113.6 108.15) (end 114 108.55) (width 0.15) (layer "F.Cu") (net 26))
  (via (at 103.7347 165.173) (size 0.5) (drill 0.2) (layers "F.Cu" "B.Cu") (net 26))
  (via (at 114 108.55) (size 0.5) (drill 0.2) (layers "F.Cu" "B.Cu") (net 26))
  (segment (start 114 108.55) (end 114.683129 107.866871) (width 0.1) (layer "In5.Cu") (net 26))
  (segment (start 136.7 110.8) (end 136.7 135.959156) (width 0.1) (layer "In5.Cu") (net 26))
  (segment (start 114.683129 107.866871) (end 133.766872 107.866871) (width 0.1) (layer "In5.Cu") (net 26))
  (segment (start 107.486156 165.173) (end 103.7347 165.173) (width 0.1) (layer "In5.Cu") (net 26))
  (segment (start 136.7 135.959156) (end 107.486156 165.173) (width 0.1) (layer "In5.Cu") (net 26))
  (segment (start 133.766872 107.866871) (end 136.7 110.8) (width 0.1) (layer "In5.Cu") (net 26))
  (segment (start 101.09 167.2081) (end 103.1251 165.173) (width 0.1) (layer "B.Cu") (net 26))
  (segment (start 103.1251 165.173) (end 103.7347 165.173) (width 0.1) (layer "B.Cu") (net 26))
  (segment (start 101.09 177.345) (end 101.09 167.2081) (width 0.1) (layer "B.Cu") (net 26))
  (segment (start 110.4 110.55) (end 110.8 110.15) (width 0.15) (layer "F.Cu") (net 27))
  (via (at 94.2351 167.1191) (size 0.5) (drill 0.2) (layers "F.Cu" "B.Cu") (net 27))
  (via (at 110.8 110.15) (size 0.5) (drill 0.2) (layers "F.Cu" "B.Cu") (net 27))
  (segment (start 119.24862 110.099926) (end 119.848546 109.5) (width 0.1) (layer "In5.Cu") (net 27))
  (segment (start 101.7167 161.75) (end 96.3476 167.1191) (width 0.1) (layer "In5.Cu") (net 27))
  (segment (start 108.434264 161.75) (end 101.7167 161.75) (width 0.1) (layer "In5.Cu") (net 27))
  (segment (start 112.349926 110.099926) (end 119.24862 110.099926) (width 0.1) (layer "In5.Cu") (net 27))
  (segment (start 119.848546 109.5) (end 132.55 109.5) (width 0.1) (layer "In5.Cu") (net 27))
  (segment (start 110.8 110.15) (end 111.2 109.75) (width 0.1) (layer "In5.Cu") (net 27))
  (segment (start 132.55 109.5) (end 134.95 111.9) (width 0.1) (layer "In5.Cu") (net 27))
  (segment (start 134.95 135.234264) (end 108.434264 161.75) (width 0.1) (layer "In5.Cu") (net 27))
  (segment (start 134.95 111.9) (end 134.95 135.234264) (width 0.1) (layer "In5.Cu") (net 27))
  (segment (start 112 109.75) (end 112.349926 110.099926) (width 0.1) (layer "In5.Cu") (net 27))
  (segment (start 96.3476 167.1191) (end 94.2351 167.1191) (width 0.1) (layer "In5.Cu") (net 27))
  (segment (start 111.2 109.75) (end 112 109.75) (width 0.1) (layer "In5.Cu") (net 27))
  (segment (start 90.89 168.5084) (end 92.2793 167.1191) (width 0.1) (layer "B.Cu") (net 27))
  (segment (start 92.2793 167.1191) (end 94.2351 167.1191) (width 0.1) (layer "B.Cu") (net 27))
  (segment (start 90.89 177.345) (end 90.89 168.5084) (width 0.1) (layer "B.Cu") (net 27))
  (segment (start 108.8 111.35) (end 109.211083 110.938917) (width 0.15) (layer "F.Cu") (net 28))
  (via (at 93.7 164.55) (size 0.5) (drill 0.2) (layers "F.Cu" "B.Cu") (net 28))
  (via (at 109.211083 110.938917) (size 0.5) (drill 0.2) (layers "F.Cu" "B.Cu") (net 28))
  (segment (start 97.14892 164.55) (end 101.19892 160.5) (width 0.1) (layer "In5.Cu") (net 28))
  (segment (start 109.622166 111.35) (end 109.211083 110.938917) (width 0.1) (layer "In5.Cu") (net 28))
  (segment (start 101.19892 160.5) (end 107.916484 160.5) (width 0.1) (layer "In5.Cu") (net 28))
  (segment (start 119.766326 111.35) (end 109.622166 111.35) (width 0.1) (layer "In5.Cu") (net 28))
  (segment (start 133.7 134.716484) (end 133.7 112.65) (width 0.1) (layer "In5.Cu") (net 28))
  (segment (start 107.916484 160.5) (end 133.7 134.716484) (width 0.1) (layer "In5.Cu") (net 28))
  (segment (start 120.366326 110.75) (end 119.766326 111.35) (width 0.1) (layer "In5.Cu") (net 28))
  (segment (start 93.7 164.55) (end 97.14892 164.55) (width 0.1) (layer "In5.Cu") (net 28))
  (segment (start 131.8 110.75) (end 120.366326 110.75) (width 0.1) (layer "In5.Cu") (net 28))
  (segment (start 133.7 112.65) (end 131.8 110.75) (width 0.1) (layer "In5.Cu") (net 28))
  (segment (start 92.4 164.55) (end 93.7 164.55) (width 0.1) (layer "B.Cu") (net 28))
  (segment (start 87.89 177.345) (end 87.89 169.06) (width 0.1) (layer "B.Cu") (net 28))
  (segment (start 87.89 169.06) (end 92.4 164.55) (width 0.1) (layer "B.Cu") (net 28))
  (segment (start 109.6 111.35) (end 110 110.95) (width 0.15) (layer "F.Cu") (net 29))
  (via (at 94.1716 165.0363) (size 0.5) (drill 0.2) (layers "F.Cu" "B.Cu") (net 29))
  (via (at 110 110.95) (size 0.5) (drill 0.2) (layers "F.Cu" "B.Cu") (net 29))
  (segment (start 108.02004 160.75) (end 133.95 134.82004) (width 0.1) (layer "In5.Cu") (net 29))
  (segment (start 133.95 134.82004) (end 133.95 112.5) (width 0.1) (layer "In5.Cu") (net 29))
  (segment (start 94.1716 165.0363) (end 97.016176 165.0363) (width 0.1) (layer "In5.Cu") (net 29))
  (segment (start 120.26277 110.5) (end 119.66277 111.1) (width 0.1) (layer "In5.Cu") (net 29))
  (segment (start 97.016176 165.0363) (end 101.302476 160.75) (width 0.1) (layer "In5.Cu") (net 29))
  (segment (start 110.15 111.1) (end 110 110.95) (width 0.1) (layer "In5.Cu") (net 29))
  (segment (start 133.95 112.5) (end 131.95 110.5) (width 0.1) (layer "In5.Cu") (net 29))
  (segment (start 131.95 110.5) (end 120.26277 110.5) (width 0.1) (layer "In5.Cu") (net 29))
  (segment (start 101.302476 160.75) (end 108.02004 160.75) (width 0.1) (layer "In5.Cu") (net 29))
  (segment (start 119.66277 111.1) (end 110.15 111.1) (width 0.1) (layer "In5.Cu") (net 29))
  (segment (start 92.3936 165.0363) (end 94.1716 165.0363) (width 0.1) (layer "B.Cu") (net 29))
  (segment (start 88.49 177.345) (end 88.49 168.9399) (width 0.1) (layer "B.Cu") (net 29))
  (segment (start 88.49 168.9399) (end 92.3936 165.0363) (width 0.1) (layer "B.Cu") (net 29))
  (segment (start 111.2 109.75) (end 111.6 109.35) (width 0.15) (layer "F.Cu") (net 30))
  (via (at 111.6 109.35) (size 0.5) (drill 0.2) (layers "F.Cu" "B.Cu") (net 30))
  (via (at 104.2935 165.7191) (size 0.5) (drill 0.2) (layers "F.Cu" "B.Cu") (net 30))
  (segment (start 112.2 109.35) (end 112.35 109.2) (width 0.1) (layer "In5.Cu") (net 30))
  (segment (start 107.293612 165.7191) (end 136.95 136.062712) (width 0.1) (layer "In5.Cu") (net 30))
  (segment (start 112.35 109.2) (end 112.75 109.2) (width 0.1) (layer "In5.Cu") (net 30))
  (segment (start 112.75 109.2) (end 114.283139 107.666861) (width 0.1) (layer "In5.Cu") (net 30))
  (segment (start 104.2935 165.7191) (end 107.293612 165.7191) (width 0.1) (layer "In5.Cu") (net 30))
  (segment (start 136.95 110.65) (end 133.966862 107.666861) (width 0.1) (layer "In5.Cu") (net 30))
  (segment (start 133.966862 107.666861) (end 114.283139 107.666861) (width 0.1) (layer "In5.Cu") (net 30))
  (segment (start 136.95 136.062712) (end 136.95 110.65) (width 0.1) (layer "In5.Cu") (net 30))
  (segment (start 111.6 109.35) (end 112.2 109.35) (width 0.1) (layer "In5.Cu") (net 30))
  (segment (start 101.69 175.865) (end 101.475 175.65) (width 0.1) (layer "B.Cu") (net 30))
  (segment (start 101.475 175.65) (end 101.475 175.155) (width 0.1) (layer "B.Cu") (net 30))
  (segment (start 101.69 174.94) (end 101.69 167.1034) (width 0.1) (layer "B.Cu") (net 30))
  (segment (start 101.69 177.345) (end 101.69 175.865) (width 0.1) (layer "B.Cu") (net 30))
  (segment (start 103.0743 165.7191) (end 104.2935 165.7191) (width 0.1) (layer "B.Cu") (net 30))
  (segment (start 101.69 167.1034) (end 103.0743 165.7191) (width 0.1) (layer "B.Cu") (net 30))
  (segment (start 101.475 175.155) (end 101.69 174.94) (width 0.1) (layer "B.Cu") (net 30))
  (segment (start 109.6 110.55) (end 110 110.15) (width 0.15) (layer "F.Cu") (net 31))
  (via (at 94.1716 166.065) (size 0.5) (drill 0.2) (layers "F.Cu" "B.Cu") (net 31))
  (via (at 110 110.15) (size 0.5) (drill 0.2) (layers "F.Cu" "B.Cu") (net 31))
  (segment (start 101.509588 161.25) (end 96.694588 166.065) (width 0.1) (layer "In5.Cu") (net 31))
  (segment (start 132.25 110) (end 134.45 112.2) (width 0.1) (layer "In5.Cu") (net 31))
  (segment (start 96.694588 166.065) (end 94.1716 166.065) (width 0.1) (layer "In5.Cu") (net 31))
  (segment (start 110.65 110.6) (end 119.455658 110.6) (width 0.1) (layer "In5.Cu") (net 31))
  (segment (start 110 110.15) (end 110.2 110.15) (width 0.1) (layer "In5.Cu") (net 31))
  (segment (start 120.055658 110) (end 132.25 110) (width 0.1) (layer "In5.Cu") (net 31))
  (segment (start 134.45 135.027152) (end 108.227152 161.25) (width 0.1) (layer "In5.Cu") (net 31))
  (segment (start 119.455658 110.6) (end 120.055658 110) (width 0.1) (layer "In5.Cu") (net 31))
  (segment (start 108.227152 161.25) (end 101.509588 161.25) (width 0.1) (layer "In5.Cu") (net 31))
  (segment (start 134.45 112.2) (end 134.45 135.027152) (width 0.1) (layer "In5.Cu") (net 31))
  (segment (start 110.2 110.15) (end 110.65 110.6) (width 0.1) (layer "In5.Cu") (net 31))
  (segment (start 89.695 168.6874) (end 92.3174 166.065) (width 0.1) (layer "B.Cu") (net 31))
  (segment (start 92.3301 166.065) (end 94.1716 166.065) (width 0.1) (layer "B.Cu") (net 31))
  (segment (start 89.69 168.6924) (end 89.695 168.6874) (width 0.1) (layer "B.Cu") (net 31))
  (segment (start 89.69 177.345) (end 89.69 168.6924) (width 0.1) (layer "B.Cu") (net 31))
  (segment (start 108.8 110.55) (end 109.2 110.15) (width 0.15) (layer "F.Cu") (net 32))
  (via (at 93.6763 165.557) (size 0.5) (drill 0.2) (layers "F.Cu" "B.Cu") (net 32))
  (via (at 109.2 110.15) (size 0.5) (drill 0.2) (layers "F.Cu" "B.Cu") (net 32))
  (segment (start 134.2 112.35) (end 132.1 110.25) (width 0.1) (layer "In5.Cu") (net 32))
  (segment (start 132.1 110.25) (end 120.159214 110.25) (width 0.1) (layer "In5.Cu") (net 32))
  (segment (start 109.6 110.55) (end 109.2 110.15) (width 0.1) (layer "In5.Cu") (net 32))
  (segment (start 134.2 134.923596) (end 134.2 112.35) (width 0.1) (layer "In5.Cu") (net 32))
  (segment (start 120.159214 110.25) (end 119.559214 110.85) (width 0.1) (layer "In5.Cu") (net 32))
  (segment (start 110.2 110.55) (end 109.6 110.55) (width 0.1) (layer "In5.Cu") (net 32))
  (segment (start 101.406032 161) (end 108.123596 161) (width 0.1) (layer "In5.Cu") (net 32))
  (segment (start 108.123596 161) (end 134.2 134.923596) (width 0.1) (layer "In5.Cu") (net 32))
  (segment (start 96.849032 165.557) (end 101.406032 161) (width 0.1) (layer "In5.Cu") (net 32))
  (segment (start 119.559214 110.85) (end 110.5 110.85) (width 0.1) (layer "In5.Cu") (net 32))
  (segment (start 93.6763 165.557) (end 96.849032 165.557) (width 0.1) (layer "In5.Cu") (net 32))
  (segment (start 110.5 110.85) (end 110.2 110.55) (width 0.1) (layer "In5.Cu") (net 32))
  (segment (start 89.095 168.7667) (end 92.3047 165.557) (width 0.1) (layer "B.Cu") (net 32))
  (segment (start 92.3047 165.557) (end 93.6763 165.557) (width 0.1) (layer "B.Cu") (net 32))
  (segment (start 89.095 168.7667) (end 89.095 177.345) (width 0.1) (layer "B.Cu") (net 32))
  (segment (start 114.4 108.95) (end 114.8 109.35) (width 0.15) (layer "F.Cu") (net 33))
  (via (at 94.1589 168.0589) (size 0.5) (drill 0.2) (layers "F.Cu" "B.Cu") (net 33))
  (via (at 114.8 109.35) (size 0.5) (drill 0.2) (layers "F.Cu" "B.Cu") (net 33))
  (segment (start 135.45 135.441376) (end 108.641376 162.25) (width 0.1) (layer "In5.Cu") (net 33))
  (segment (start 114.8 109.35) (end 115.2 108.95) (width 0.1) (layer "In5.Cu") (net 33))
  (segment (start 132.85 109) (end 135.45 111.6) (width 0.1) (layer "In5.Cu") (net 33))
  (segment (start 119.641434 109) (end 132.85 109) (width 0.1) (layer "In5.Cu") (net 33))
  (segment (start 108.641376 162.25) (end 101.923812 162.25) (width 0.1) (layer "In5.Cu") (net 33))
  (segment (start 96.114912 168.0589) (end 94.1589 168.0589) (width 0.1) (layer "In5.Cu") (net 33))
  (segment (start 101.923812 162.25) (end 96.114912 168.0589) (width 0.1) (layer "In5.Cu") (net 33))
  (segment (start 116.6 108.95) (end 117.25 109.6) (width 0.1) (layer "In5.Cu") (net 33))
  (segment (start 115.2 108.95) (end 116.6 108.95) (width 0.1) (layer "In5.Cu") (net 33))
  (segment (start 119.041434 109.6) (end 119.641434 109) (width 0.1) (layer "In5.Cu") (net 33))
  (segment (start 117.25 109.6) (end 119.041434 109.6) (width 0.1) (layer "In5.Cu") (net 33))
  (segment (start 135.45 111.6) (end 135.45 135.441376) (width 0.1) (layer "In5.Cu") (net 33))
  (segment (start 92.095 168.4083) (end 92.4444 168.0589) (width 0.1) (layer "B.Cu") (net 33))
  (segment (start 92.4444 168.0589) (end 94.1589 168.0589) (width 0.1) (layer "B.Cu") (net 33))
  (segment (start 92.095 175.78) (end 92.095 177.345) (width 0.1) (layer "B.Cu") (net 33))
  (segment (start 92.095 168.4) (end 91.821 168.674) (width 0.1) (layer "B.Cu") (net 33))
  (segment (start 91.821 168.674) (end 91.821 175.506) (width 0.1) (layer "B.Cu") (net 33))
  (segment (start 91.821 175.506) (end 92.095 175.78) (width 0.1) (layer "B.Cu") (net 33))
  (segment (start 115.75 107.6) (end 117.3 107.6) (width 0.1) (layer "F.Cu") (net 34))
  (segment (start 115.2 108.15) (end 115.75 107.6) (width 0.1) (layer "F.Cu") (net 34))
  (segment (start 117.3 107.6) (end 118.35 108.65) (width 0.1) (layer "F.Cu") (net 34))
  (via (at 118.35 108.65) (size 0.5) (drill 0.2) (layers "F.Cu" "B.Cu") (net 34))
  (via (at 103.7347 164.157) (size 0.5) (drill 0.2) (layers "F.Cu" "B.Cu") (net 34))
  (segment (start 118.733109 108.266891) (end 118.35 108.65) (width 0.1) (layer "In5.Cu") (net 34))
  (segment (start 133.366892 108.266891) (end 118.733109 108.266891) (width 0.1) (layer "In5.Cu") (net 34))
  (segment (start 136.2 135.752044) (end 136.2 111.1) (width 0.1) (layer "In5.Cu") (net 34))
  (segment (start 107.795044 164.157) (end 136.2 135.752044) (width 0.1) (layer "In5.Cu") (net 34))
  (segment (start 103.7347 164.157) (end 107.795044 164.157) (width 0.1) (layer "In5.Cu") (net 34))
  (segment (start 136.2 111.1) (end 133.366892 108.266891) (width 0.1) (layer "In5.Cu") (net 34))
  (segment (start 103.0997 164.157) (end 103.7347 164.157) (width 0.1) (layer "B.Cu") (net 34))
  (segment (start 99.89 177.345) (end 99.89 167.3667) (width 0.1) (layer "B.Cu") (net 34))
  (segment (start 99.89 167.3667) (end 103.0997 164.157) (width 0.1) (layer "B.Cu") (net 34))
  (segment (start 114.4 108.15) (end 114.8 108.55) (width 0.15) (layer "F.Cu") (net 35))
  (via (at 104.23 164.665) (size 0.5) (drill 0.2) (layers "F.Cu" "B.Cu") (net 35))
  (via (at 114.8 108.55) (size 0.5) (drill 0.2) (layers "F.Cu" "B.Cu") (net 35))
  (segment (start 104.23 164.665) (end 107.6406 164.665) (width 0.1) (layer "In5.Cu") (net 35))
  (segment (start 107.6406 164.665) (end 136.45 135.8556) (width 0.1) (layer "In5.Cu") (net 35))
  (segment (start 133.566882 108.066881) (end 115.283119 108.066881) (width 0.1) (layer "In5.Cu") (net 35))
  (segment (start 115.283119 108.066881) (end 114.8 108.55) (width 0.1) (layer "In5.Cu") (net 35))
  (segment (start 136.45 110.95) (end 133.566882 108.066881) (width 0.1) (layer "In5.Cu") (net 35))
  (segment (start 136.45 135.8556) (end 136.45 110.95) (width 0.1) (layer "In5.Cu") (net 35))
  (segment (start 100.49 177.345) (end 100.49 167.2874) (width 0.1) (layer "B.Cu") (net 35))
  (segment (start 103.1124 164.665) (end 104.23 164.665) (width 0.1) (layer "B.Cu") (net 35))
  (segment (start 100.49 167.2874) (end 103.1124 164.665) (width 0.1) (layer "B.Cu") (net 35))
  (segment (start 112.45 109.75) (end 112 109.75) (width 0.15) (layer "F.Cu") (net 36))
  (segment (start 112.6 109.6) (end 112.45 109.75) (width 0.15) (layer "F.Cu") (net 36))
  (via (at 93.6636 167.589) (size 0.5) (drill 0.2) (layers "F.Cu" "B.Cu") (net 36))
  (via (at 112.6 109.6) (size 0.5) (drill 0.2) (layers "F.Cu" "B.Cu") (net 36))
  (segment (start 101.820256 162) (end 108.53782 162) (width 0.1) (layer "In5.Cu") (net 36))
  (segment (start 112.849999 109.849999) (end 112.6 109.6) (width 0.1) (layer "In5.Cu") (net 36))
  (segment (start 135.2 135.33782) (end 135.2 111.75) (width 0.1) (layer "In5.Cu") (net 36))
  (segment (start 119.144991 109.849999) (end 112.849999 109.849999) (width 0.1) (layer "In5.Cu") (net 36))
  (segment (start 132.7 109.25) (end 119.74499 109.25) (width 0.1) (layer "In5.Cu") (net 36))
  (segment (start 93.6636 167.589) (end 96.231256 167.589) (width 0.1) (layer "In5.Cu") (net 36))
  (segment (start 135.2 111.75) (end 132.7 109.25) (width 0.1) (layer "In5.Cu") (net 36))
  (segment (start 96.231256 167.589) (end 101.820256 162) (width 0.1) (layer "In5.Cu") (net 36))
  (segment (start 108.53782 162) (end 135.2 135.33782) (width 0.1) (layer "In5.Cu") (net 36))
  (segment (start 119.74499 109.25) (end 119.144991 109.849999) (width 0.1) (layer "In5.Cu") (net 36))
  (segment (start 91.49 177.345) (end 91.49 168.4164) (width 0.1) (layer "B.Cu") (net 36))
  (segment (start 91.49 168.4164) (end 92.3174 167.589) (width 0.1) (layer "B.Cu") (net 36))
  (segment (start 92.3174 167.589) (end 93.6636 167.589) (width 0.1) (layer "B.Cu") (net 36))
  (segment (start 111.2 111.35) (end 111.6 111.75) (width 0.15) (layer "F.Cu") (net 37))
  (via (at 93.7 163.55) (size 0.5) (drill 0.2) (layers "F.Cu" "B.Cu") (net 37))
  (via (at 111.6 111.75) (size 0.5) (drill 0.2) (layers "F.Cu" "B.Cu") (net 37))
  (segment (start 100.991808 160) (end 107.709372 160) (width 0.1) (layer "In5.Cu") (net 37))
  (segment (start 93.7 163.55) (end 97.441808 163.55) (width 0.1) (layer "In5.Cu") (net 37))
  (segment (start 107.709372 160) (end 133.2 134.509372) (width 0.1) (layer "In5.Cu") (net 37))
  (segment (start 133.2 112.95) (end 131.5 111.25) (width 0.1) (layer "In5.Cu") (net 37))
  (segment (start 112.3 112.45) (end 111.6 111.75) (width 0.1) (layer "In5.Cu") (net 37))
  (segment (start 133.2 134.509372) (end 133.2 112.95) (width 0.1) (layer "In5.Cu") (net 37))
  (segment (start 119.373438 112.45) (end 112.3 112.45) (width 0.1) (layer "In5.Cu") (net 37))
  (segment (start 131.5 111.25) (end 120.573438 111.25) (width 0.1) (layer "In5.Cu") (net 37))
  (segment (start 120.573438 111.25) (end 119.373438 112.45) (width 0.1) (layer "In5.Cu") (net 37))
  (segment (start 97.441808 163.55) (end 100.991808 160) (width 0.1) (layer "In5.Cu") (net 37))
  (segment (start 92.4 163.55) (end 93.7 163.55) (width 0.1) (layer "B.Cu") (net 37))
  (segment (start 86.685 169.265) (end 92.4 163.55) (width 0.1) (layer "B.Cu") (net 37))
  (segment (start 86.685 177.345) (end 86.685 169.265) (width 0.1) (layer "B.Cu") (net 37))
  (segment (start 112.85 110.95) (end 112.85 111.75) (width 0.1) (layer "F.Cu") (net 38))
  (segment (start 112.45 110.55) (end 112.85 110.95) (width 0.1) (layer "F.Cu") (net 38))
  (segment (start 112.45 110.55) (end 112 110.55) (width 0.1) (layer "F.Cu") (net 38))
  (via (at 94.2 164.05) (size 0.5) (drill 0.2) (layers "F.Cu" "B.Cu") (net 38))
  (via (at 112.85 111.75) (size 0.5) (drill 0.2) (layers "F.Cu" "B.Cu") (net 38))
  (segment (start 113.3 112.2) (end 119.269882 112.2) (width 0.1) (layer "In5.Cu") (net 38))
  (segment (start 107.812928 160.25) (end 101.095364 160.25) (width 0.1) (layer "In5.Cu") (net 38))
  (segment (start 112.85 111.75) (end 113.3 112.2) (width 0.1) (layer "In5.Cu") (net 38))
  (segment (start 101.095364 160.25) (end 97.295364 164.05) (width 0.1) (layer "In5.Cu") (net 38))
  (segment (start 120.469882 111) (end 131.65 111) (width 0.1) (layer "In5.Cu") (net 38))
  (segment (start 133.45 134.612928) (end 107.812928 160.25) (width 0.1) (layer "In5.Cu") (net 38))
  (segment (start 131.65 111) (end 133.45 112.8) (width 0.1) (layer "In5.Cu") (net 38))
  (segment (start 133.45 112.8) (end 133.45 134.612928) (width 0.1) (layer "In5.Cu") (net 38))
  (segment (start 119.269882 112.2) (end 120.469882 111) (width 0.1) (layer "In5.Cu") (net 38))
  (segment (start 97.295364 164.05) (end 94.2 164.05) (width 0.1) (layer "In5.Cu") (net 38))
  (segment (start 87.29 169.16) (end 92.4 164.05) (width 0.1) (layer "B.Cu") (net 38))
  (segment (start 87.29 177.345) (end 87.29 169.16) (width 0.1) (layer "B.Cu") (net 38))
  (segment (start 92.4 164.05) (end 94.2 164.05) (width 0.1) (layer "B.Cu") (net 38))
  (segment (start 109.6 112.15) (end 110 111.75) (width 0.15) (layer "F.Cu") (net 39))
  (segment (start 77.25 174.93) (end 77.49 174.69) (width 0.15) (layer "F.Cu") (net 39))
  (segment (start 85.2 162.55) (end 86.1 162.55) (width 0.15) (layer "F.Cu") (net 39))
  (segment (start 77.49 177.345) (end 77.49 175.925) (width 0.15) (layer "F.Cu") (net 39))
  (segment (start 77.49 174.69) (end 77.49 170.26) (width 0.15) (layer "F.Cu") (net 39))
  (segment (start 77.49 175.925) (end 77.25 175.685) (width 0.15) (layer "F.Cu") (net 39))
  (segment (start 77.25 175.685) (end 77.25 174.93) (width 0.15) (layer "F.Cu") (net 39))
  (segment (start 77.49 170.26) (end 85.2 162.55) (width 0.15) (layer "F.Cu") (net 39))
  (via (at 110 111.75) (size 0.5) (drill 0.2) (layers "F.Cu" "B.Cu") (net 39))
  (via (at 86.1 162.55) (size 0.5) (drill 0.2) (layers "F.Cu" "B.Cu") (net 39))
  (segment (start 100.68114 159.25) (end 107.398704 159.25) (width 0.1) (layer "In5.Cu") (net 39))
  (segment (start 97.43114 162.5) (end 100.68114 159.25) (width 0.1) (layer "In5.Cu") (net 39))
  (segment (start 110.85 113.2) (end 110 112.35) (width 0.1) (layer "In5.Cu") (net 39))
  (segment (start 118.14057 113.2) (end 110.85 113.2) (width 0.1) (layer "In5.Cu") (net 39))
  (segment (start 120.45 115.50943) (end 118.14057 113.2) (width 0.1) (layer "In5.Cu") (net 39))
  (segment (start 121.95 137.3389) (end 120.45 135.8389) (width 0.1) (layer "In5.Cu") (net 39))
  (segment (start 107.398704 159.25) (end 121.95 144.698704) (width 0.1) (layer "In5.Cu") (net 39))
  (segment (start 86.15 162.5) (end 97.43114 162.5) (width 0.1) (layer "In5.Cu") (net 39))
  (segment (start 121.95 144.698704) (end 121.95 137.3389) (width 0.1) (layer "In5.Cu") (net 39))
  (segment (start 110 112.35) (end 110 111.75) (width 0.1) (layer "In5.Cu") (net 39))
  (segment (start 86.1 162.55) (end 86.15 162.5) (width 0.1) (layer "In5.Cu") (net 39))
  (segment (start 120.45 135.8389) (end 120.45 115.50943) (width 0.1) (layer "In5.Cu") (net 39))
  (segment (start 134.65 107.35) (end 137.9 110.6) (width 0.1) (layer "F.Cu") (net 40))
  (segment (start 112.85 107.35) (end 134.65 107.35) (width 0.1) (layer "F.Cu") (net 40))
  (segment (start 137.9 112.45) (end 139.2 113.75) (width 0.1) (layer "F.Cu") (net 40))
  (segment (start 112.05 108.15) (end 112.85 107.35) (width 0.1) (layer "F.Cu") (net 40))
  (segment (start 137.9 110.6) (end 137.9 112.45) (width 0.1) (layer "F.Cu") (net 40))
  (via (at 113.962554 161.878606) (size 0.5) (drill 0.2) (layers "F.Cu" "B.Cu") (net 40))
  (via (at 139.2 113.75) (size 0.5) (drill 0.2) (layers "F.Cu" "B.Cu") (net 40))
  (segment (start 139.2 114.25) (end 138.7 114.75) (width 0.1) (layer "In5.Cu") (net 40))
  (segment (start 138.7 114.75) (end 138.7 136.787607) (width 0.1) (layer "In5.Cu") (net 40))
  (segment (start 113.962554 161.525053) (end 113.962554 161.878606) (width 0.1) (layer "In5.Cu") (net 40))
  (segment (start 139.2 113.75) (end 139.2 114.25) (width 0.1) (layer "In5.Cu") (net 40))
  (segment (start 138.7 136.787607) (end 113.962554 161.525053) (width 0.1) (layer "In5.Cu") (net 40))
  (segment (start 112.29 177.345) (end 112.075 177.13) (width 0.1) (layer "B.Cu") (net 40))
  (segment (start 112.075 177.13) (end 112.075 163.76616) (width 0.1) (layer "B.Cu") (net 40))
  (segment (start 112.075 163.76616) (end 113.962554 161.878606) (width 0.1) (layer "B.Cu") (net 40))
  (segment (start 110.4 112.15) (end 110.8 112.55) (width 0.15) (layer "F.Cu") (net 41))
  (segment (start 78.69 177.345) (end 78.69 169.66) (width 0.15) (layer "F.Cu") (net 41))
  (segment (start 85.3 163.05) (end 86.7 163.05) (width 0.15) (layer "F.Cu") (net 41))
  (segment (start 78.69 169.66) (end 85.3 163.05) (width 0.15) (layer "F.Cu") (net 41))
  (via (at 110.8 112.55) (size 0.5) (drill 0.2) (layers "F.Cu" "B.Cu") (net 41))
  (via (at 86.7 163.05) (size 0.5) (drill 0.2) (layers "F.Cu" "B.Cu") (net 41))
  (segment (start 118.235452 112.95) (end 111.2 112.95) (width 0.1) (layer "In5.Cu") (net 41))
  (segment (start 100.784696 159.5) (end 107.50226 159.5) (width 0.1) (layer "In5.Cu") (net 41))
  (segment (start 122.2 137.235344) (end 120.7 135.735344) (width 0.1) (layer "In5.Cu") (net 41))
  (segment (start 87 162.75) (end 97.534696 162.75) (width 0.1) (layer "In5.Cu") (net 41))
  (segment (start 120.7 135.735344) (end 120.7 115.414548) (width 0.1) (layer "In5.Cu") (net 41))
  (segment (start 111.2 112.95) (end 110.8 112.55) (width 0.1) (layer "In5.Cu") (net 41))
  (segment (start 97.534696 162.75) (end 100.784696 159.5) (width 0.1) (layer "In5.Cu") (net 41))
  (segment (start 86.7 163.05) (end 87 162.75) (width 0.1) (layer "In5.Cu") (net 41))
  (segment (start 107.50226 159.5) (end 122.2 144.80226) (width 0.1) (layer "In5.Cu") (net 41))
  (segment (start 122.2 144.80226) (end 122.2 137.235344) (width 0.1) (layer "In5.Cu") (net 41))
  (segment (start 120.7 115.414548) (end 118.235452 112.95) (width 0.1) (layer "In5.Cu") (net 41))
  (segment (start 138.2 110.45) (end 138.2 112.05) (width 0.1) (layer "F.Cu") (net 42))
  (segment (start 134.85 107.1) (end 138.2 110.45) (width 0.1) (layer "F.Cu") (net 42))
  (segment (start 139.1 112.95) (end 139.2 112.95) (width 0.1) (layer "F.Cu") (net 42))
  (segment (start 112.25 107.1) (end 134.85 107.1) (width 0.1) (layer "F.Cu") (net 42))
  (segment (start 111.2 108.15) (end 112.25 107.1) (width 0.1) (layer "F.Cu") (net 42))
  (segment (start 138.2 112.05) (end 139.1 112.95) (width 0.1) (layer "F.Cu") (net 42))
  (via (at 113.949998 162.585718) (size 0.5) (drill 0.2) (layers "F.Cu" "B.Cu") (net 42))
  (via (at 139.2 112.95) (size 0.5) (drill 0.2) (layers "F.Cu" "B.Cu") (net 42))
  (segment (start 138.95 115) (end 138.95 136.908969) (width 0.1) (layer "In5.Cu") (net 42))
  (segment (start 139.2 112.95) (end 139.7 113.45) (width 0.1) (layer "In5.Cu") (net 42))
  (segment (start 139.7 113.45) (end 139.7 114.25) (width 0.1) (layer "In5.Cu") (net 42))
  (segment (start 139.7 114.25) (end 138.95 115) (width 0.1) (layer "In5.Cu") (net 42))
  (segment (start 114.6 161.258969) (end 114.6 161.935716) (width 0.1) (layer "In5.Cu") (net 42))
  (segment (start 114.6 161.935716) (end 113.949998 162.585718) (width 0.1) (layer "In5.Cu") (net 42))
  (segment (start 138.95 136.908969) (end 114.6 161.258969) (width 0.1) (layer "In5.Cu") (net 42))
  (segment (start 113.075 163.460716) (end 113.949998 162.585718) (width 0.1) (layer "B.Cu") (net 42))
  (segment (start 113.075 177.16) (end 113.075 163.460716) (width 0.1) (layer "B.Cu") (net 42))
  (segment (start 109.6 109.75) (end 109.2 109.35) (width 0.15) (layer "F.Cu") (net 43))
  (via (at 109.189548 165.237388) (size 0.5) (drill 0.2) (layers "F.Cu" "B.Cu") (net 43))
  (via (at 109.2 109.35) (size 0.5) (drill 0.2) (layers "F.Cu" "B.Cu") (net 43))
  (segment (start 110.2 109.75) (end 110.4 109.55) (width 0.1) (layer "In5.Cu") (net 43))
  (segment (start 109.189548 164.883835) (end 109.189548 165.237388) (width 0.1) (layer "In5.Cu") (net 43))
  (segment (start 110.4 109.55) (end 110.4 109.15) (width 0.1) (layer "In5.Cu") (net 43))
  (segment (start 109.2 109.35) (end 109.6 109.75) (width 0.1) (layer "In5.Cu") (net 43))
  (segment (start 110.4 109.15) (end 112.483169 107.066831) (width 0.1) (layer "In5.Cu") (net 43))
  (segment (start 112.483169 107.066831) (end 134.616831 107.066831) (width 0.1) (layer "In5.Cu") (net 43))
  (segment (start 134.616831 107.066831) (end 137.7 110.15) (width 0.1) (layer "In5.Cu") (net 43))
  (segment (start 137.7 110.15) (end 137.7 136.373383) (width 0.1) (layer "In5.Cu") (net 43))
  (segment (start 137.7 136.373383) (end 109.189548 164.883835) (width 0.1) (layer "In5.Cu") (net 43))
  (segment (start 109.6 109.75) (end 110.2 109.75) (width 0.1) (layer "In5.Cu") (net 43))
  (segment (start 106.9 167.526936) (end 109.189548 165.237388) (width 0.1) (layer "B.Cu") (net 43))
  (segment (start 106.9 177.345) (end 106.9 167.526936) (width 0.1) (layer "B.Cu") (net 43))
  (segment (start 110.4 109.75) (end 110 109.35) (width 0.15) (layer "F.Cu") (net 44))
  (via (at 110 109.35) (size 0.5) (drill 0.2) (layers "F.Cu" "B.Cu") (net 44))
  (via (at 109.189548 165.9445) (size 0.5) (drill 0.2) (layers "F.Cu" "B.Cu") (net 44))
  (segment (start 110 109.35) (end 110 109.15) (width 0.1) (layer "In5.Cu") (net 44))
  (segment (start 110.250216 164.883832) (end 109.189548 165.9445) (width 0.1) (layer "In5.Cu") (net 44))
  (segment (start 137.95 110) (end 137.95 136.476939) (width 0.1) (layer "In5.Cu") (net 44))
  (segment (start 110 109.15) (end 112.283179 106.866821) (width 0.1) (layer "In5.Cu") (net 44))
  (segment (start 112.283179 106.866821) (end 134.816821 106.866821) (width 0.1) (layer "In5.Cu") (net 44))
  (segment (start 110.250216 164.176723) (end 110.250216 164.883832) (width 0.1) (layer "In5.Cu") (net 44))
  (segment (start 134.816821 106.866821) (end 137.95 110) (width 0.1) (layer "In5.Cu") (net 44))
  (segment (start 137.95 136.476939) (end 110.250216 164.176723) (width 0.1) (layer "In5.Cu") (net 44))
  (segment (start 107.49 167.644048) (end 109.189548 165.9445) (width 0.1) (layer "B.Cu") (net 44))
  (segment (start 107.49 177.345) (end 107.49 167.644048) (width 0.1) (layer "B.Cu") (net 44))
  (segment (start 85.5 163.55) (end 86.1 163.55) (width 0.15) (layer "F.Cu") (net 45))
  (segment (start 79.29 169.76) (end 85.5 163.55) (width 0.15) (layer "F.Cu") (net 45))
  (segment (start 79.29 177.345) (end 79.29 169.76) (width 0.15) (layer "F.Cu") (net 45))
  (segment (start 111.2 112.15) (end 111.6 112.55) (width 0.15) (layer "F.Cu") (net 45))
  (via (at 86.1 163.55) (size 0.5) (drill 0.2) (layers "F.Cu" "B.Cu") (net 45))
  (via (at 111.6 112.55) (size 0.5) (drill 0.2) (layers "F.Cu" "B.Cu") (net 45))
  (segment (start 86.1 163.55) (end 87.15 163.55) (width 0.1) (layer "In5.Cu") (net 45))
  (segment (start 97.638252 163) (end 100.888252 159.75) (width 0.1) (layer "In5.Cu") (net 45))
  (segment (start 107.605816 159.75) (end 122.45 144.905816) (width 0.1) (layer "In5.Cu") (net 45))
  (segment (start 118.347682 112.7) (end 111.75 112.7) (width 0.1) (layer "In5.Cu") (net 45))
  (segment (start 120.95 115.302318) (end 118.347682 112.7) (width 0.1) (layer "In5.Cu") (net 45))
  (segment (start 122.45 137.131788) (end 120.95 135.631788) (width 0.1) (layer "In5.Cu") (net 45))
  (segment (start 100.888252 159.75) (end 107.605816 159.75) (width 0.1) (layer "In5.Cu") (net 45))
  (segment (start 122.45 144.905816) (end 122.45 137.131788) (width 0.1) (layer "In5.Cu") (net 45))
  (segment (start 111.75 112.7) (end 111.6 112.55) (width 0.1) (layer "In5.Cu") (net 45))
  (segment (start 87.15 163.55) (end 87.7 163) (width 0.1) (layer "In5.Cu") (net 45))
  (segment (start 120.95 135.631788) (end 120.95 115.302318) (width 0.1) (layer "In5.Cu") (net 45))
  (segment (start 87.7 163) (end 97.638252 163) (width 0.1) (layer "In5.Cu") (net 45))
  (segment (start 108.8 112.15) (end 109.2 111.75) (width 0.15) (layer "F.Cu") (net 46))
  (segment (start 85.2 162.05) (end 86.7 162.05) (width 0.15) (layer "F.Cu") (net 46))
  (segment (start 76.89 170.36) (end 85.2 162.05) (width 0.15) (layer "F.Cu") (net 46))
  (segment (start 76.89 177.345) (end 76.89 170.36) (width 0.15) (layer "F.Cu") (net 46))
  (via (at 109.2 111.75) (size 0.5) (drill 0.2) (layers "F.Cu" "B.Cu") (net 46))
  (via (at 86.7 162.05) (size 0.5) (drill 0.2) (layers "F.Cu" "B.Cu") (net 46))
  (segment (start 86.9 162.25) (end 97.327584 162.25) (width 0.1) (layer "In5.Cu") (net 46))
  (segment (start 109.2 112.103553) (end 109.2 111.75) (width 0.1) (layer "In5.Cu") (net 46))
  (segment (start 118.037014 113.45) (end 110.546447 113.45) (width 0.1) (layer "In5.Cu") (net 46))
  (segment (start 100.577584 159) (end 107.295148 159) (width 0.1) (layer "In5.Cu") (net 46))
  (segment (start 120.2 135.942456) (end 120.2 115.612986) (width 0.1) (layer "In5.Cu") (net 46))
  (segment (start 121.7 144.595148) (end 121.7 137.442456) (width 0.1) (layer "In5.Cu") (net 46))
  (segment (start 107.295148 159) (end 121.7 144.595148) (width 0.1) (layer "In5.Cu") (net 46))
  (segment (start 86.7 162.05) (end 86.9 162.25) (width 0.1) (layer "In5.Cu") (net 46))
  (segment (start 120.2 115.612986) (end 118.037014 113.45) (width 0.1) (layer "In5.Cu") (net 46))
  (segment (start 110.546447 113.45) (end 109.2 112.103553) (width 0.1) (layer "In5.Cu") (net 46))
  (segment (start 121.7 137.442456) (end 120.2 135.942456) (width 0.1) (layer "In5.Cu") (net 46))
  (segment (start 97.327584 162.25) (end 100.577584 159) (width 0.1) (layer "In5.Cu") (net 46))
  (segment (start 108.8 108.95) (end 109.2 108.55) (width 0.15) (layer "F.Cu") (net 47))
  (via (at 109.2 108.55) (size 0.5) (drill 0.2) (layers "F.Cu" "B.Cu") (net 47))
  (via (at 109.189548 167.358724) (size 0.5) (drill 0.2) (layers "F.Cu" "B.Cu") (net 47))
  (segment (start 111.283199 106.466801) (end 135.316801 106.466801) (width 0.1) (layer "In5.Cu") (net 47))
  (segment (start 109.2 108.55) (end 111.283199 106.466801) (width 0.1) (layer "In5.Cu") (net 47))
  (segment (start 135.316801 106.466801) (end 138.45 109.6) (width 0.1) (layer "In5.Cu") (net 47))
  (segment (start 138.45 136.684048) (end 111 164.134048) (width 0.1) (layer "In5.Cu") (net 47))
  (segment (start 111 165.548272) (end 109.189548 167.358724) (width 0.1) (layer "In5.Cu") (net 47))
  (segment (start 138.45 109.6) (end 138.45 136.684048) (width 0.1) (layer "In5.Cu") (net 47))
  (segment (start 111 164.134048) (end 111 165.548272) (width 0.1) (layer "In5.Cu") (net 47))
  (segment (start 108.69 167.858272) (end 109.189548 167.358724) (width 0.1) (layer "B.Cu") (net 47))
  (segment (start 108.69 177.345) (end 108.69 167.858272) (width 0.1) (layer "B.Cu") (net 47))
  (segment (start 109.6 108.95) (end 110 108.55) (width 0.15) (layer "F.Cu") (net 48))
  (via (at 109.189548 166.651612) (size 0.5) (drill 0.2) (layers "F.Cu" "B.Cu") (net 48))
  (via (at 110 108.55) (size 0.5) (drill 0.2) (layers "F.Cu" "B.Cu") (net 48))
  (segment (start 110.603772 164.176723) (end 110.603772 165.237388) (width 0.1) (layer "In5.Cu") (net 48))
  (segment (start 135.066811 106.666811) (end 138.2 109.8) (width 0.1) (layer "In5.Cu") (net 48))
  (segment (start 138.2 136.580495) (end 110.603772 164.176723) (width 0.1) (layer "In5.Cu") (net 48))
  (segment (start 110.603772 165.237388) (end 109.189548 166.651612) (width 0.1) (layer "In5.Cu") (net 48))
  (segment (start 111.883189 106.666811) (end 135.066811 106.666811) (width 0.1) (layer "In5.Cu") (net 48))
  (segment (start 138.2 109.8) (end 138.2 136.580495) (width 0.1) (layer "In5.Cu") (net 48))
  (segment (start 110 108.55) (end 111.883189 106.666811) (width 0.1) (layer "In5.Cu") (net 48))
  (segment (start 108.09 177.345) (end 108.09 167.75116) (width 0.1) (layer "B.Cu") (net 48))
  (segment (start 108.09 167.75116) (end 109.189548 166.651612) (width 0.1) (layer "B.Cu") (net 48))
  (segment (start 135.15 106.6) (end 139.2 110.65) (width 0.1) (layer "F.Cu") (net 49))
  (segment (start 139.2 110.65) (end 139.2 111.45) (width 0.1) (layer "F.Cu") (net 49))
  (segment (start 111.15 106.6) (end 135.15 106.6) (width 0.1) (layer "F.Cu") (net 49))
  (segment (start 109.6 108.15) (end 111.15 106.6) (width 0.1) (layer "F.Cu") (net 49))
  (via (at 113.962554 163.999942) (size 0.5) (drill 0.2) (layers "F.Cu" "B.Cu") (net 49))
  (via (at 139.2 111.45) (size 0.5) (drill 0.2) (layers "F.Cu" "B.Cu") (net 49))
  (segment (start 139.2 111.45) (end 140.2 112.45) (width 0.1) (layer "In5.Cu") (net 49))
  (segment (start 139.45 137.098272) (end 115.25 161.298272) (width 0.1) (layer "In5.Cu") (net 49))
  (segment (start 115.25 161.298272) (end 115.25 162.712496) (width 0.1) (layer "In5.Cu") (net 49))
  (segment (start 140.2 114.75) (end 139.45 115.5) (width 0.1) (layer "In5.Cu") (net 49))
  (segment (start 139.45 115.5) (end 139.45 137.098272) (width 0.1) (layer "In5.Cu") (net 49))
  (segment (start 140.2 112.45) (end 140.2 114.75) (width 0.1) (layer "In5.Cu") (net 49))
  (segment (start 115.25 162.712496) (end 113.962554 163.999942) (width 0.1) (layer "In5.Cu") (net 49))
  (segment (start 114.09 164.127388) (end 113.962554 163.999942) (width 0.1) (layer "B.Cu") (net 49))
  (segment (start 114.09 177.345) (end 114.09 164.127388) (width 0.1) (layer "B.Cu") (net 49))
  (segment (start 135 106.85) (end 138.5 110.35) (width 0.1) (layer "F.Cu") (net 50))
  (segment (start 138.5 110.35) (end 138.5 111.5) (width 0.1) (layer "F.Cu") (net 50))
  (segment (start 111.7 106.85) (end 135 106.85) (width 0.1) (layer "F.Cu") (net 50))
  (segment (start 138.5 111.5) (end 139.2 112.2) (width 0.1) (layer "F.Cu") (net 50))
  (segment (start 110.4 108.15) (end 111.7 106.85) (width 0.1) (layer "F.Cu") (net 50))
  (via (at 139.2 112.2) (size 0.5) (drill 0.2) (layers "F.Cu" "B.Cu") (net 50))
  (via (at 113.962554 163.29283) (size 0.5) (drill 0.2) (layers "F.Cu" "B.Cu") (net 50))
  (segment (start 139.95 112.95) (end 139.95 114.5) (width 0.1) (layer "In5.Cu") (net 50))
  (segment (start 139.95 114.5) (end 139.2 115.25) (width 0.1) (layer "In5.Cu") (net 50))
  (segment (start 115.04999 162.205394) (end 113.962554 163.29283) (width 0.1) (layer "In5.Cu") (net 50))
  (segment (start 139.2 115.25) (end 139.2 136.994716) (width 0.1) (layer "In5.Cu") (net 50))
  (segment (start 115.04999 161.144726) (end 115.04999 162.205394) (width 0.1) (layer "In5.Cu") (net 50))
  (segment (start 139.2 136.994716) (end 115.04999 161.144726) (width 0.1) (layer "In5.Cu") (net 50))
  (segment (start 139.2 112.2) (end 139.95 112.95) (width 0.1) (layer "In5.Cu") (net 50))
  (segment (start 113.49 163.765384) (end 113.962554 163.29283) (width 0.1) (layer "B.Cu") (net 50))
  (segment (start 113.49 177.345) (end 113.49 163.765384) (width 0.1) (layer "B.Cu") (net 50))
  (segment (start 111.2 108.95) (end 111.6 108.55) (width 0.15) (layer "F.Cu") (net 51))
  (via (at 111.6 108.55) (size 0.5) (drill 0.2) (layers "F.Cu" "B.Cu") (net 51))
  (via (at 103.722 166.189) (size 0.5) (drill 0.2) (layers "F.Cu" "B.Cu") (net 51))
  (segment (start 114.129583 107.466851) (end 112.646434 108.95) (width 0.1) (layer "In5.Cu") (net 51))
  (segment (start 107.177268 166.189) (end 137.2 136.166268) (width 0.1) (layer "In5.Cu") (net 51))
  (segment (start 112.646434 108.95) (end 112 108.95) (width 0.1) (layer "In5.Cu") (net 51))
  (segment (start 103.722 166.189) (end 107.177268 166.189) (width 0.1) (layer "In5.Cu") (net 51))
  (segment (start 112 108.95) (end 111.6 108.55) (width 0.1) (layer "In5.Cu") (net 51))
  (segment (start 134.166851 107.466851) (end 114.129583 107.466851) (width 0.1) (layer "In5.Cu") (net 51))
  (segment (start 137.2 136.166268) (end 137.2 110.5) (width 0.1) (layer "In5.Cu") (net 51))
  (segment (start 137.2 110.5) (end 134.166851 107.466851) (width 0.1) (layer "In5.Cu") (net 51))
  (segment (start 102.29 175.885) (end 102.29 177.345) (width 0.1) (layer "B.Cu") (net 51))
  (segment (start 102.5 175.675) (end 102.29 175.885) (width 0.1) (layer "B.Cu") (net 51))
  (segment (start 102.29 167.0114) (end 102.29 174.94) (width 0.1) (layer "B.Cu") (net 51))
  (segment (start 103.1124 166.189) (end 102.29 167.0114) (width 0.1) (layer "B.Cu") (net 51))
  (segment (start 102.29 174.94) (end 102.5 175.15) (width 0.1) (layer "B.Cu") (net 51))
  (segment (start 103.722 166.189) (end 103.1124 166.189) (width 0.1) (layer "B.Cu") (net 51))
  (segment (start 102.5 175.15) (end 102.5 175.675) (width 0.1) (layer "B.Cu") (net 51))
  (segment (start 112 108.95) (end 112.4 108.55) (width 0.15) (layer "F.Cu") (net 52))
  (via (at 104.2173 166.6589) (size 0.5) (drill 0.2) (layers "F.Cu" "B.Cu") (net 52))
  (via (at 112.4 108.55) (size 0.5) (drill 0.2) (layers "F.Cu" "B.Cu") (net 52))
  (segment (start 137.45 136.269824) (end 107.060924 166.6589) (width 0.1) (layer "In5.Cu") (net 52))
  (segment (start 113.683159 107.266841) (end 134.416841 107.266841) (width 0.1) (layer "In5.Cu") (net 52))
  (segment (start 112.4 108.55) (end 113.683159 107.266841) (width 0.1) (layer "In5.Cu") (net 52))
  (segment (start 134.416841 107.266841) (end 137.45 110.3) (width 0.1) (layer "In5.Cu") (net 52))
  (segment (start 137.45 110.3) (end 137.45 136.269824) (width 0.1) (layer "In5.Cu") (net 52))
  (segment (start 107.060924 166.6589) (end 104.2173 166.6589) (width 0.1) (layer "In5.Cu") (net 52))
  (segment (start 102.89 177.345) (end 102.89 167.0083) (width 0.1) (layer "B.Cu") (net 52))
  (segment (start 103.2394 166.6589) (end 104.2173 166.6589) (width 0.1) (layer "B.Cu") (net 52))
  (segment (start 102.89 167.0083) (end 103.2394 166.6589) (width 0.1) (layer "B.Cu") (net 52))
  (segment (start 81.09 169.16) (end 85.7 164.55) (width 0.15) (layer "F.Cu") (net 53))
  (segment (start 85.7 164.55) (end 86.1 164.55) (width 0.15) (layer "F.Cu") (net 53))
  (segment (start 81.09 177.345) (end 81.09 169.16) (width 0.15) (layer "F.Cu") (net 53))
  (via (at 86.1 164.55) (size 0.5) (drill 0.2) (layers "F.Cu" "B.Cu") (net 53))
  (via (at 87.44 137.14) (size 0.5) (drill 0.2) (layers "F.Cu" "B.Cu") (net 53))
  (segment (start 74.12 102.69) (end 65.11 102.69) (width 0.15) (layer "In2.Cu") (net 53))
  (segment (start 74.73 104.6) (end 74.73 103.3) (width 0.15) (layer "In2.Cu") (net 53))
  (segment (start 65.11 102.69) (end 64.61 102.19) (width 0.15) (layer "In2.Cu") (net 53))
  (segment (start 74.73 103.3) (end 74.12 102.69) (width 0.15) (layer "In2.Cu") (net 53))
  (segment (start 64.61 102.19) (end 64.61 100.76) (width 0.15) (layer "In2.Cu") (net 53))
  (segment (start 72.4 106.93) (end 74.73 104.6) (width 0.15) (layer "In5.Cu") (net 53))
  (segment (start 87.44 137.14) (end 86.869989 136.569989) (width 0.15) (layer "In5.Cu") (net 53))
  (segment (start 86.869989 136.569989) (end 84.492825 136.569989) (width 0.15) (layer "In5.Cu") (net 53))
  (segment (start 68.03 108.58) (end 69.68 106.93) (width 0.15) (layer "In5.Cu") (net 53))
  (segment (start 75.912804 127.989967) (end 69.279967 127.989967) (width 0.15) (layer "In5.Cu") (net 53))
  (segment (start 69.68 106.93) (end 72.4 106.93) (width 0.15) (layer "In5.Cu") (net 53))
  (segment (start 68.03 126.74) (end 68.03 108.58) (width 0.15) (layer "In5.Cu") (net 53))
  (segment (start 84.492825 136.569989) (end 75.912804 127.989967) (width 0.15) (layer "In5.Cu") (net 53))
  (segment (start 69.279967 127.989967) (end 68.03 126.74) (width 0.15) (layer "In5.Cu") (net 53))
  (segment (start 87.45 137.13) (end 87.44 137.14) (width 0.15) (layer "B.Cu") (net 53))
  (segment (start 86.1 164.55) (end 86.95 164.55) (width 0.15) (layer "B.Cu") (net 53))
  (segment (start 87.45 136.1) (end 87.45 137.13) (width 0.15) (layer "B.Cu") (net 53))
  (segment (start 86.95 164.55) (end 88.200011 163.299989) (width 0.15) (layer "B.Cu") (net 53))
  (segment (start 88.200011 137.900011) (end 87.44 137.14) (width 0.15) (layer "B.Cu") (net 53))
  (segment (start 88.200011 163.299989) (end 88.200011 137.900011) (width 0.15) (layer "B.Cu") (net 53))
  (segment (start 80.725 174.99) (end 80.725 175.745) (width 0.15) (layer "F.Cu") (net 54))
  (segment (start 80.485 174.75) (end 80.725 174.99) (width 0.15) (layer "F.Cu") (net 54))
  (segment (start 80.725 175.745) (end 80.485 175.985) (width 0.15) (layer "F.Cu") (net 54))
  (segment (start 80.49 169.16) (end 85.6 164.05) (width 0.15) (layer "F.Cu") (net 54))
  (segment (start 85.6 164.05) (end 86.7 164.05) (width 0.15) (layer "F.Cu") (net 54))
  (segment (start 80.485 175.985) (end 80.485 177.31) (width 0.15) (layer "F.Cu") (net 54))
  (segment (start 80.485 174.75) (end 80.49 169.16) (width 0.15) (layer "F.Cu") (net 54))
  (via (at 86.7 164.05) (size 0.5) (drill 0.2) (layers "F.Cu" "B.Cu") (net 54))
  (via (at 86.39 137.14) (size 0.5) (drill 0.2) (layers "F.Cu" "B.Cu") (net 54))
  (segment (start 75.788536 128.289978) (end 69.155699 128.289978) (width 0.15) (layer "In5.Cu") (net 54))
  (segment (start 84.368558 136.87) (end 75.788536 128.289978) (width 0.15) (layer "In5.Cu") (net 54))
  (segment (start 69.53 106.62) (end 71.65 106.62) (width 0.15) (layer "In5.Cu") (net 54))
  (segment (start 69.155699 128.289978) (end 67.729989 126.864268) (width 0.15) (layer "In5.Cu") (net 54))
  (segment (start 86.39 137.14) (end 86.12 136.87) (width 0.15) (layer "In5.Cu") (net 54))
  (segment (start 72.19 106.08) (end 72.19 104.6) (width 0.15) (layer "In5.Cu") (net 54))
  (segment (start 86.12 136.87) (end 84.368558 136.87) (width 0.15) (layer "In5.Cu") (net 54))
  (segment (start 72.19 104.6) (end 72.19 100.8) (width 0.15) (layer "In5.Cu") (net 54))
  (segment (start 67.729989 126.864268) (end 67.729989 108.420011) (width 0.15) (layer "In5.Cu") (net 54))
  (segment (start 71.65 106.62) (end 72.19 106.08) (width 0.15) (layer "In5.Cu") (net 54))
  (segment (start 67.729989 108.420011) (end 69.53 106.62) (width 0.15) (layer "In5.Cu") (net 54))
  (segment (start 86.4 136.075) (end 86.4 137.13) (width 0.15) (layer "B.Cu") (net 54))
  (segment (start 87.9 162.85) (end 87.9 138.65) (width 0.15) (layer "B.Cu") (net 54))
  (segment (start 86.4 137.13) (end 86.39 137.14) (width 0.15) (layer "B.Cu") (net 54))
  (segment (start 86.7 164.05) (end 87.9 162.85) (width 0.15) (layer "B.Cu") (net 54))
  (segment (start 87.9 138.65) (end 86.39 137.14) (width 0.15) (layer "B.Cu") (net 54))
  (segment (start 85.75 165.2) (end 81.69 169.26) (width 0.15) (layer "F.Cu") (net 55))
  (segment (start 81.6 175) (end 81.6 175.8) (width 0.15) (layer "F.Cu") (net 55))
  (segment (start 81.825 174.775) (end 81.6 175) (width 0.15) (layer "F.Cu") (net 55))
  (segment (start 81.825 174.475) (end 81.825 174.775) (width 0.15) (layer "F.Cu") (net 55))
  (segment (start 81.6 175.8) (end 81.675 175.875) (width 0.15) (layer "F.Cu") (net 55))
  (segment (start 81.69 169.26) (end 81.825 174.475) (width 0.15) (layer "F.Cu") (net 55))
  (segment (start 81.675 175.875) (end 81.675 177.45) (width 0.15) (layer "F.Cu") (net 55))
  (segment (start 86.1 165.2) (end 85.75 165.2) (width 0.15) (layer "F.Cu") (net 55))
  (via (at 89.42 137.14) (size 0.5) (drill 0.2) (layers "F.Cu" "B.Cu") (net 55))
  (via (at 86.1 165.2) (size 0.5) (drill 0.2) (layers "F.Cu" "B.Cu") (net 55))
  (segment (start 68.907163 128.89) (end 67.11 127.092837) (width 0.15) (layer "In5.Cu") (net 55))
  (segment (start 84.64 137.99) (end 75.54 128.89) (width 0.15) (layer "In5.Cu") (net 55))
  (segment (start 67.11 104.6) (end 67.11 100.8) (width 0.15) (layer "In5.Cu") (net 55))
  (segment (start 67.11 127.092837) (end 67.11 104.6) (width 0.15) (layer "In5.Cu") (net 55))
  (segment (start 89.42 137.14) (end 88.57 137.99) (width 0.15) (layer "In5.Cu") (net 55))
  (segment (start 88.57 137.99) (end 84.64 137.99) (width 0.15) (layer "In5.Cu") (net 55))
  (segment (start 75.54 128.89) (end 68.907163 128.89) (width 0.15) (layer "In5.Cu") (net 55))
  (segment (start 86.1 165.2) (end 86.6 165.7) (width 0.15) (layer "B.Cu") (net 55))
  (segment (start 88.800033 164.099967) (end 88.800033 137.759967) (width 0.15) (layer "B.Cu") (net 55))
  (segment (start 89.525 136.075) (end 89.525 137.035) (width 0.15) (layer "B.Cu") (net 55))
  (segment (start 88.800033 137.759967) (end 89.42 137.14) (width 0.15) (layer "B.Cu") (net 55))
  (segment (start 86.6 165.7) (end 87.2 165.7) (width 0.15) (layer "B.Cu") (net 55))
  (segment (start 87.2 165.7) (end 88.800033 164.099967) (width 0.15) (layer "B.Cu") (net 55))
  (segment (start 89.525 137.035) (end 89.42 137.14) (width 0.15) (layer "B.Cu") (net 55))
  (segment (start 82.65 175.65) (end 82.275 176.025) (width 0.15) (layer "F.Cu") (net 56))
  (segment (start 82.29 169.36) (end 82.29 174.79) (width 0.15) (layer "F.Cu") (net 56))
  (segment (start 82.29 174.79) (end 82.65 175.15) (width 0.15) (layer "F.Cu") (net 56))
  (segment (start 82.275 176.025) (end 82.275 177.3) (width 0.15) (layer "F.Cu") (net 56))
  (segment (start 85.95 165.7) (end 86.3 165.7) (width 0.15) (layer "F.Cu") (net 56))
  (segment (start 82.29 169.36) (end 85.95 165.7) (width 0.15) (layer "F.Cu") (net 56))
  (segment (start 86.3 165.7) (end 86.8 165.2) (width 0.15) (layer "F.Cu") (net 56))
  (segment (start 82.65 175.15) (end 82.65 175.65) (width 0.15) (layer "F.Cu") (net 56))
  (via (at 88.499994 137.14) (size 0.5) (drill 0.2) (layers "F.Cu" "B.Cu") (net 56))
  (via (at 86.8 165.2) (size 0.5) (drill 0.2) (layers "F.Cu" "B.Cu") (net 56))
  (segment (start 69.031431 128.589989) (end 67.429978 126.988536) (width 0.15) (layer "In5.Cu") (net 56))
  (segment (start 84.764267 137.689989) (end 75.664268 128.589989) (width 0.15) (layer "In5.Cu") (net 56))
  (segment (start 67.429978 106.820022) (end 69.65 104.6) (width 0.15) (layer "In5.Cu") (net 56))
  (segment (start 88.499994 137.14) (end 87.950005 137.689989) (width 0.15) (layer "In5.Cu") (net 56))
  (segment (start 87.950005 137.689989) (end 84.764267 137.689989) (width 0.15) (layer "In5.Cu") (net 56))
  (segment (start 69.65 104.6) (end 69.65 100.8) (width 0.15) (layer "In5.Cu") (net 56))
  (segment (start 75.664268 128.589989) (end 69.031431 128.589989) (width 0.15) (layer "In5.Cu") (net 56))
  (segment (start 67.429978 126.988536) (end 67.429978 106.820022) (width 0.15) (layer "In5.Cu") (net 56))
  (segment (start 88.500022 163.499978) (end 88.500022 137.140028) (width 0.15) (layer "B.Cu") (net 56))
  (segment (start 88.499994 136.95) (end 88.5 136.949994) (width 0.15) (layer "B.Cu") (net 56))
  (segment (start 88.5 136.91) (end 88.5 136.05) (width 0.15) (layer "B.Cu") (net 56))
  (segment (start 88.500022 137.140028) (end 88.499994 137.14) (width 0.15) (layer "B.Cu") (net 56))
  (segment (start 88.5 136.949994) (end 88.5 136.91) (width 0.15) (layer "B.Cu") (net 56))
  (segment (start 86.8 165.2) (end 88.500022 163.499978) (width 0.15) (layer "B.Cu") (net 56))
  (segment (start 88.499994 137.14) (end 88.499994 136.95) (width 0.15) (layer "B.Cu") (net 56))
  (segment (start 84.965 64.71) (end 85.89 64.71) (width 0.3) (layer "F.Cu") (net 57))
  (segment (start 84.965 63.985) (end 86.015 63.985) (width 0.3) (layer "F.Cu") (net 57))
  (segment (start 75.09 174.065) (end 75.025 174) (width 0.3) (layer "F.Cu") (net 57))
  (segment (start 74.15 175.75) (end 74.15 174) (width 0.3) (layer "F.Cu") (net 57))
  (segment (start 74.49 177.345) (end 74.49 176.09) (width 0.3) (layer "F.Cu") (net 57))
  (segment (start 75.09 177.345) (end 75.09 174.065) (width 0.3) (layer "F.Cu") (net 57))
  (segment (start 74.49 176.09) (end 74.15 175.75) (width 0.3) (layer "F.Cu") (net 57))
  (segment (start 84.965 63.26) (end 85.965 63.26) (width 0.3) (layer "F.Cu") (net 57))
  (via (at 74.15 174.8) (size 0.6) (drill 0.3) (layers "F.Cu" "B.Cu") (net 57))
  (via (at 75.025 174.8) (size 0.6) (drill 0.3) (layers "F.Cu" "B.Cu") (net 57))
  (via (at 74.15 174) (size 0.6) (drill 0.3) (layers "F.Cu" "B.Cu") (net 57))
  (via (at 75.025 174) (size 0.6) (drill 0.3) (layers "F.Cu" "B.Cu") (net 57))
  (via (at 64.6 162.89) (size 0.6) (drill 0.3) (layers "F.Cu" "B.Cu") (net 57))
  (via (at 64.6 162.015) (size 0.6) (drill 0.3) (layers "F.Cu" "B.Cu") (net 57))
  (via (at 63.8 162.89) (size 0.6) (drill 0.3) (layers "F.Cu" "B.Cu") (net 57))
  (via (at 63.8 162.015) (size 0.6) (drill 0.3) (layers "F.Cu" "B.Cu") (net 57))
  (via (at 65.4 162.015) (size 0.6) (drill 0.3) (layers "F.Cu" "B.Cu") (net 57))
  (via (at 65.4 162.89) (size 0.6) (drill 0.3) (layers "F.Cu" "B.Cu") (net 57))
  (via (at 84.965 63.26) (size 0.6) (drill 0.3) (layers "F.Cu" "B.Cu") (net 57))
  (via (at 75.025 175.6) (size 0.6) (drill 0.3) (layers "F.Cu" "B.Cu") (net 57))
  (via (at 84.965 64.71) (size 0.6) (drill 0.3) (layers "F.Cu" "B.Cu") (net 57))
  (via (at 74.15 175.6) (size 0.6) (drill 0.3) (layers "F.Cu" "B.Cu") (net 57))
  (via (at 84.965 63.985) (size 0.6) (drill 0.3) (layers "F.Cu" "B.Cu") (net 57))
  (segment (start 75.09 174.065) (end 75.025 174) (width 0.3) (layer "B.Cu") (net 57))
  (segment (start 74.15 175.725) (end 74.15 174) (width 0.3) (layer "B.Cu") (net 57))
  (segment (start 74.49 176.065) (end 74.15 175.725) (width 0.3) (layer "B.Cu") (net 57))
  (segment (start 74.49 177.345) (end 74.49 176.065) (width 0.3) (layer "B.Cu") (net 57))
  (segment (start 75.09 177.345) (end 75.09 174.065) (width 0.3) (layer "B.Cu") (net 57))
  (segment (start 93.585 132.155) (end 93.985 132.555) (width 0.15) (layer "F.Cu") (net 58))
  (segment (start 83.2 163.45) (end 75.69 170.96) (width 0.15) (layer "F.Cu") (net 58))
  (segment (start 116.0325 161.62) (end 120.66 161.62) (width 0.15) (layer "F.Cu") (net 58))
  (segment (start 126.55 156.4) (end 127.1 155.85) (width 0.15) (layer "F.Cu") (net 58))
  (segment (start 115.270001 160.857501) (end 116.0325 161.62) (width 0.15) (layer "F.Cu") (net 58))
  (segment (start 89.575054 160.875) (end 85.575 160.875) (width 0.15) (layer "F.Cu") (net 58))
  (segment (start 83.2 163.25) (end 83.2 163.45) (width 0.15) (layer "F.Cu") (net 58))
  (segment (start 75.69 170.96) (end 75.69 177.345) (width 0.15) (layer "F.Cu") (net 58))
  (segment (start 126.55 157.325) (end 126.55 156.4) (width 0.15) (layer "F.Cu") (net 58))
  (segment (start 85.575 160.875) (end 83.2 163.25) (width 0.15) (layer "F.Cu") (net 58))
  (segment (start 127.1 155.85) (end 127.1 154.785) (width 0.15) (layer "F.Cu") (net 58))
  (via (at 93.985 132.555) (size 0.5) (drill 0.2) (layers "F.Cu" "B.Cu") (net 58))
  (via (at 116.02499 161.6) (size 0.5) (drill 0.2) (layers "F.Cu" "B.Cu") (net 58))
  (via (at 120.66 161.62) (size 0.5) (drill 0.2) (layers "F.Cu" "B.Cu") (net 58))
  (via (at 127.1 155.85) (size 0.5) (drill 0.2) (layers "F.Cu" "B.Cu") (net 58))
  (via (at 89.575054 160.875) (size 0.5) (drill 0.2) (layers "F.Cu" "B.Cu") (net 58))
  (via (at 83.2 163.25) (size 0.5) (drill 0.2) (layers "F.Cu" "B.Cu") (net 58))
  (segment (start 127.1 155.85) (end 127.1 156.44) (width 0.15) (layer "In5.Cu") (net 58))
  (segment (start 108.793386 170.053) (end 116.02499 162.821396) (width 0.1) (layer "In5.Cu") (net 58))
  (segment (start 88.5 168.55) (end 92.604 168.55) (width 0.1) (layer "In5.Cu") (net 58))
  (segment (start 116.02499 162.821396) (end 116.02499 161.6) (width 0.1) (layer "In5.Cu") (net 58))
  (segment (start 94.107 170.053) (end 108.793386 170.053) (width 0.1) (layer "In5.Cu") (net 58))
  (segment (start 92.604 168.55) (end 94.107 170.053) (width 0.1) (layer "In5.Cu") (net 58))
  (segment (start 127.1 156.44) (end 121.92 161.62) (width 0.15) (layer "In5.Cu") (net 58))
  (segment (start 83.2 163.25) (end 88.5 168.55) (width 0.1) (layer "In5.Cu") (net 58))
  (segment (start 121.92 161.62) (end 120.66 161.62) (width 0.15) (layer "In5.Cu") (net 58))
  (segment (start 89.41 139.39) (end 89.41 160.356393) (width 0.15) (layer "B.Cu") (net 58))
  (segment (start 89.575054 160.521447) (end 89.575054 160.875) (width 0.15) (layer "B.Cu") (net 58))
  (segment (start 93.985 132.555) (end 93.985 134.815) (width 0.15) (layer "B.Cu") (net 58))
  (segment (start 93.985 134.815) (end 89.41 139.39) (width 0.15) (layer "B.Cu") (net 58))
  (segment (start 89.41 160.356393) (end 89.575054 160.521447) (width 0.15) (layer "B.Cu") (net 58))
  (segment (start 86.685 166.705354) (end 92.640354 160.75) (width 0.1) (layer "F.Cu") (net 59))
  (segment (start 97.766916 160.75) (end 107.6 150.916916) (width 0.1) (layer "F.Cu") (net 59))
  (segment (start 106.1 140.520472) (end 107.469944 139.150528) (width 0.1) (layer "F.Cu") (net 59))
  (segment (start 86.685 177.345) (end 86.685 166.705354) (width 0.1) (layer "F.Cu") (net 59))
  (segment (start 106.1 144.838352) (end 106.1 140.520472) (width 0.1) (layer "F.Cu") (net 59))
  (segment (start 92.640354 160.75) (end 97.766916 160.75) (width 0.1) (layer "F.Cu") (net 59))
  (segment (start 107.6 150.916916) (end 107.6 146.338352) (width 0.1) (layer "F.Cu") (net 59))
  (segment (start 116 116.15) (end 115.6 116.55) (width 0.15) (layer "F.Cu") (net 59))
  (segment (start 107.469944 139.150528) (end 108.499472 139.150528) (width 0.1) (layer "F.Cu") (net 59))
  (segment (start 107.6 146.338352) (end 106.1 144.838352) (width 0.1) (layer "F.Cu") (net 59))
  (via (at 115.6 116.55) (size 0.5) (drill 0.2) (layers "F.Cu" "B.Cu") (net 59))
  (via (at 108.499472 139.150528) (size 0.5) (drill 0.2) (layers "F.Cu" "B.Cu") (net 59))
  (segment (start 115.6 116.55) (end 115.6 117.360101) (width 0.1) (layer "In5.Cu") (net 59))
  (segment (start 114.063048 139.150528) (end 108.499472 139.150528) (width 0.1) (layer "In5.Cu") (net 59))
  (segment (start 115.6 117.360101) (end 117.95 119.710101) (width 0.1) (layer "In5.Cu") (net 59))
  (segment (start 117.95 119.710101) (end 117.95 135.263576) (width 0.1) (layer "In5.Cu") (net 59))
  (segment (start 117.95 135.263576) (end 114.063048 139.150528) (width 0.1) (layer "In5.Cu") (net 59))
  (segment (start 116.8 116.15) (end 116.4 116.55) (width 0.15) (layer "F.Cu") (net 60))
  (segment (start 87.29 177.345) (end 87.29 166.45391) (width 0.1) (layer "F.Cu") (net 60))
  (segment (start 106.35 140.800806) (end 107.54519 139.605616) (width 0.1) (layer "F.Cu") (net 60))
  (segment (start 87.29 166.45391) (end 92.74391 161) (width 0.1) (layer "F.Cu") (net 60))
  (segment (start 107.54519 139.605616) (end 108.108437 139.605616) (width 0.1) (layer "F.Cu") (net 60))
  (segment (start 107.85 146.234796) (end 106.35 144.734796) (width 0.1) (layer "F.Cu") (net 60))
  (segment (start 107.85 151.020472) (end 107.85 146.234796) (width 0.1) (layer "F.Cu") (net 60))
  (segment (start 97.870472 161) (end 107.85 151.020472) (width 0.1) (layer "F.Cu") (net 60))
  (segment (start 106.35 144.734796) (end 106.35 140.800806) (width 0.1) (layer "F.Cu") (net 60))
  (segment (start 92.74391 161) (end 97.870472 161) (width 0.1) (layer "F.Cu") (net 60))
  (via (at 116.4 116.55) (size 0.5) (drill 0.2) (layers "F.Cu" "B.Cu") (net 60))
  (via (at 108.108437 139.605616) (size 0.5) (drill 0.2) (layers "F.Cu" "B.Cu") (net 60))
  (segment (start 118.200011 118.750011) (end 118.200011 135.367121) (width 0.1) (layer "In5.Cu") (net 60))
  (segment (start 116.4 116.55) (end 116.4 116.665383) (width 0.1) (layer "In5.Cu") (net 60))
  (segment (start 114.015012 139.55212) (end 108.161933 139.55212) (width 0.1) (layer "In5.Cu") (net 60))
  (segment (start 108.161933 139.55212) (end 108.108437 139.605616) (width 0.1) (layer "In5.Cu") (net 60))
  (segment (start 117.232947 117.49833) (end 118.01945 117.49833) (width 0.1) (layer "In5.Cu") (net 60))
  (segment (start 116.4 116.665383) (end 117.232947 117.49833) (width 0.1) (layer "In5.Cu") (net 60))
  (segment (start 118.2 117.67888) (end 118.2 118.75) (width 0.1) (layer "In5.Cu") (net 60))
  (segment (start 118.200011 135.367121) (end 114.015012 139.55212) (width 0.1) (layer "In5.Cu") (net 60))
  (segment (start 118.2 118.75) (end 118.200011 118.750011) (width 0.1) (layer "In5.Cu") (net 60))
  (segment (start 118.01945 117.49833) (end 118.2 117.67888) (width 0.1) (layer "In5.Cu") (net 60))
  (segment (start 108.644383 140.005617) (end 108.65 140) (width 0.1) (layer "F.Cu") (net 61))
  (segment (start 87.89 166.207466) (end 92.847466 161.25) (width 0.1) (layer "F.Cu") (net 61))
  (segment (start 87.89 177.345) (end 87.89 166.207466) (width 0.1) (layer "F.Cu") (net 61))
  (segment (start 92.847466 161.25) (end 97.974028 161.25) (width 0.1) (layer "F.Cu") (net 61))
  (segment (start 106.6 144.63124) (end 106.6 141.08114) (width 0.1) (layer "F.Cu") (net 61))
  (segment (start 107.675523 140.005617) (end 108.644383 140.005617) (width 0.1) (layer "F.Cu") (net 61))
  (segment (start 108.1 146.13124) (end 106.6 144.63124) (width 0.1) (layer "F.Cu") (net 61))
  (segment (start 97.974028 161.25) (end 108.1 151.124028) (width 0.1) (layer "F.Cu") (net 61))
  (segment (start 108.1 151.124028) (end 108.1 146.13124) (width 0.1) (layer "F.Cu") (net 61))
  (segment (start 106.6 141.08114) (end 107.675523 140.005617) (width 0.1) (layer "F.Cu") (net 61))
  (segment (start 115.2 115.35) (end 115.6 115.75) (width 0.15) (layer "F.Cu") (net 61))
  (via (at 108.65 140) (size 0.5) (drill 0.2) (layers "F.Cu" "B.Cu") (net 61))
  (via (at 115.6 115.75) (size 0.5) (drill 0.2) (layers "F.Cu" "B.Cu") (net 61))
  (segment (start 118.45 117.575324) (end 118.028448 117.153772) (width 0.1) (layer "In5.Cu") (net 61))
  (segment (start 113.888029 140) (end 118.45 135.438029) (width 0.1) (layer "In5.Cu") (net 61))
  (segment (start 116.75 116.15) (end 116 116.15) (width 0.1) (layer "In5.Cu") (net 61))
  (segment (start 118.45 135.438029) (end 118.45 117.575324) (width 0.1) (layer "In5.Cu") (net 61))
  (segment (start 118.028448 117.153772) (end 117.232947 117.153772) (width 0.1) (layer "In5.Cu") (net 61))
  (segment (start 116 116.15) (end 115.6 115.75) (width 0.1) (layer "In5.Cu") (net 61))
  (segment (start 117.232947 117.153772) (end 116.96778 116.888605) (width 0.1) (layer "In5.Cu") (net 61))
  (segment (start 116.96778 116.36778) (end 116.75 116.15) (width 0.1) (layer "In5.Cu") (net 61))
  (segment (start 108.65 140) (end 113.888029 140) (width 0.1) (layer "In5.Cu") (net 61))
  (segment (start 116.96778 116.888605) (end 116.96778 116.36778) (width 0.1) (layer "In5.Cu") (net 61))
  (segment (start 108.35 151.227584) (end 108.35 146.027684) (width 0.1) (layer "F.Cu") (net 62))
  (segment (start 106.85 144.527684) (end 106.85 141.361474) (width 0.1) (layer "F.Cu") (net 62))
  (segment (start 92.951022 161.5) (end 98.077584 161.5) (width 0.1) (layer "F.Cu") (net 62))
  (segment (start 88.49 165.961022) (end 92.951022 161.5) (width 0.1) (layer "F.Cu") (net 62))
  (segment (start 108.35 146.027684) (end 106.85 144.527684) (width 0.1) (layer "F.Cu") (net 62))
  (segment (start 115.2 113.75) (end 115.6 114.15) (width 0.15) (layer "F.Cu") (net 62))
  (segment (start 88.49 177.345) (end 88.49 165.961022) (width 0.1) (layer "F.Cu") (net 62))
  (segment (start 107.711474 140.5) (end 108.2 140.5) (width 0.1) (layer "F.Cu") (net 62))
  (segment (start 106.85 141.361474) (end 107.711474 140.5) (width 0.1) (layer "F.Cu") (net 62))
  (segment (start 98.077584 161.5) (end 108.35 151.227584) (width 0.1) (layer "F.Cu") (net 62))
  (via (at 115.6 114.15) (size 0.5) (drill 0.2) (layers "F.Cu" "B.Cu") (net 62))
  (via (at 108.2 140.5) (size 0.5) (drill 0.2) (layers "F.Cu" "B.Cu") (net 62))
  (via (at 117.51715 116.68285) (size 0.5) (drill 0.2) (layers "F.Cu" "B.Cu") (net 62))
  (segment (start 117.717149 114.867149) (end 117.717149 116.482851) (width 0.1) (layer "In2.Cu") (net 62))
  (segment (start 115.6 114.15) (end 116 114.55) (width 0.1) (layer "In2.Cu") (net 62))
  (segment (start 117.717149 116.482851) (end 117.51715 116.68285) (width 0.1) (layer "In2.Cu") (net 62))
  (segment (start 116 114.55) (end 117.4 114.55) (width 0.1) (layer "In2.Cu") (net 62))
  (segment (start 117.4 114.55) (end 117.717149 114.867149) (width 0.1) (layer "In2.Cu") (net 62))
  (segment (start 113.774244 140.5) (end 118.7 135.574244) (width 0.1) (layer "In5.Cu") (net 62))
  (segment (start 108.2 140.5) (end 113.774244 140.5) (width 0.1) (layer "In5.Cu") (net 62))
  (segment (start 118.7 117.471768) (end 117.911082 116.68285) (width 0.1) (layer "In5.Cu") (net 62))
  (segment (start 118.7 135.574244) (end 118.7 117.471768) (width 0.1) (layer "In5.Cu") (net 62))
  (segment (start 117.911082 116.68285) (end 117.51715 116.68285) (width 0.1) (layer "In5.Cu") (net 62))
  (segment (start 116.8 115.35) (end 117.2 115.75) (width 0.15) (layer "F.Cu") (net 63))
  (segment (start 107.641808 141.1) (end 108.65 141.1) (width 0.1) (layer "F.Cu") (net 63))
  (segment (start 89.09 177.345) (end 89.09 165.714578) (width 0.1) (layer "F.Cu") (net 63))
  (segment (start 108.6 151.33114) (end 108.6 145.924128) (width 0.1) (layer "F.Cu") (net 63))
  (segment (start 107.1 144.424128) (end 107.1 141.641808) (width 0.1) (layer "F.Cu") (net 63))
  (segment (start 98.18114 161.75) (end 108.6 151.33114) (width 0.1) (layer "F.Cu") (net 63))
  (segment (start 108.6 145.924128) (end 107.1 144.424128) (width 0.1) (layer "F.Cu") (net 63))
  (segment (start 107.1 141.641808) (end 107.641808 141.1) (width 0.1) (layer "F.Cu") (net 63))
  (segment (start 89.09 165.714578) (end 93.054578 161.75) (width 0.1) (layer "F.Cu") (net 63))
  (segment (start 93.054578 161.75) (end 98.18114 161.75) (width 0.1) (layer "F.Cu") (net 63))
  (via (at 117.2 115.75) (size 0.5) (drill 0.2) (layers "F.Cu" "B.Cu") (net 63))
  (via (at 108.65 141.1) (size 0.5) (drill 0.2) (layers "F.Cu" "B.Cu") (net 63))
  (segment (start 108.65 141.1) (end 113.5278 141.1) (width 0.1) (layer "In5.Cu") (net 63))
  (segment (start 118.569234 115.75) (end 117.2 115.75) (width 0.1) (layer "In5.Cu") (net 63))
  (segment (start 113.5278 141.1) (end 118.95 135.6778) (width 0.1) (layer "In5.Cu") (net 63))
  (segment (start 118.95 135.6778) (end 118.95 116.130766) (width 0.1) (layer "In5.Cu") (net 63))
  (segment (start 118.95 116.130766) (end 118.569234 115.75) (width 0.1) (layer "In5.Cu") (net 63))
  (segment (start 107.672142 141.6) (end 108.2 141.6) (width 0.1) (layer "F.Cu") (net 64))
  (segment (start 89.69 165.468134) (end 93.158134 162) (width 0.1) (layer "F.Cu") (net 64))
  (segment (start 107.35 144.320572) (end 107.35 141.922142) (width 0.1) (layer "F.Cu") (net 64))
  (segment (start 107.35 141.922142) (end 107.672142 141.6) (width 0.1) (layer "F.Cu") (net 64))
  (segment (start 108.85 145.820572) (end 107.35 144.320572) (width 0.1) (layer "F.Cu") (net 64))
  (segment (start 116 115.35) (end 116.4 115.75) (width 0.15) (layer "F.Cu") (net 64))
  (segment (start 108.85 151.434696) (end 108.85 145.820572) (width 0.1) (layer "F.Cu") (net 64))
  (segment (start 98.284696 162) (end 108.85 151.434696) (width 0.1) (layer "F.Cu") (net 64))
  (segment (start 89.69 177.345) (end 89.69 165.468134) (width 0.1) (layer "F.Cu") (net 64))
  (segment (start 93.158134 162) (end 98.284696 162) (width 0.1) (layer "F.Cu") (net 64))
  (via (at 108.2 141.6) (size 0.5) (drill 0.2) (layers "F.Cu" "B.Cu") (net 64))
  (via (at 116.4 115.75) (size 0.5) (drill 0.2) (layers "F.Cu" "B.Cu") (net 64))
  (segment (start 116.4 115.75) (end 116.8 115.35) (width 0.1) (layer "In5.Cu") (net 64))
  (segment (start 119.2 116.02721) (end 119.2 135.781356) (width 0.1) (layer "In5.Cu") (net 64))
  (segment (start 116.8 115.35) (end 118.52279 115.35) (width 0.1) (layer "In5.Cu") (net 64))
  (segment (start 118.52279 115.35) (end 119.2 116.02721) (width 0.1) (layer "In5.Cu") (net 64))
  (segment (start 119.2 135.781356) (end 113.381356 141.6) (width 0.1) (layer "In5.Cu") (net 64))
  (segment (start 113.381356 141.6) (end 108.2 141.6) (width 0.1) (layer "In5.Cu") (net 64))
  (segment (start 109.1 151.538252) (end 109.1 145.717016) (width 0.1) (layer "F.Cu") (net 65))
  (segment (start 90.29 177.345) (end 90.29 165.22169) (width 0.1) (layer "F.Cu") (net 65))
  (segment (start 116.8 114.55) (end 117.2 114.95) (width 0.15) (layer "F.Cu") (net 65))
  (segment (start 107.906032 142.25) (end 108.65 142.25) (width 0.1) (layer "F.Cu") (net 65))
  (segment (start 90.29 165.22169) (end 93.26163 162.25006) (width 0.1) (layer "F.Cu") (net 65))
  (segment (start 107.6 144.217016) (end 107.6 142.556032) (width 0.1) (layer "F.Cu") (net 65))
  (segment (start 98.388192 162.25006) (end 109.1 151.538252) (width 0.1) (layer "F.Cu") (net 65))
  (segment (start 109.1 145.717016) (end 107.6 144.217016) (width 0.1) (layer "F.Cu") (net 65))
  (segment (start 93.26163 162.25006) (end 98.388192 162.25006) (width 0.1) (layer "F.Cu") (net 65))
  (segment (start 107.6 142.556032) (end 107.906032 142.25) (width 0.1) (layer "F.Cu") (net 65))
  (via (at 108.65 142.25) (size 0.5) (drill 0.2) (layers "F.Cu" "B.Cu") (net 65))
  (via (at 117.2 114.95) (size 0.5) (drill 0.2) (layers "F.Cu" "B.Cu") (net 65))
  (segment (start 119.45 115.923654) (end 119.45 135.884912) (width 0.1) (layer "In5.Cu") (net 65))
  (segment (start 118.426346 114.9) (end 119.45 115.923654) (width 0.1) (layer "In5.Cu") (net 65))
  (segment (start 119.45 135.884912) (end 113.084912 142.25) (width 0.1) (layer "In5.Cu") (net 65))
  (segment (start 113.084912 142.25) (end 108.65 142.25) (width 0.1) (layer "In5.Cu") (net 65))
  (segment (start 117.2 114.95) (end 117.2 114.9) (width 0.1) (layer "In5.Cu") (net 65))
  (segment (start 117.2 114.9) (end 118.426346 114.9) (width 0.1) (layer "In5.Cu") (net 65))
  (segment (start 109.35 145.61346) (end 107.85 144.11346) (width 0.1) (layer "F.Cu") (net 66))
  (segment (start 109.35 151.641808) (end 109.35 145.61346) (width 0.1) (layer "F.Cu") (net 66))
  (segment (start 107.85 144.11346) (end 107.85 143.1) (width 0.1) (layer "F.Cu") (net 66))
  (segment (start 90.89 164.975246) (end 93.365246 162.5) (width 0.1) (layer "F.Cu") (net 66))
  (segment (start 90.89 177.345) (end 90.89 164.975246) (width 0.1) (layer "F.Cu") (net 66))
  (segment (start 98.491808 162.5) (end 109.35 151.641808) (width 0.1) (layer "F.Cu") (net 66))
  (segment (start 107.85 143.1) (end 108.2 142.75) (width 0.1) (layer "F.Cu") (net 66))
  (segment (start 93.365246 162.5) (end 98.491808 162.5) (width 0.1) (layer "F.Cu") (net 66))
  (segment (start 116 113.75) (end 116.4 114.15) (width 0.15) (layer "F.Cu") (net 66))
  (via (at 108.2 142.75) (size 0.5) (drill 0.2) (layers "F.Cu" "B.Cu") (net 66))
  (via (at 116.4 114.15) (size 0.5) (drill 0.2) (layers "F.Cu" "B.Cu") (net 66))
  (segment (start 108.2 142.75) (end 112.938468 142.75) (width 0.1) (layer "In5.Cu") (net 66))
  (segment (start 119.7 115.820098) (end 118.429902 114.55) (width 0.1) (layer "In5.Cu") (net 66))
  (segment (start 119.7 135.988468) (end 119.7 115.820098) (width 0.1) (layer "In5.Cu") (net 66))
  (segment (start 118.429902 114.55) (end 116.8 114.55) (width 0.1) (layer "In5.Cu") (net 66))
  (segment (start 116.8 114.55) (end 116.4 114.15) (width 0.1) (layer "In5.Cu") (net 66))
  (segment (start 112.938468 142.75) (end 119.7 135.988468) (width 0.1) (layer "In5.Cu") (net 66))
  (segment (start 93.468802 162.75) (end 98.595364 162.75) (width 0.1) (layer "F.Cu") (net 67))
  (segment (start 109.6 145.509904) (end 108.1 144.009904) (width 0.1) (layer "F.Cu") (net 67))
  (segment (start 108.1 143.6) (end 108.45 143.25) (width 0.1) (layer "F.Cu") (net 67))
  (segment (start 91.49 177.345) (end 91.49 164.728802) (width 0.1) (layer "F.Cu") (net 67))
  (segment (start 116.8 113.75) (end 117.2 114.15) (width 0.15) (layer "F.Cu") (net 67))
  (segment (start 108.1 144.009904) (end 108.1 143.6) (width 0.1) (layer "F.Cu") (net 67))
  (segment (start 109.6 151.745364) (end 109.6 145.509904) (width 0.1) (layer "F.Cu") (net 67))
  (segment (start 91.49 164.728802) (end 93.468802 162.75) (width 0.1) (layer "F.Cu") (net 67))
  (segment (start 98.595364 162.75) (end 109.6 151.745364) (width 0.1) (layer "F.Cu") (net 67))
  (segment (start 108.45 143.25) (end 108.65 143.25) (width 0.1) (layer "F.Cu") (net 67))
  (via (at 108.65 143.25) (size 0.5) (drill 0.2) (layers "F.Cu" "B.Cu") (net 67))
  (via (at 117.2 114.15) (size 0.5) (drill 0.2) (layers "F.Cu" "B.Cu") (net 67))
  (segment (start 112.792024 143.25) (end 119.95 136.092024) (width 0.1) (layer "In5.Cu") (net 67))
  (segment (start 108.65 143.25) (end 112.792024 143.25) (width 0.1) (layer "In5.Cu") (net 67))
  (segment (start 119.95 115.716542) (end 118.383458 114.15) (width 0.1) (layer "In5.Cu") (net 67))
  (segment (start 118.383458 114.15) (end 117.2 114.15) (width 0.1) (layer "In5.Cu") (net 67))
  (segment (start 119.95 136.092024) (end 119.95 115.716542) (width 0.1) (layer "In5.Cu") (net 67))
  (segment (start 72.052 158.75802) (end 72.052 160.15712) (width 0.15) (layer "F.Cu") (net 68))
  (segment (start 92.69 175.785) (end 92.925 175.55) (width 0.15) (layer "F.Cu") (net 68))
  (segment (start 92.925 175.55) (end 92.925 174.95) (width 0.15) (layer "F.Cu") (net 68))
  (segment (start 92.329 173.198) (end 92.69 172.837) (width 0.15) (layer "F.Cu") (net 68))
  (segment (start 92.329 173.198) (end 92.329 174.354) (width 0.15) (layer "F.Cu") (net 68))
  (segment (start 92.69 177.345) (end 92.69 175.785) (width 0.15) (layer "F.Cu") (net 68))
  (segment (start 92.925 174.95) (end 92.329 174.354) (width 0.15) (layer "F.Cu") (net 68))
  (via (at 72.052 160.15712) (size 0.5) (drill 0.2) (layers "F.Cu" "B.Cu") (net 68))
  (via (at 92.69 172.837) (size 0.5) (drill 0.2) (layers "F.Cu" "B.Cu") (net 68))
  (segment (start 90.203 170.45) (end 92.69 172.937) (width 0.15) (layer "In5.Cu") (net 68))
  (segment (start 72.052 161.502) (end 81 170.45) (width 0.15) (layer "In5.Cu") (net 68))
  (segment (start 81 170.45) (end 90.203 170.45) (width 0.15) (layer "In5.Cu") (net 68))
  (segment (start 72.052 160.15712) (end 72.052 161.502) (width 0.15) (layer "In5.Cu") (net 68))
  (segment (start 92.69 172.937) (end 92.69 172.837) (width 0.15) (layer "In5.Cu") (net 68))
  (segment (start 72.552 158.75802) (end 72.552 159.75712) (width 0.15) (layer "F.Cu") (net 69))
  (segment (start 92.837 173.482) (end 92.837 174.244) (width 0.15) (layer "F.Cu") (net 69))
  (segment (start 92.837 174.244) (end 93.29 174.697) (width 0.15) (layer "F.Cu") (net 69))
  (segment (start 93.29 174.697) (end 93.29 177.345) (width 0.15) (layer "F.Cu") (net 69))
  (segment (start 93.29 173.029) (end 92.837 173.482) (width 0.15) (layer "F.Cu") (net 69))
  (segment (start 93.29 172.356996) (end 93.29 173.029) (width 0.15) (layer "F.Cu") (net 69))
  (via (at 72.552 159.75712) (size 0.5) (drill 0.2) (layers "F.Cu" "B.Cu") (net 69))
  (via (at 93.29 172.356996) (size 0.5) (drill 0.2) (layers "F.Cu" "B.Cu") (net 69))
  (segment (start 81.2 170.15) (end 90.703 170.15) (width 0.15) (layer "In5.Cu") (net 69))
  (segment (start 90.703 170.15) (end 92.909996 172.356996) (width 0.15) (layer "In5.Cu") (net 69))
  (segment (start 72.552 159.75712) (end 72.552 161.502) (width 0.15) (layer "In5.Cu") (net 69))
  (segment (start 72.552 161.502) (end 81.2 170.15) (width 0.15) (layer "In5.Cu") (net 69))
  (segment (start 92.909996 172.356996) (end 93.29 172.356996) (width 0.15) (layer "In5.Cu") (net 69))
  (segment (start 73.052 158.75802) (end 73.052 160.15712) (width 0.15) (layer "F.Cu") (net 70))
  (segment (start 93.345 173.609) (end 93.345 174.117) (width 0.15) (layer "F.Cu") (net 70))
  (segment (start 93.89 174.662) (end 93.89 177.145) (width 0.15) (layer "F.Cu") (net 70))
  (segment (start 93.89 173.064) (end 93.345 173.609) (width 0.15) (layer "F.Cu") (net 70))
  (segment (start 93.89 172.037) (end 93.89 173.064) (width 0.15) (layer "F.Cu") (net 70))
  (segment (start 93.345 174.117) (end 93.89 174.662) (width 0.15) (layer "F.Cu") (net 70))
  (via (at 93.89 172.037) (size 0.5) (drill 0.2) (layers "F.Cu" "B.Cu") (net 70))
  (via (at 73.052 160.15712) (size 0.5) (drill 0.2) (layers "F.Cu" "B.Cu") (net 70))
  (segment (start 73.052 160.15712) (end 73.052 161.502) (width 0.15) (layer "In5.Cu") (net 70))
  (segment (start 93.500011 171.647011) (end 93.89 172.037) (width 0.15) (layer "In5.Cu") (net 70))
  (segment (start 91.203 169.85) (end 93.000011 171.647011) (width 0.15) (layer "In5.Cu") (net 70))
  (segment (start 81.4 169.85) (end 91.203 169.85) (width 0.15) (layer "In5.Cu") (net 70))
  (segment (start 93.000011 171.647011) (end 93.500011 171.647011) (width 0.15) (layer "In5.Cu") (net 70))
  (segment (start 73.052 161.502) (end 81.4 169.85) (width 0.15) (layer "In5.Cu") (net 70))
  (segment (start 94.49 177.145) (end 94.49 171.637) (width 0.15) (layer "F.Cu") (net 71))
  (segment (start 73.552 158.75802) (end 73.552 159.75712) (width 0.15) (layer "F.Cu") (net 71))
  (segment (start 94.49 171.637) (end 94.2 171.347) (width 0.15) (layer "F.Cu") (net 71))
  (via (at 94.2 171.347) (size 0.5) (drill 0.2) (layers "F.Cu" "B.Cu") (net 71))
  (via (at 73.552 159.75712) (size 0.5) (drill 0.2) (layers "F.Cu" "B.Cu") (net 71))
  (segment (start 73.552 159.75712) (end 73.552 161.502) (width 0.15) (layer "In5.Cu") (net 71))
  (segment (start 73.552 161.502) (end 81.6 169.55) (width 0.15) (layer "In5.Cu") (net 71))
  (segment (start 93.25 171.347) (end 94.2 171.347) (width 0.15) (layer "In5.Cu") (net 71))
  (segment (start 81.6 169.55) (end 91.453 169.55) (width 0.15) (layer "In5.Cu") (net 71))
  (segment (start 91.453 169.55) (end 93.25 171.347) (width 0.15) (layer "In5.Cu") (net 71))
  (segment (start 94.4 170.847) (end 93.6 170.847) (width 0.15) (layer "F.Cu") (net 72))
  (segment (start 95.09 177.145) (end 95.09 171.537) (width 0.15) (layer "F.Cu") (net 72))
  (segment (start 95.09 171.537) (end 94.4 170.847) (width 0.15) (layer "F.Cu") (net 72))
  (segment (start 74.052 158.75802) (end 74.052 160.15712) (width 0.15) (layer "F.Cu") (net 72))
  (via (at 93.6 170.847) (size 0.5) (drill 0.2) (layers "F.Cu" "B.Cu") (net 72))
  (via (at 74.052 160.15712) (size 0.5) (drill 0.2) (layers "F.Cu" "B.Cu") (net 72))
  (segment (start 74.052 161.502) (end 74.052 160.15712) (width 0.15) (layer "In5.Cu") (net 72))
  (segment (start 81.8 169.25) (end 74.052 161.502) (width 0.15) (layer "In5.Cu") (net 72))
  (segment (start 81.8 169.25) (end 92.003 169.25) (width 0.15) (layer "In5.Cu") (net 72))
  (segment (start 92.003 169.25) (end 93.6 170.847) (width 0.15) (layer "In5.Cu") (net 72))
  (segment (start 95.69 171.483447) (end 95.69 177.145) (width 0.15) (layer "F.Cu") (net 73))
  (segment (start 94.95 170.743447) (end 95.69 171.483447) (width 0.15) (layer "F.Cu") (net 73))
  (segment (start 94.95 170.597) (end 94.95 170.743447) (width 0.15) (layer "F.Cu") (net 73))
  (segment (start 95.69 177.345) (end 95.69 175.54) (width 0.15) (layer "F.Cu") (net 73))
  (segment (start 74.552 158.75802) (end 74.552 159.75712) (width 0.15) (layer "F.Cu") (net 73))
  (via (at 74.552 159.75712) (size 0.5) (drill 0.2) (layers "F.Cu" "B.Cu") (net 73))
  (via (at 94.95 170.597) (size 0.5) (drill 0.2) (layers "F.Cu" "B.Cu") (net 73))
  (segment (start 92.496 168.95) (end 94.143 170.597) (width 0.15) (layer "In5.Cu") (net 73))
  (segment (start 94.143 170.597) (end 94.95 170.597) (width 0.15) (layer "In5.Cu") (net 73))
  (segment (start 74.552 161.502) (end 82 168.95) (width 0.15) (layer "In5.Cu") (net 73))
  (segment (start 82 168.95) (end 92.496 168.95) (width 0.15) (layer "In5.Cu") (net 73))
  (segment (start 74.552 159.75712) (end 74.552 161.502) (width 0.15) (layer "In5.Cu") (net 73))
  (segment (start 96.89 177.145) (end 96.89 164.80892) (width 0.1) (layer "F.Cu") (net 74))
  (segment (start 109.85 140.004794) (end 110.7 139.154794) (width 0.1) (layer "F.Cu") (net 74))
  (segment (start 110.7 139.154794) (end 110.7 135.35) (width 0.1) (layer "F.Cu") (net 74))
  (segment (start 110.7 135.35) (end 112.65 133.4) (width 0.1) (layer "F.Cu") (net 74))
  (segment (start 96.89 164.80892) (end 109.85 151.84892) (width 0.1) (layer "F.Cu") (net 74))
  (segment (start 109.85 151.84892) (end 109.85 140.004794) (width 0.1) (layer "F.Cu") (net 74))
  (segment (start 112.65 133.4) (end 112.65 131.5) (width 0.1) (layer "F.Cu") (net 74))
  (segment (start 112.65 131.5) (end 113.6 130.55) (width 0.1) (layer "F.Cu") (net 74))
  (segment (start 110.1 140.10835) (end 110.95 139.25835) (width 0.1) (layer "F.Cu") (net 75))
  (segment (start 97.49 177.145) (end 97.49 174.833) (width 0.1) (layer "F.Cu") (net 75))
  (segment (start 97.282 164.770476) (end 110.1 151.952476) (width 0.1) (layer "F.Cu") (net 75))
  (segment (start 97.282 174.625) (end 97.282 164.770476) (width 0.1) (layer "F.Cu") (net 75))
  (segment (start 112.9 133.55) (end 112.9 132.05) (width 0.1) (layer "F.Cu") (net 75))
  (segment (start 110.1 151.952476) (end 110.1 140.10835) (width 0.1) (layer "F.Cu") (net 75))
  (segment (start 112.9 132.05) (end 113.6 131.35) (width 0.1) (layer "F.Cu") (net 75))
  (segment (start 110.95 135.5) (end 112.9 133.55) (width 0.1) (layer "F.Cu") (net 75))
  (segment (start 97.49 174.833) (end 97.282 174.625) (width 0.1) (layer "F.Cu") (net 75))
  (segment (start 110.95 139.25835) (end 110.95 135.5) (width 0.1) (layer "F.Cu") (net 75))
  (segment (start 111.2 135.65) (end 111.2 139.361906) (width 0.1) (layer "F.Cu") (net 76))
  (segment (start 110.35 140.211906) (end 110.35 152.056032) (width 0.1) (layer "F.Cu") (net 76))
  (segment (start 98.09 174.706) (end 98.09 177.145) (width 0.1) (layer "F.Cu") (net 76))
  (segment (start 97.85 164.556032) (end 97.85 172.907) (width 0.1) (layer "F.Cu") (net 76))
  (segment (start 97.85 172.907) (end 98.190001 173.247001) (width 0.1) (layer "F.Cu") (net 76))
  (segment (start 113.15 132.6) (end 113.15 133.7) (width 0.1) (layer "F.Cu") (net 76))
  (segment (start 111.2 139.361906) (end 110.35 140.211906) (width 0.1) (layer "F.Cu") (net 76))
  (segment (start 98.190001 174.605999) (end 98.09 174.706) (width 0.1) (layer "F.Cu") (net 76))
  (segment (start 113.15 133.7) (end 111.2 135.65) (width 0.1) (layer "F.Cu") (net 76))
  (segment (start 110.35 152.056032) (end 97.85 164.556032) (width 0.1) (layer "F.Cu") (net 76))
  (segment (start 98.190001 173.247001) (end 98.190001 174.605999) (width 0.1) (layer "F.Cu") (net 76))
  (segment (start 113.6 132.15) (end 113.15 132.6) (width 0.1) (layer "F.Cu") (net 76))
  (segment (start 98.69 177.345) (end 98.69 176.185) (width 0.1) (layer "F.Cu") (net 77))
  (segment (start 98.69 174.9315) (end 98.552 174.7935) (width 0.1) (layer "F.Cu") (net 77))
  (segment (start 98.552 174.7935) (end 98.552 173.0375) (width 0.1) (layer "F.Cu") (net 77))
  (segment (start 98.69 164.069588) (end 110.6 152.159588) (width 0.1) (layer "F.Cu") (net 77))
  (segment (start 113.6 133.657996) (end 113.6 132.95) (width 0.1) (layer "F.Cu") (net 77))
  (segment (start 98.552 173.0375) (end 98.69 172.8995) (width 0.1) (layer "F.Cu") (net 77))
  (segment (start 111.45 135.807996) (end 113.6 133.657996) (width 0.1) (layer "F.Cu") (net 77))
  (segment (start 110.6 152.159588) (end 110.6 140.315462) (width 0.1) (layer "F.Cu") (net 77))
  (segment (start 98.69 177.145) (end 98.69 174.9315) (width 0.1) (layer "F.Cu") (net 77))
  (segment (start 111.45 139.465462) (end 111.45 135.807996) (width 0.1) (layer "F.Cu") (net 77))
  (segment (start 98.69 172.8995) (end 98.69 164.069588) (width 0.1) (layer "F.Cu") (net 77))
  (segment (start 110.6 140.315462) (end 111.45 139.465462) (width 0.1) (layer "F.Cu") (net 77))
  (segment (start 113.6 129.75) (end 114 130.15) (width 0.15) (layer "F.Cu") (net 78))
  (segment (start 98.913999 173.247001) (end 98.913999 174.605999) (width 0.1) (layer "F.Cu") (net 78))
  (segment (start 99.314 172.847) (end 98.913999 173.247001) (width 0.1) (layer "F.Cu") (net 78))
  (segment (start 111.7 136.56) (end 111.7 139.569018) (width 0.1) (layer "F.Cu") (net 78))
  (segment (start 111.7 139.569018) (end 110.85 140.419018) (width 0.1) (layer "F.Cu") (net 78))
  (segment (start 99.314 169.847) (end 99.314 172.847) (width 0.1) (layer "F.Cu") (net 78))
  (segment (start 110.85 152.263144) (end 99.29 163.823144) (width 0.1) (layer "F.Cu") (net 78))
  (segment (start 110.85 140.419018) (end 110.85 152.263144) (width 0.1) (layer "F.Cu") (net 78))
  (segment (start 98.913999 174.605999) (end 99.29 174.982) (width 0.1) (layer "F.Cu") (net 78))
  (segment (start 112.9 135.36) (end 111.7 136.56) (width 0.1) (layer "F.Cu") (net 78))
  (segment (start 99.29 163.823144) (end 99.29 169.823) (width 0.1) (layer "F.Cu") (net 78))
  (segment (start 99.29 169.823) (end 99.314 169.847) (width 0.1) (layer "F.Cu") (net 78))
  (segment (start 99.29 174.982) (end 99.29 177.145) (width 0.1) (layer "F.Cu") (net 78))
  (via (at 114 130.15) (size 0.5) (drill 0.2) (layers "F.Cu" "B.Cu") (net 78))
  (via (at 112.9 135.36) (size 0.5) (drill 0.2) (layers "F.Cu" "B.Cu") (net 78))
  (segment (start 114 130.15) (end 112.9 131.25) (width 0.1) (layer "In5.Cu") (net 78))
  (segment (start 112.9 131.25) (end 112.9 135.36) (width 0.1) (layer "In5.Cu") (net 78))
  (segment (start 111.95 139.672574) (end 111.95 137) (width 0.1) (layer "F.Cu") (net 79))
  (segment (start 115.2 129.75) (end 114.8 130.15) (width 0.15) (layer "F.Cu") (net 79))
  (segment (start 99.89 163.5767) (end 111.1 152.3667) (width 0.1) (layer "F.Cu") (net 79))
  (segment (start 111.95 137) (end 112.9 136.05) (width 0.1) (layer "F.Cu") (net 79))
  (segment (start 111.1 152.3667) (end 111.1 140.522574) (width 0.1) (layer "F.Cu") (net 79))
  (segment (start 111.1 140.522574) (end 111.95 139.672574) (width 0.1) (layer "F.Cu") (net 79))
  (segment (start 99.89 177.345) (end 99.89 163.5767) (width 0.1) (layer "F.Cu") (net 79))
  (via (at 112.9 136.05) (size 0.5) (drill 0.2) (layers "F.Cu" "B.Cu") (net 79))
  (via (at 114.8 130.15) (size 0.5) (drill 0.2) (layers "F.Cu" "B.Cu") (net 79))
  (segment (start 113.99 134.96) (end 112.9 136.05) (width 0.1) (layer "In5.Cu") (net 79))
  (segment (start 114.8 130.15) (end 113.99 130.96) (width 0.1) (layer "In5.Cu") (net 79))
  (segment (start 113.99 130.96) (end 113.99 134.96) (width 0.1) (layer "In5.Cu") (net 79))
  (segment (start 111.35 152.470256) (end 111.35 140.62613) (width 0.1) (layer "F.Cu") (net 80))
  (segment (start 111.35 140.62613) (end 112.2 139.77613) (width 0.1) (layer "F.Cu") (net 80))
  (segment (start 112.2 137.454008) (end 112.89 136.764008) (width 0.1) (layer "F.Cu") (net 80))
  (segment (start 100.49 177.345) (end 100.49 163.330256) (width 0.1) (layer "F.Cu") (net 80))
  (segment (start 112.89 136.764008) (end 112.89 136.74) (width 0.1) (layer "F.Cu") (net 80))
  (segment (start 112.2 139.77613) (end 112.2 137.454008) (width 0.1) (layer "F.Cu") (net 80))
  (segment (start 100.49 163.330256) (end 111.35 152.470256) (width 0.1) (layer "F.Cu") (net 80))
  (segment (start 114.4 130.55) (end 114.8 130.95) (width 0.15) (layer "F.Cu") (net 80))
  (via (at 112.89 136.74) (size 0.5) (drill 0.2) (layers "F.Cu" "B.Cu") (net 80))
  (via (at 114.8 130.95) (size 0.5) (drill 0.2) (layers "F.Cu" "B.Cu") (net 80))
  (segment (start 114.190011 135.439989) (end 112.89 136.74) (width 0.1) (layer "In5.Cu") (net 80))
  (segment (start 114.190011 131.559989) (end 114.190011 135.439989) (width 0.1) (layer "In5.Cu") (net 80))
  (segment (start 114.8 130.95) (end 114.190011 131.559989) (width 0.1) (layer "In5.Cu") (net 80))
  (segment (start 111.6 152.573812) (end 111.6 140.729686) (width 0.1) (layer "F.Cu") (net 81))
  (segment (start 111.6 140.729686) (end 112.45 139.879686) (width 0.1) (layer "F.Cu") (net 81))
  (segment (start 114.4 131.35) (end 114.8 131.75) (width 0.15) (layer "F.Cu") (net 81))
  (segment (start 112.45 137.900065) (end 112.900065 137.45) (width 0.1) (layer "F.Cu") (net 81))
  (segment (start 101.09 163.083812) (end 111.6 152.573812) (width 0.1) (layer "F.Cu") (net 81))
  (segment (start 101.09 177.345) (end 101.09 163.083812) (width 0.1) (layer "F.Cu") (net 81))
  (segment (start 112.45 139.879686) (end 112.45 137.900065) (width 0.1) (layer "F.Cu") (net 81))
  (via (at 112.900065 137.45) (size 0.5) (drill 0.2) (layers "F.Cu" "B.Cu") (net 81))
  (via (at 114.8 131.75) (size 0.5) (drill 0.2) (layers "F.Cu" "B.Cu") (net 81))
  (segment (start 114.390021 132.159979) (end 114.390021 135.960044) (width 0.1) (layer "In5.Cu") (net 81))
  (segment (start 114.8 131.75) (end 114.390021 132.159979) (width 0.1) (layer "In5.Cu") (net 81))
  (segment (start 114.390021 135.960044) (end 112.900065 137.45) (width 0.1) (layer "In5.Cu") (net 81))
  (segment (start 106.9 158.33448) (end 112.35 152.88448) (width 0.1) (layer "F.Cu") (net 82))
  (segment (start 114.699907 136.499907) (end 114.4 136.2) (width 0.1) (layer "F.Cu") (net 82))
  (segment (start 112.35 152.88448) (end 112.35 141.040354) (width 0.1) (layer "F.Cu") (net 82))
  (segment (start 114.4 136.2) (end 114.4 132.95) (width 0.1) (layer "F.Cu") (net 82))
  (segment (start 114.699907 138.690447) (end 114.699907 136.499907) (width 0.1) (layer "F.Cu") (net 82))
  (segment (start 112.35 141.040354) (end 114.699907 138.690447) (width 0.1) (layer "F.Cu") (net 82))
  (segment (start 106.9 177.345) (end 106.9 158.33448) (width 0.1) (layer "F.Cu") (net 82))
  (segment (start 115.2 131.35) (end 115.6 131.75) (width 0.15) (layer "F.Cu") (net 83))
  (segment (start 112.6 152.988036) (end 107.49 158.098036) (width 0.1) (layer "F.Cu") (net 83))
  (segment (start 114.9 138.84391) (end 112.6 141.14391) (width 0.1) (layer "F.Cu") (net 83))
  (segment (start 112.6 141.14391) (end 112.6 152.988036) (width 0.1) (layer "F.Cu") (net 83))
  (segment (start 114.9 135.9) (end 114.9 138.84391) (width 0.1) (layer "F.Cu") (net 83))
  (segment (start 107.49 158.098036) (end 107.49 177.345) (width 0.1) (layer "F.Cu") (net 83))
  (via (at 115.6 131.75) (size 0.5) (drill 0.2) (layers "F.Cu" "B.Cu") (net 83))
  (via (at 114.9 135.9) (size 0.5) (drill 0.2) (layers "F.Cu" "B.Cu") (net 83))
  (segment (start 114.9 135.9) (end 114.8 135.8) (width 0.1) (layer "In5.Cu") (net 83))
  (segment (start 115.2 132.2) (end 115.6 131.8) (width 0.1) (layer "In5.Cu") (net 83))
  (segment (start 115.2 133.6) (end 115.2 132.2) (width 0.1) (layer "In5.Cu") (net 83))
  (segment (start 114.8 134) (end 115.2 133.6) (width 0.1) (layer "In5.Cu") (net 83))
  (segment (start 115.6 131.8) (end 115.6 131.75) (width 0.1) (layer "In5.Cu") (net 83))
  (segment (start 114.8 135.8) (end 114.8 134) (width 0.1) (layer "In5.Cu") (net 83))
  (segment (start 115.2 136.2) (end 115.2 136.75) (width 0.1) (layer "B.Cu") (net 83))
  (segment (start 114.9 135.9) (end 115.2 136.2) (width 0.1) (layer "B.Cu") (net 83))
  (segment (start 115.397241 135.722241) (end 115.397241 138.700225) (width 0.1) (layer "F.Cu") (net 84))
  (segment (start 115.2 135.525) (end 115.397241 135.722241) (width 0.1) (layer "F.Cu") (net 84))
  (segment (start 112.85 141.247466) (end 112.85 153.091592) (width 0.1) (layer "F.Cu") (net 84))
  (segment (start 112.85 153.091592) (end 108.09 157.851592) (width 0.1) (layer "F.Cu") (net 84))
  (segment (start 108.09 157.851592) (end 108.09 177.345) (width 0.1) (layer "F.Cu") (net 84))
  (segment (start 115.397241 138.700225) (end 112.85 141.247466) (width 0.1) (layer "F.Cu") (net 84))
  (segment (start 115.2 132.95) (end 115.2 135.525) (width 0.1) (layer "F.Cu") (net 84))
  (segment (start 113.1 153.195148) (end 108.69 157.605148) (width 0.1) (layer "F.Cu") (net 85))
  (segment (start 115.599937 138.851085) (end 113.1 141.351022) (width 0.1) (layer "F.Cu") (net 85))
  (segment (start 115.599937 135.400063) (end 115.599937 138.851085) (width 0.1) (layer "F.Cu") (net 85))
  (segment (start 108.69 157.605148) (end 108.69 177.345) (width 0.1) (layer "F.Cu") (net 85))
  (segment (start 115.7 135.3) (end 115.599937 135.400063) (width 0.1) (layer "F.Cu") (net 85))
  (segment (start 113.1 141.351022) (end 113.1 153.195148) (width 0.1) (layer "F.Cu") (net 85))
  (segment (start 115.2 132.15) (end 115.6 132.55) (width 0.15) (layer "F.Cu") (net 85))
  (via (at 115.7 135.3) (size 0.5) (drill 0.2) (layers "F.Cu" "B.Cu") (net 85))
  (via (at 115.6 132.55) (size 0.5) (drill 0.2) (layers "F.Cu" "B.Cu") (net 85))
  (segment (start 115.5 135.1) (end 115.5 132.65) (width 0.1) (layer "In5.Cu") (net 85))
  (segment (start 115.5 132.65) (end 115.6 132.55) (width 0.1) (layer "In5.Cu") (net 85))
  (segment (start 115.7 135.3) (end 115.5 135.1) (width 0.1) (layer "In5.Cu") (net 85))
  (segment (start 116.249999 135.400001) (end 115.799948 135.850052) (width 0.1) (layer "F.Cu") (net 86))
  (segment (start 113.35 141.454578) (end 113.35 153.298704) (width 0.1) (layer "F.Cu") (net 86))
  (segment (start 115.2 130.55) (end 115.6 130.95) (width 0.15) (layer "F.Cu") (net 86))
  (segment (start 116 134.7) (end 116.249999 134.949999) (width 0.1) (layer "F.Cu") (net 86))
  (segment (start 115.799948 139.00463) (end 113.35 141.454578) (width 0.1) (layer "F.Cu") (net 86))
  (segment (start 113.35 153.298704) (end 109.89 156.758704) (width 0.1) (layer "F.Cu") (net 86))
  (segment (start 109.89 156.758704) (end 109.89 177.345) (width 0.1) (layer "F.Cu") (net 86))
  (segment (start 116.249999 134.949999) (end 116.249999 135.400001) (width 0.1) (layer "F.Cu") (net 86))
  (segment (start 115.799948 135.850052) (end 115.799948 139.00463) (width 0.1) (layer "F.Cu") (net 86))
  (via (at 115.6 130.95) (size 0.5) (drill 0.2) (layers "F.Cu" "B.Cu") (net 86))
  (via (at 116 134.7) (size 0.5) (drill 0.2) (layers "F.Cu" "B.Cu") (net 86))
  (segment (start 116 131.35) (end 115.6 130.95) (width 0.1) (layer "In5.Cu") (net 86))
  (segment (start 116 134.7) (end 116 131.35) (width 0.1) (layer "In5.Cu") (net 86))
  (segment (start 111.09 156.265816) (end 113.85 153.505816) (width 0.1) (layer "F.Cu") (net 87))
  (segment (start 116.7 133.1) (end 116.949999 133.349999) (width 0.1) (layer "F.Cu") (net 87))
  (segment (start 116 131.35) (end 116.4 131.75) (width 0.15) (layer "F.Cu") (net 87))
  (segment (start 116.949999 133.349999) (end 116.949999 138.561691) (width 0.1) (layer "F.Cu") (net 87))
  (segment (start 113.85 141.66169) (end 113.85 153.505816) (width 0.1) (layer "F.Cu") (net 87))
  (segment (start 111.09 177.135) (end 111.09 156.265816) (width 0.1) (layer "F.Cu") (net 87))
  (segment (start 116.949999 138.561691) (end 113.85 141.66169) (width 0.1) (layer "F.Cu") (net 87))
  (via (at 116.4 131.75) (size 0.5) (drill 0.2) (layers "F.Cu" "B.Cu") (net 87))
  (via (at 116.7 133.1) (size 0.5) (drill 0.2) (layers "F.Cu" "B.Cu") (net 87))
  (segment (start 116.8 132.15) (end 116.4 131.75) (width 0.1) (layer "In5.Cu") (net 87))
  (segment (start 116.7 133.1) (end 116.8 133) (width 0.1) (layer "In5.Cu") (net 87))
  (segment (start 116.8 133) (end 116.8 132.15) (width 0.1) (layer "In5.Cu") (net 87))
  (segment (start 114.1 141.765246) (end 117.15 138.715246) (width 0.1) (layer "F.Cu") (net 88))
  (segment (start 111.69 177.345) (end 111.690001 156.039685) (width 0.1) (layer "F.Cu") (net 88))
  (segment (start 117.15 132.5) (end 116.8 132.15) (width 0.1) (layer "F.Cu") (net 88))
  (segment (start 111.690001 156.039685) (end 114.1 153.629686) (width 0.1) (layer "F.Cu") (net 88))
  (segment (start 117.15 138.715246) (end 117.15 132.5) (width 0.1) (layer "F.Cu") (net 88))
  (segment (start 114.1 153.629686) (end 114.1 141.765246) (width 0.1) (layer "F.Cu") (net 88))
  (segment (start 112.89 176.185) (end 113.18 175.895) (width 0.1) (layer "F.Cu") (net 89))
  (segment (start 112.89 177.345) (end 112.89 176.185) (width 0.1) (layer "F.Cu") (net 89))
  (segment (start 114.35 155.10338) (end 114.35 141.868802) (width 0.1) (layer "F.Cu") (net 89))
  (segment (start 117.82 138.398802) (end 117.82 130.9) (width 0.1) (layer "F.Cu") (net 89))
  (segment (start 112.89 156.56338) (end 114.35 155.10338) (width 0.1) (layer "F.Cu") (net 89))
  (segment (start 112.89 174.89) (end 112.89 156.56338) (width 0.1) (layer "F.Cu") (net 89))
  (segment (start 113.18 175.895) (end 113.18 175.18) (width 0.1) (layer "F.Cu") (net 89))
  (segment (start 113.18 175.18) (end 112.89 174.89) (width 0.1) (layer "F.Cu") (net 89))
  (segment (start 114.35 141.868802) (end 117.82 138.398802) (width 0.1) (layer "F.Cu") (net 89))
  (segment (start 117.47 130.55) (end 116.8 130.55) (width 0.1) (layer "F.Cu") (net 89))
  (segment (start 117.82 130.9) (end 117.47 130.55) (width 0.1) (layer "F.Cu") (net 89))
  (segment (start 118.2 130.35) (end 118.2 138.372358) (width 0.1) (layer "F.Cu") (net 90))
  (segment (start 116.8 129.75) (end 117.6 129.75) (width 0.1) (layer "F.Cu") (net 90))
  (segment (start 114.6 155.699824) (end 113.49 156.809824) (width 0.1) (layer "F.Cu") (net 90))
  (segment (start 113.49 156.809824) (end 113.49 177.345) (width 0.1) (layer "F.Cu") (net 90))
  (segment (start 118.2 138.372358) (end 114.6 141.972358) (width 0.1) (layer "F.Cu") (net 90))
  (segment (start 117.6 129.75) (end 118.2 130.35) (width 0.1) (layer "F.Cu") (net 90))
  (segment (start 114.6 141.972358) (end 114.6 155.699824) (width 0.1) (layer "F.Cu") (net 90))
  (segment (start 69.552 151.833176) (end 69.551472 151.832648) (width 0.15) (layer "F.Cu") (net 91))
  (segment (start 69.572 151.853176) (end 69.551472 151.832648) (width 0.15) (layer "F.Cu") (net 91))
  (segment (start 114.69 177.345) (end 114.69 170.850002) (width 0.15) (layer "F.Cu") (net 91))
  (segment (start 114.69 170.850002) (end 114.689998 170.85) (width 0.15) (layer "F.Cu") (net 91))
  (segment (start 69.572 154.34712) (end 69.572 151.853176) (width 0.15) (layer "F.Cu") (net 91))
  (via (at 69.551472 151.832648) (size 0.5) (drill 0.2) (layers "F.Cu" "B.Cu") (net 91))
  (via (at 114.689998 170.85) (size 0.5) (drill 0.2) (layers "F.Cu" "B.Cu") (net 91))
  (segment (start 71.54 157.92) (end 71.54 161.49) (width 0.15) (layer "In5.Cu") (net 91))
  (segment (start 72.15 157.31) (end 71.54 157.92) (width 0.15) (layer "In5.Cu") (net 91))
  (segment (start 72.15 156.44) (end 72.15 157.31) (width 0.15) (layer "In5.Cu") (net 91))
  (segment (start 71.54 161.49) (end 80.8 170.75) (width 0.15) (layer "In5.Cu") (net 91))
  (segment (start 92.329 173.355) (end 94.086 173.355) (width 0.15) (layer "In5.Cu") (net 91))
  (segment (start 94.086 173.355) (end 96.591 170.85) (width 0.15) (layer "In5.Cu") (net 91))
  (segment (start 80.8 170.75) (end 89.724 170.75) (width 0.15) (layer "In5.Cu") (net 91))
  (segment (start 69.551472 153.841472) (end 72.15 156.44) (width 0.15) (layer "In5.Cu") (net 91))
  (segment (start 69.551472 151.832648) (end 69.551472 153.841472) (width 0.15) (layer "In5.Cu") (net 91))
  (segment (start 96.591 170.85) (end 114.689998 170.85) (width 0.15) (layer "In5.Cu") (net 91))
  (segment (start 89.724 170.75) (end 92.329 173.355) (width 0.15) (layer "In5.Cu") (net 91))
  (segment (start 119.585 177.37) (end 119.585 175.77) (width 0.2) (layer "F.Cu") (net 92))
  (segment (start 116 130.55) (end 116.4 130.95) (width 0.15) (layer "F.Cu") (net 92))
  (via blind (at 119.585 175.77) (size 0.5) (drill 0.2) (layers "F.Cu" "In2.Cu") (net 92))
  (via (at 116.4 130.95) (size 0.5) (drill 0.2) (layers "F.Cu" "B.Cu") (net 92))
  (segment (start 119.585 165.285) (end 117.199945 162.899945) (width 0.15) (layer "In2.Cu") (net 92))
  (segment (start 119.585 175.77) (end 119.585 165.285) (width 0.15) (layer "In2.Cu") (net 92))
  (segment (start 117.199945 162.899945) (end 117.199945 131.749945) (width 0.15) (layer "In2.Cu") (net 92))
  (segment (start 117.199945 131.749945) (end 116.4 130.95) (width 0.15) (layer "In2.Cu") (net 92))
  (segment (start 120.185 177.37) (end 120.185 175.47) (width 0.2) (layer "F.Cu") (net 93))
  (segment (start 116.8 131.35) (end 117.2 130.95) (width 0.15) (layer "F.Cu") (net 93))
  (via blind (at 120.185 175.47) (size 0.5) (drill 0.2) (layers "F.Cu" "In2.Cu") (net 93))
  (via (at 117.2 130.95) (size 0.5) (drill 0.2) (layers "F.Cu" "B.Cu") (net 93))
  (segment (start 120.185 164.835) (end 117.499956 162.149956) (width 0.15) (layer "In2.Cu") (net 93))
  (segment (start 120.185 175.47) (end 120.185 164.835) (width 0.15) (layer "In2.Cu") (net 93))
  (segment (start 117.499956 131.249956) (end 117.2 130.95) (width 0.15) (layer "In2.Cu") (net 93))
  (segment (start 117.499956 162.149956) (end 117.499956 131.249956) (width 0.15) (layer "In2.Cu") (net 93))
  (segment (start 120.785 177.37) (end 120.785 175.77) (width 0.2) (layer "F.Cu") (net 94))
  (segment (start 113.6 128.95) (end 114.2 128.35) (width 0.15) (layer "F.Cu") (net 94))
  (segment (start 114.2 128.35) (end 114.4 128.35) (width 0.15) (layer "F.Cu") (net 94))
  (via blind (at 120.785 175.77) (size 0.5) (drill 0.2) (layers "F.Cu" "In2.Cu") (net 94))
  (via (at 114.4 128.35) (size 0.5) (drill 0.2) (layers "F.Cu" "B.Cu") (net 94))
  (segment (start 120.785 175.77) (end 120.785 164.535) (width 0.15) (layer "In2.Cu") (net 94))
  (segment (start 117.200011 129.500011) (end 115.550011 129.500011) (width 0.15) (layer "In2.Cu") (net 94))
  (segment (start 117.799967 161.549967) (end 117.799967 130.099967) (width 0.15) (layer "In2.Cu") (net 94))
  (segment (start 120.785 164.535) (end 117.799967 161.549967) (width 0.15) (layer "In2.Cu") (net 94))
  (segment (start 117.799967 130.099967) (end 117.200011 129.500011) (width 0.15) (layer "In2.Cu") (net 94))
  (segment (start 115.550011 129.500011) (end 114.4 128.35) (width 0.15) (layer "In2.Cu") (net 94))
  (segment (start 121.385 177.37) (end 121.385 175.47) (width 0.2) (layer "F.Cu") (net 95))
  (segment (start 114.6 128.95) (end 115.2 128.35) (width 0.15) (layer "F.Cu") (net 95))
  (segment (start 114.4 128.95) (end 114.6 128.95) (width 0.15) (layer "F.Cu") (net 95))
  (via blind (at 121.385 175.47) (size 0.5) (drill 0.2) (layers "F.Cu" "In2.Cu") (net 95))
  (via (at 115.2 128.35) (size 0.5) (drill 0.2) (layers "F.Cu" "B.Cu") (net 95))
  (segment (start 117.324279 129.2) (end 116.05 129.2) (width 0.15) (layer "In2.Cu") (net 95))
  (segment (start 121.385 175.47) (end 121.385 157.483557) (width 0.15) (layer "In2.Cu") (net 95))
  (segment (start 116.05 129.2) (end 115.2 128.35) (width 0.15) (layer "In2.Cu") (net 95))
  (segment (start 118.099978 129.975699) (end 117.324279 129.2) (width 0.15) (layer "In2.Cu") (net 95))
  (segment (start 121.385 157.483557) (end 118.099978 154.198536) (width 0.15) (layer "In2.Cu") (net 95))
  (segment (start 118.099978 154.198536) (end 118.099978 129.975699) (width 0.15) (layer "In2.Cu") (net 95))
  (segment (start 121.985 177.37) (end 121.985 175.77) (width 0.2) (layer "F.Cu") (net 96))
  (segment (start 116.044998 128.35) (end 116.1 128.35) (width 0.15) (layer "F.Cu") (net 96))
  (segment (start 115.2 128.95) (end 115.444998 128.95) (width 0.15) (layer "F.Cu") (net 96))
  (segment (start 115.444998 128.95) (end 116.044998 128.35) (width 0.15) (layer "F.Cu") (net 96))
  (via blind (at 121.985 175.77) (size 0.5) (drill 0.2) (layers "F.Cu" "In2.Cu") (net 96))
  (via (at 116.1 128.35) (size 0.5) (drill 0.2) (layers "F.Cu" "B.Cu") (net 96))
  (segment (start 121.985 157.659278) (end 118.399989 154.074268) (width 0.15) (layer "In2.Cu") (net 96))
  (segment (start 118.399989 129.851431) (end 117.448547 128.899989) (width 0.15) (layer "In2.Cu") (net 96))
  (segment (start 118.399989 154.074268) (end 118.399989 129.851431) (width 0.15) (layer "In2.Cu") (net 96))
  (segment (start 121.985 175.77) (end 121.985 157.659278) (width 0.15) (layer "In2.Cu") (net 96))
  (segment (start 117.448547 128.899989) (end 116.649989 128.899989) (width 0.15) (layer "In2.Cu") (net 96))
  (segment (start 116.649989 128.899989) (end 116.1 128.35) (width 0.15) (layer "In2.Cu") (net 96))
  (segment (start 122.585 177.37) (end 122.585 175.47) (width 0.2) (layer "F.Cu") (net 97))
  (segment (start 116.8 128.95) (end 116.8 128.55) (width 0.15) (layer "F.Cu") (net 97))
  (segment (start 116.8 128.55) (end 117 128.35) (width 0.15) (layer "F.Cu") (net 97))
  (via blind (at 122.585 175.47) (size 0.5) (drill 0.2) (layers "F.Cu" "In2.Cu") (net 97))
  (via (at 117 128.35) (size 0.5) (drill 0.2) (layers "F.Cu" "B.Cu") (net 97))
  (segment (start 117.353553 128.35) (end 117 128.35) (width 0.15) (layer "In2.Cu") (net 97))
  (segment (start 118.7 153.95) (end 118.7 129.696447) (width 0.15) (layer "In2.Cu") (net 97))
  (segment (start 122.585 157.835) (end 118.7 153.95) (width 0.15) (layer "In2.Cu") (net 97))
  (segment (start 118.7 129.696447) (end 117.353553 128.35) (width 0.15) (layer "In2.Cu") (net 97))
  (segment (start 122.585 175.47) (end 122.585 157.835) (width 0.15) (layer "In2.Cu") (net 97))
  (segment (start 128.885796 125.365) (end 127.39 125.365) (width 0.16) (layer "F.Cu") (net 98))
  (segment (start 123 149.01158) (end 132.769967 139.241613) (width 0.16) (layer "F.Cu") (net 98))
  (segment (start 135 137.01158) (end 135 131.479204) (width 0.15) (layer "F.Cu") (net 98))
  (segment (start 123.93 176.355) (end 123.93 175.619204) (width 0.16) (layer "F.Cu") (net 98))
  (segment (start 123 174.689204) (end 123 149.01158) (width 0.16) (layer "F.Cu") (net 98))
  (segment (start 132.769967 139.241613) (end 135 137.01158) (width 0.15) (layer "F.Cu") (net 98))
  (segment (start 135 131.479204) (end 128.885796 125.365) (width 0.15) (layer "F.Cu") (net 98))
  (segment (start 123.93 175.619204) (end 123 174.689204) (width 0.16) (layer "F.Cu") (net 98))
  (segment (start 123.785 176.5) (end 123.93 176.355) (width 0.16) (layer "F.Cu") (net 98))
  (segment (start 128.824217 124.865) (end 127.39 124.865) (width 0.16) (layer "F.Cu") (net 99))
  (segment (start 123.310011 174.560794) (end 123.310011 149.139989) (width 0.16) (layer "F.Cu") (net 99))
  (segment (start 124.385 177.37) (end 124.385 175.635783) (width 0.16) (layer "F.Cu") (net 99))
  (segment (start 135.300011 137.14999) (end 135.300011 131.340794) (width 0.15) (layer "F.Cu") (net 99))
  (segment (start 124.385 175.635783) (end 123.310011 174.560794) (width 0.16) (layer "F.Cu") (net 99))
  (segment (start 135.300011 131.340794) (end 128.824217 124.865) (width 0.15) (layer "F.Cu") (net 99))
  (segment (start 133.079978 139.370023) (end 135.300011 137.14999) (width 0.15) (layer "F.Cu") (net 99))
  (segment (start 123.310011 149.139989) (end 133.079978 139.370023) (width 0.16) (layer "F.Cu") (net 99))
  (segment (start 135.7 110.05) (end 134.6 108.95) (width 0.15) (layer "F.Cu") (net 100))
  (segment (start 135.7 110.55) (end 135.7 110.05) (width 0.15) (layer "F.Cu") (net 100))
  (segment (start 123.620022 149.291557) (end 123.620022 173.470022) (width 0.16) (layer "F.Cu") (net 100))
  (segment (start 135.7 137.211579) (end 123.620022 149.291557) (width 0.16) (layer "F.Cu") (net 100))
  (segment (start 125.73 175.58) (end 125.73 176.355) (width 0.16) (layer "F.Cu") (net 100))
  (segment (start 123.735 112.719999) (end 123.64 112.624999) (width 0.16) (layer "F.Cu") (net 100))
  (segment (start 123.64 110.21) (end 123.64 111.164204) (width 0.15) (layer "F.Cu") (net 100))
  (segment (start 135.7 110.55) (end 135.7 137.211579) (width 0.16) (layer "F.Cu") (net 100))
  (segment (start 125.73 176.355) (end 125.585 176.5) (width 0.16) (layer "F.Cu") (net 100))
  (segment (start 123.64 112.624999) (end 123.64 111.164204) (width 0.16) (layer "F.Cu") (net 100))
  (segment (start 123.735 113.365) (end 123.735 112.719999) (width 0.16) (layer "F.Cu") (net 100))
  (segment (start 124.9 108.95) (end 123.64 110.21) (width 0.15) (layer "F.Cu") (net 100))
  (segment (start 134.6 108.95) (end 124.9 108.95) (width 0.15) (layer "F.Cu") (net 100))
  (segment (start 123.620022 173.470022) (end 125.73 175.58) (width 0.16) (layer "F.Cu") (net 100))
  (segment (start 134.724278 108.65) (end 124.775722 108.65) (width 0.15) (layer "F.Cu") (net 101))
  (segment (start 136.00501 109.930732) (end 134.724278 108.65) (width 0.15) (layer "F.Cu") (net 101))
  (segment (start 124.775722 108.65) (end 123.235 110.190722) (width 0.15) (layer "F.Cu") (net 101))
  (segment (start 123.235 113.365) (end 123.235 111.130783) (width 0.16) (layer "F.Cu") (net 101))
  (segment (start 123.235 110.190722) (end 123.235 111.130783) (width 0.15) (layer "F.Cu") (net 101))
  (segment (start 126.185 175.596579) (end 126.185 177.37) (width 0.16) (layer "F.Cu") (net 101))
  (segment (start 133.7 139.650001) (end 136.00501 137.344991) (width 0.15) (layer "F.Cu") (net 101))
  (segment (start 136.00501 137.344991) (end 136.00501 109.930732) (width 0.15) (layer "F.Cu") (net 101))
  (segment (start 123.930033 173.341612) (end 126.185 175.596579) (width 0.16) (layer "F.Cu") (net 101))
  (segment (start 123.930033 149.419967) (end 123.930033 173.341612) (width 0.16) (layer "F.Cu") (net 101))
  (segment (start 133.7 139.650001) (end 123.930033 149.419967) (width 0.16) (layer "F.Cu") (net 101))
  (segment (start 93.585 131.355) (end 93.985 131.755) (width 0.15) (layer "F.Cu") (net 102))
  (via (at 93.985 131.755) (size 0.5) (drill 0.2) (layers "F.Cu" "B.Cu") (net 102))
  (segment (start 82.29 174.74) (end 82.29 171.384279) (width 0.15) (layer "B.Cu") (net 102))
  (segment (start 93.35 132.39) (end 93.985 131.755) (width 0.15) (layer "B.Cu") (net 102))
  (segment (start 82.29 171.384279) (end 89.100044 164.574235) (width 0.15) (layer "B.Cu") (net 102))
  (segment (start 89.100044 139.249956) (end 93.35 135) (width 0.15) (layer "B.Cu") (net 102))
  (segment (start 82.275 176) (end 82.275 177.4) (width 0.15) (layer "B.Cu") (net 102))
  (segment (start 93.35 135) (end 93.35 132.39) (width 0.15) (layer "B.Cu") (net 102))
  (segment (start 82.65 175.1) (end 82.65 175.625) (width 0.15) (layer "B.Cu") (net 102))
  (segment (start 89.100044 164.574235) (end 89.100044 139.249956) (width 0.15) (layer "B.Cu") (net 102))
  (segment (start 82.29 174.74) (end 82.65 175.1) (width 0.15) (layer "B.Cu") (net 102))
  (segment (start 82.65 175.625) (end 82.275 176) (width 0.15) (layer "B.Cu") (net 102))
  (segment (start 102.675 133.225) (end 102.4 132.95) (width 0.127) (layer "F.Cu") (net 103))
  (segment (start 102.675 133.753222) (end 102.675 133.225) (width 0.127) (layer "F.Cu") (net 103))
  (segment (start 100.258222 136.17) (end 102.675 133.753222) (width 0.127) (layer "F.Cu") (net 103))
  (segment (start 96.338891 136.534332) (end 96.703223 136.17) (width 0.127) (layer "F.Cu") (net 103))
  (segment (start 96.703223 136.17) (end 100.258222 136.17) (width 0.127) (layer "F.Cu") (net 103))
  (segment (start 96.084332 136.534332) (end 96.338891 136.534332) (width 0.127) (layer "F.Cu") (net 103))
  (via (at 96.084332 136.534332) (size 0.5) (drill 0.2) (layers "F.Cu" "B.Cu") (net 103))
  (segment (start 94.49 177.145) (end 94.49 175.854999) (width 0.127) (layer "B.Cu") (net 103))
  (segment (start 94.665 175.679999) (end 94.665 173.382222) (width 0.127) (layer "B.Cu") (net 103))
  (segment (start 95.633 137.240223) (end 96.084332 136.788891) (width 0.127) (layer "B.Cu") (net 103))
  (segment (start 94.49 175.854999) (end 94.665 175.679999) (width 0.127) (layer "B.Cu") (net 103))
  (segment (start 94.665 173.382222) (end 95.633 172.414222) (width 0.127) (layer "B.Cu") (net 103))
  (segment (start 96.084332 136.788891) (end 96.084332 136.534332) (width 0.127) (layer "B.Cu") (net 103))
  (segment (start 95.633 172.414222) (end 95.633 137.240223) (width 0.127) (layer "B.Cu") (net 103))
  (segment (start 102.925 133.856778) (end 102.925 133.225) (width 0.127) (layer "F.Cu") (net 104))
  (segment (start 96.515668 136.965668) (end 96.515668 136.711109) (width 0.127) (layer "F.Cu") (net 104))
  (segment (start 100.361778 136.42) (end 102.925 133.856778) (width 0.127) (layer "F.Cu") (net 104))
  (segment (start 102.925 133.225) (end 103.2 132.95) (width 0.127) (layer "F.Cu") (net 104))
  (segment (start 96.515668 136.711109) (end 96.806777 136.42) (width 0.127) (layer "F.Cu") (net 104))
  (segment (start 96.806777 136.42) (end 100.361778 136.42) (width 0.127) (layer "F.Cu") (net 104))
  (via (at 96.515668 136.965668) (size 0.5) (drill 0.2) (layers "F.Cu" "B.Cu") (net 104))
  (segment (start 94.915 175.679999) (end 94.915 173.485778) (width 0.127) (layer "B.Cu") (net 104))
  (segment (start 95.883 172.517778) (end 95.883 137.343777) (width 0.127) (layer "B.Cu") (net 104))
  (segment (start 95.09 177.145) (end 95.09 175.854999) (width 0.127) (layer "B.Cu") (net 104))
  (segment (start 94.915 173.485778) (end 95.883 172.517778) (width 0.127) (layer "B.Cu") (net 104))
  (segment (start 96.261109 136.965668) (end 96.515668 136.965668) (width 0.127) (layer "B.Cu") (net 104))
  (segment (start 95.883 137.343777) (end 96.261109 136.965668) (width 0.127) (layer "B.Cu") (net 104))
  (segment (start 95.09 175.854999) (end 94.915 175.679999) (width 0.127) (layer "B.Cu") (net 104))
  (segment (start 96.71 138.955) (end 97.07 139.315) (width 0.127) (layer "B.Cu") (net 105))
  (segment (start 96.29 177.145) (end 96.29 175.854999) (width 0.127) (layer "B.Cu") (net 105))
  (segment (start 96.465 174.630222) (end 96.776 174.319222) (width 0.127) (layer "B.Cu") (net 105))
  (segment (start 96.465 175.679999) (end 96.465 174.630222) (width 0.127) (layer "B.Cu") (net 105))
  (segment (start 96.29 175.854999) (end 96.465 175.679999) (width 0.127) (layer "B.Cu") (net 105))
  (segment (start 97.07 141.259222) (end 97.07 139.315) (width 0.127) (layer "B.Cu") (net 105))
  (segment (start 96.776 141.553222) (end 97.07 141.259222) (width 0.127) (layer "B.Cu") (net 105))
  (segment (start 96.776 174.319222) (end 96.776 141.553222) (width 0.127) (layer "B.Cu") (net 105))
  (segment (start 97.026 141.656778) (end 97.32 141.362778) (width 0.127) (layer "B.Cu") (net 106))
  (segment (start 96.89 177.145) (end 96.89 175.854999) (width 0.127) (layer "B.Cu") (net 106))
  (segment (start 97.026 174.422778) (end 97.026 141.656778) (width 0.127) (layer "B.Cu") (net 106))
  (segment (start 97.32 141.362778) (end 97.32 139.315) (width 0.127) (layer "B.Cu") (net 106))
  (segment (start 96.715 174.733778) (end 97.026 174.422778) (width 0.127) (layer "B.Cu") (net 106))
  (segment (start 96.715 175.679999) (end 96.715 174.733778) (width 0.127) (layer "B.Cu") (net 106))
  (segment (start 97.68 138.955) (end 97.32 139.315) (width 0.127) (layer "B.Cu") (net 106))
  (segment (start 96.89 175.854999) (end 96.715 175.679999) (width 0.127) (layer "B.Cu") (net 106))
  (segment (start 97.875 133.225) (end 97.875 134.22) (width 0.127) (layer "F.Cu") (net 107))
  (segment (start 97.6 132.95) (end 97.875 133.225) (width 0.127) (layer "F.Cu") (net 107))
  (segment (start 97.875 134.22) (end 97.695 134.4) (width 0.127) (layer "F.Cu") (net 107))
  (via (at 97.695 134.4) (size 0.5) (drill 0.2) (layers "F.Cu" "B.Cu") (net 107))
  (segment (start 98.09 177.145) (end 98.09 175.854999) (width 0.127) (layer "B.Cu") (net 107))
  (segment (start 98.665 139.613222) (end 98.665 135.836778) (width 0.127) (layer "B.Cu") (net 107))
  (segment (start 98.265 140.013222) (end 98.665 139.613222) (width 0.127) (layer "B.Cu") (net 107))
  (segment (start 98.09 175.854999) (end 98.265 175.679999) (width 0.127) (layer "B.Cu") (net 107))
  (segment (start 97.875 135.046778) (end 97.875 134.58) (width 0.127) (layer "B.Cu") (net 107))
  (segment (start 98.665 135.836778) (end 97.875 135.046778) (width 0.127) (layer "B.Cu") (net 107))
  (segment (start 97.875 134.58) (end 97.695 134.4) (width 0.127) (layer "B.Cu") (net 107))
  (segment (start 98.265 175.679999) (end 98.265 140.013222) (width 0.127) (layer "B.Cu") (net 107))
  (segment (start 98.125 134.22) (end 98.305 134.4) (width 0.127) (layer "F.Cu") (net 108))
  (segment (start 98.4 132.95) (end 98.125 133.225) (width 0.127) (layer "F.Cu") (net 108))
  (segment (start 98.125 133.225) (end 98.125 134.22) (width 0.127) (layer "F.Cu") (net 108))
  (via (at 98.305 134.4) (size 0.5) (drill 0.2) (layers "F.Cu" "B.Cu") (net 108))
  (segment (start 98.69 177.145) (end 98.69 175.854999) (width 0.127) (layer "B.Cu") (net 108))
  (segment (start 98.125 134.58) (end 98.305 134.4) (width 0.127) (layer "B.Cu") (net 108))
  (segment (start 98.125 134.943222) (end 98.125 134.58) (width 0.127) (layer "B.Cu") (net 108))
  (segment (start 98.515 175.679999) (end 98.515 140.116778) (width 0.127) (layer "B.Cu") (net 108))
  (segment (start 98.515 140.116778) (end 98.915 139.716778) (width 0.127) (layer "B.Cu") (net 108))
  (segment (start 98.915 139.716778) (end 98.915 135.733222) (width 0.127) (layer "B.Cu") (net 108))
  (segment (start 98.69 175.854999) (end 98.515 175.679999) (width 0.127) (layer "B.Cu") (net 108))
  (segment (start 98.915 135.733222) (end 98.125 134.943222) (width 0.127) (layer "B.Cu") (net 108))
  (segment (start 112.8 124.95) (end 113.2 124.55) (width 0.15) (layer "F.Cu") (net 109))
  (via (at 113.2 124.55) (size 0.5) (drill 0.2) (layers "F.Cu" "B.Cu") (net 109))
  (segment (start 121.2 137.296012) (end 117.95 134.046012) (width 0.1) (layer "B.Cu") (net 109))
  (segment (start 119.605 177.345) (end 119.605 169.845) (width 0.1) (layer "B.Cu") (net 109))
  (segment (start 117.639332 125.25) (end 113.9 125.25) (width 0.1) (layer "B.Cu") (net 109))
  (segment (start 121.2 168.249998) (end 121.2 137.296012) (width 0.1) (layer "B.Cu") (net 109))
  (segment (start 119.605 169.845) (end 121.2 168.249998) (width 0.1) (layer "B.Cu") (net 109))
  (segment (start 117.95 125.560668) (end 117.639332 125.25) (width 0.1) (layer "B.Cu") (net 109))
  (segment (start 113.9 125.25) (end 113.2 124.55) (width 0.1) (layer "B.Cu") (net 109))
  (segment (start 117.95 134.046012) (end 117.95 125.560668) (width 0.1) (layer "B.Cu") (net 109))
  (segment (start 113.6 124.95) (end 114 124.55) (width 0.15) (layer "F.Cu") (net 110))
  (via (at 114 124.55) (size 0.5) (drill 0.2) (layers "F.Cu" "B.Cu") (net 110))
  (segment (start 121.45 137.189737) (end 118.2 133.939737) (width 0.1) (layer "B.Cu") (net 110))
  (segment (start 117.792877 125.049989) (end 114.499989 125.049989) (width 0.1) (layer "B.Cu") (net 110))
  (segment (start 121.45 168.282856) (end 121.45 137.189737) (width 0.1) (layer "B.Cu") (net 110))
  (segment (start 120.19 177.345) (end 120.19 169.542856) (width 0.1) (layer "B.Cu") (net 110))
  (segment (start 118.2 125.457112) (end 117.792877 125.049989) (width 0.1) (layer "B.Cu") (net 110))
  (segment (start 118.2 133.939737) (end 118.2 125.457112) (width 0.1) (layer "B.Cu") (net 110))
  (segment (start 120.19 169.542856) (end 121.45 168.282856) (width 0.1) (layer "B.Cu") (net 110))
  (segment (start 114.499989 125.049989) (end 114 124.55) (width 0.1) (layer "B.Cu") (net 110))
  (segment (start 114.767184 124.582816) (end 114.778122 124.582816) (width 0.15) (layer "F.Cu") (net 111))
  (segment (start 114.4 124.95) (end 114.767184 124.582816) (width 0.15) (layer "F.Cu") (net 111))
  (via (at 114.778122 124.582816) (size 0.5) (drill 0.2) (layers "F.Cu" "B.Cu") (net 111))
  (segment (start 120.79 169.225714) (end 121.7 168.315714) (width 0.1) (layer "B.Cu") (net 111))
  (segment (start 120.79 177.345) (end 120.79 169.225714) (width 0.1) (layer "B.Cu") (net 111))
  (segment (start 118.45 125.353556) (end 117.67926 124.582816) (width 0.1) (layer "B.Cu") (net 111))
  (segment (start 117.67926 124.582816) (end 114.778122 124.582816) (width 0.1) (layer "B.Cu") (net 111))
  (segment (start 121.7 168.315714) (end 121.7 137.0889) (width 0.1) (layer "B.Cu") (net 111))
  (segment (start 118.45 133.8389) (end 118.45 125.353556) (width 0.1) (layer "B.Cu") (net 111))
  (segment (start 121.7 137.0889) (end 118.45 133.8389) (width 0.1) (layer "B.Cu") (net 111))
  (segment (start 112.8 123.35) (end 113.2 123.75) (width 0.15) (layer "F.Cu") (net 112))
  (via (at 113.2 123.75) (size 0.5) (drill 0.2) (layers "F.Cu" "B.Cu") (net 112))
  (segment (start 113.6 124.15) (end 117.6 124.15) (width 0.1) (layer "B.Cu") (net 112))
  (segment (start 121.95 136.985344) (end 121.95 175.625) (width 0.1) (layer "B.Cu") (net 112))
  (segment (start 118.7 133.735344) (end 121.95 136.985344) (width 0.1) (layer "B.Cu") (net 112))
  (segment (start 118.7 125.25) (end 118.7 133.735344) (width 0.1) (layer "B.Cu") (net 112))
  (segment (start 117.6 124.15) (end 118.7 125.25) (width 0.1) (layer "B.Cu") (net 112))
  (segment (start 121.39 176.185) (end 121.39 177.345) (width 0.1) (layer "B.Cu") (net 112))
  (segment (start 113.2 123.75) (end 113.6 124.15) (width 0.1) (layer "B.Cu") (net 112))
  (segment (start 121.95 175.625) (end 121.39 176.185) (width 0.1) (layer "B.Cu") (net 112))
  (segment (start 112 120.95) (end 112.4 121.35) (width 0.15) (layer "F.Cu") (net 113))
  (via (at 112.4 121.35) (size 0.5) (drill 0.2) (layers "F.Cu" "B.Cu") (net 113))
  (segment (start 112.999992 121.949992) (end 112.999992 122.307706) (width 0.1) (layer "B.Cu") (net 113))
  (segment (start 114.542286 123.85) (end 117.653556 123.85) (width 0.1) (layer "B.Cu") (net 113))
  (segment (start 122.2 136.881788) (end 122.2 175.975) (width 0.1) (layer "B.Cu") (net 113))
  (segment (start 117.653556 123.85) (end 118.95 125.146444) (width 0.1) (layer "B.Cu") (net 113))
  (segment (start 118.95 133.631788) (end 122.2 136.881788) (width 0.1) (layer "B.Cu") (net 113))
  (segment (start 112.999992 122.307706) (end 114.542286 123.85) (width 0.1) (layer "B.Cu") (net 113))
  (segment (start 122.2 175.975) (end 121.99 176.185) (width 0.1) (layer "B.Cu") (net 113))
  (segment (start 118.95 125.146444) (end 118.95 133.631788) (width 0.1) (layer "B.Cu") (net 113))
  (segment (start 121.99 176.185) (end 121.99 177.345) (width 0.1) (layer "B.Cu") (net 113))
  (segment (start 112.4 121.35) (end 112.999992 121.949992) (width 0.1) (layer "B.Cu") (net 113))
  (segment (start 112.8 120.95) (end 113.2 121.35) (width 0.15) (layer "F.Cu") (net 114))
  (via (at 113.2 121.35) (size 0.5) (drill 0.2) (layers "F.Cu" "B.Cu") (net 114))
  (segment (start 114.625142 123.65) (end 116.7 123.65) (width 0.1) (layer "B.Cu") (net 114))
  (segment (start 122.45 136.778232) (end 119.2 133.528232) (width 0.1) (layer "B.Cu") (net 114))
  (segment (start 117.807102 123.64999) (end 116.7 123.64999) (width 0.1) (layer "B.Cu") (net 114))
  (segment (start 113.2 121.35) (end 113.2 122.224858) (width 0.1) (layer "B.Cu") (net 114))
  (segment (start 122.59 169.14) (end 122.45 169) (width 0.1) (layer "B.Cu") (net 114))
  (segment (start 113.2 122.224858) (end 114.625142 123.65) (width 0.1) (layer "B.Cu") (net 114))
  (segment (start 119.2 125.042888) (end 117.807102 123.64999) (width 0.1) (layer "B.Cu") (net 114))
  (segment (start 119.2 133.528232) (end 119.2 125.042888) (width 0.1) (layer "B.Cu") (net 114))
  (segment (start 122.45 169) (end 122.45 136.778232) (width 0.1) (layer "B.Cu") (net 114))
  (segment (start 122.59 177.345) (end 122.59 169.14) (width 0.1) (layer "B.Cu") (net 114))
  (segment (start 112.8 120.15) (end 113.2 120.55) (width 0.15) (layer "F.Cu") (net 115))
  (via (at 113.2 120.55) (size 0.5) (drill 0.2) (layers "F.Cu" "B.Cu") (net 115))
  (segment (start 114.607998 123.35) (end 117.860668 123.35) (width 0.1) (layer "B.Cu") (net 115))
  (segment (start 119.45 124.939332) (end 119.45 133.424676) (width 0.1) (layer "B.Cu") (net 115))
  (segment (start 122.7 136.674676) (end 122.7 168.95) (width 0.1) (layer "B.Cu") (net 115))
  (segment (start 123.19 169.44) (end 123.19 177.345) (width 0.1) (layer "B.Cu") (net 115))
  (segment (start 113.599999 122.342001) (end 114.607998 123.35) (width 0.1) (layer "B.Cu") (net 115))
  (segment (start 113.6 120.95) (end 113.599999 122.342001) (width 0.1) (layer "B.Cu") (net 115))
  (segment (start 117.860668 123.35) (end 119.45 124.939332) (width 0.1) (layer "B.Cu") (net 115))
  (segment (start 113.2 120.55) (end 113.6 120.95) (width 0.1) (layer "B.Cu") (net 115))
  (segment (start 122.7 168.95) (end 123.19 169.44) (width 0.1) (layer "B.Cu") (net 115))
  (segment (start 119.45 133.424676) (end 122.7 136.674676) (width 0.1) (layer "B.Cu") (net 115))
  (segment (start 115.2 122.55) (end 115.6 122.15) (width 0.15) (layer "F.Cu") (net 116))
  (via (at 115.6 122.15) (size 0.5) (drill 0.2) (layers "F.Cu" "B.Cu") (net 116))
  (segment (start 119.7 122.537662) (end 119.7 133.32112) (width 0.1) (layer "B.Cu") (net 116))
  (segment (start 123.79 169.64) (end 123.79 177.345) (width 0.1) (layer "B.Cu") (net 116))
  (segment (start 122.95 136.57112) (end 122.95 168.8) (width 0.1) (layer "B.Cu") (net 116))
  (segment (start 118.712338 121.55) (end 119.7 122.537662) (width 0.1) (layer "B.Cu") (net 116))
  (segment (start 119.7 133.32112) (end 122.95 136.57112) (width 0.1) (layer "B.Cu") (net 116))
  (segment (start 122.95 168.8) (end 123.79 169.64) (width 0.1) (layer "B.Cu") (net 116))
  (segment (start 115.6 122.15) (end 116.2 121.55) (width 0.1) (layer "B.Cu") (net 116))
  (segment (start 116.2 121.55) (end 118.712338 121.55) (width 0.1) (layer "B.Cu") (net 116))
  (segment (start 114.4 121.75) (end 114.8 122.15) (width 0.15) (layer "F.Cu") (net 117))
  (via (at 114.8 122.15) (size 0.5) (drill 0.2) (layers "F.Cu" "B.Cu") (net 117))
  (segment (start 118.865894 121.35) (end 115.6 121.35) (width 0.1) (layer "B.Cu") (net 117))
  (segment (start 119.95 133.164524) (end 119.95 122.434106) (width 0.1) (layer "B.Cu") (net 117))
  (segment (start 123.2 168.6) (end 123.2 136.414524) (width 0.1) (layer "B.Cu") (net 117))
  (segment (start 123.2 136.414524) (end 119.95 133.164524) (width 0.1) (layer "B.Cu") (net 117))
  (segment (start 124.39 169.79) (end 123.2 168.6) (width 0.1) (layer "B.Cu") (net 117))
  (segment (start 119.95 122.434106) (end 118.865894 121.35) (width 0.1) (layer "B.Cu") (net 117))
  (segment (start 115.6 121.35) (end 114.8 122.15) (width 0.1) (layer "B.Cu") (net 117))
  (segment (start 124.39 177.345) (end 124.39 169.79) (width 0.1) (layer "B.Cu") (net 117))
  (segment (start 114.4 120.95) (end 114.8 121.35) (width 0.15) (layer "F.Cu") (net 118))
  (via (at 114.8 121.35) (size 0.5) (drill 0.2) (layers "F.Cu" "B.Cu") (net 118))
  (segment (start 115.317142 121.35) (end 114.8 121.35) (width 0.1) (layer "B.Cu") (net 118))
  (segment (start 115.517152 121.14999) (end 115.317142 121.35) (width 0.1) (layer "B.Cu") (net 118))
  (segment (start 123.45 168.45) (end 123.45 136.364008) (width 0.1) (layer "B.Cu") (net 118))
  (segment (start 119.01944 121.14999) (end 115.517152 121.14999) (width 0.1) (layer "B.Cu") (net 118))
  (segment (start 124.99 169.99) (end 123.45 168.45) (width 0.1) (layer "B.Cu") (net 118))
  (segment (start 123.45 136.364008) (end 120.2 133.114008) (width 0.1) (layer "B.Cu") (net 118))
  (segment (start 124.99 177.345) (end 124.99 169.99) (width 0.1) (layer "B.Cu") (net 118))
  (segment (start 120.2 122.33055) (end 119.01944 121.14999) (width 0.1) (layer "B.Cu") (net 118))
  (segment (start 120.2 133.114008) (end 120.2 122.33055) (width 0.1) (layer "B.Cu") (net 118))
  (segment (start 113.6 120.95) (end 114 121.35) (width 0.15) (layer "F.Cu") (net 119))
  (via (at 114 121.35) (size 0.5) (drill 0.2) (layers "F.Cu" "B.Cu") (net 119))
  (segment (start 115.434284 120.95) (end 115.434306 120.94998) (width 0.1) (layer "B.Cu") (net 119))
  (segment (start 125.59 170.19) (end 125.59 177.345) (width 0.1) (layer "B.Cu") (net 119))
  (segment (start 114.4 120.95) (end 115.434284 120.95) (width 0.1) (layer "B.Cu") (net 119))
  (segment (start 120.45 122.226994) (end 120.45 133.010452) (width 0.1) (layer "B.Cu") (net 119))
  (segment (start 123.7 168.3) (end 125.59 170.19) (width 0.1) (layer "B.Cu") (net 119))
  (segment (start 120.45 133.010452) (end 123.7 136.260452) (width 0.1) (layer "B.Cu") (net 119))
  (segment (start 123.7 136.260452) (end 123.7 168.3) (width 0.1) (layer "B.Cu") (net 119))
  (segment (start 114 121.35) (end 114.4 120.95) (width 0.1) (layer "B.Cu") (net 119))
  (segment (start 115.434306 120.94998) (end 119.172986 120.94998) (width 0.1) (layer "B.Cu") (net 119))
  (segment (start 119.172986 120.94998) (end 120.45 122.226994) (width 0.1) (layer "B.Cu") (net 119))
  (segment (start 114.4 120.15) (end 114.8 120.55) (width 0.15) (layer "F.Cu") (net 120))
  (via (at 114.8 120.55) (size 0.5) (drill 0.2) (layers "F.Cu" "B.Cu") (net 120))
  (segment (start 126.19 170.34) (end 126.19 177.345) (width 0.1) (layer "B.Cu") (net 120))
  (segment (start 120.7 122.123438) (end 120.7 132.906896) (width 0.1) (layer "B.Cu") (net 120))
  (segment (start 114.999969 120.749969) (end 119.326531 120.749969) (width 0.1) (layer "B.Cu") (net 120))
  (segment (start 120.7 132.906896) (end 123.95 136.156896) (width 0.1) (layer "B.Cu") (net 120))
  (segment (start 123.95 136.156896) (end 123.95 168.1) (width 0.1) (layer "B.Cu") (net 120))
  (segment (start 119.326531 120.749969) (end 120.7 122.123438) (width 0.1) (layer "B.Cu") (net 120))
  (segment (start 114.8 120.55) (end 114.999969 120.749969) (width 0.1) (layer "B.Cu") (net 120))
  (segment (start 123.95 168.1) (end 126.19 170.34) (width 0.1) (layer "B.Cu") (net 120))
  (segment (start 113.6 120.15) (end 114 120.55) (width 0.15) (layer "F.Cu") (net 121))
  (via (at 114 120.55) (size 0.5) (drill 0.2) (layers "F.Cu" "B.Cu") (net 121))
  (segment (start 120.95 132.80334) (end 124.2 136.05334) (width 0.1) (layer "B.Cu") (net 121))
  (segment (start 124.2 136.05334) (end 124.2 167.9) (width 0.1) (layer "B.Cu") (net 121))
  (segment (start 114 120.55) (end 114.400001 120.149999) (width 0.1) (layer "B.Cu") (net 121))
  (segment (start 126.79 170.49) (end 126.79 177.345) (width 0.1) (layer "B.Cu") (net 121))
  (segment (start 120.95 122.019882) (end 120.95 132.80334) (width 0.1) (layer "B.Cu") (net 121))
  (segment (start 115.208571 120.15) (end 115.60854 120.549969) (width 0.1) (layer "B.Cu") (net 121))
  (segment (start 119.480087 120.549969) (end 120.95 122.019882) (width 0.1) (layer "B.Cu") (net 121))
  (segment (start 124.2 167.9) (end 126.79 170.49) (width 0.1) (layer "B.Cu") (net 121))
  (segment (start 114.4 120.15) (end 115.208571 120.15) (width 0.1) (layer "B.Cu") (net 121))
  (segment (start 115.60854 120.549969) (end 119.480087 120.549969) (width 0.1) (layer "B.Cu") (net 121))
  (segment (start 114.4 119.35) (end 114 119.75) (width 0.15) (layer "F.Cu") (net 122))
  (via (at 114 119.75) (size 0.5) (drill 0.2) (layers "F.Cu" "B.Cu") (net 122))
  (segment (start 121.2 132.699784) (end 121.2 121.916326) (width 0.1) (layer "B.Cu") (net 122))
  (segment (start 124.45 167.75) (end 124.45 135.949784) (width 0.1) (layer "B.Cu") (net 122))
  (segment (start 115.799949 120.34995) (end 115.199999 119.75) (width 0.1) (layer "B.Cu") (net 122))
  (segment (start 115.199999 119.75) (end 114 119.75) (width 0.1) (layer "B.Cu") (net 122))
  (segment (start 127.39 177.345) (end 127.39 170.69) (width 0.1) (layer "B.Cu") (net 122))
  (segment (start 121.2 121.916326) (end 119.633624 120.34995) (width 0.1) (layer "B.Cu") (net 122))
  (segment (start 119.633624 120.34995) (end 115.799949 120.34995) (width 0.1) (layer "B.Cu") (net 122))
  (segment (start 124.45 135.949784) (end 121.2 132.699784) (width 0.1) (layer "B.Cu") (net 122))
  (segment (start 127.39 170.69) (end 124.45 167.75) (width 0.1) (layer "B.Cu") (net 122))
  (segment (start 112.8 119.35) (end 113.2 118.95) (width 0.15) (layer "F.Cu") (net 123))
  (via (at 113.2 118.95) (size 0.5) (drill 0.2) (layers "F.Cu" "B.Cu") (net 123))
  (segment (start 113.2 118.95) (end 118.608782 118.95) (width 0.1) (layer "B.Cu") (net 123))
  (segment (start 127.99 168.64) (end 127.99 177.345) (width 0.1) (layer "B.Cu") (net 123))
  (segment (start 118.608782 118.95) (end 121.45 121.791218) (width 0.1) (layer "B.Cu") (net 123))
  (segment (start 121.45 121.791218) (end 121.45 132.596228) (width 0.1) (layer "B.Cu") (net 123))
  (segment (start 121.45 132.596228) (end 124.7 135.846228) (width 0.1) (layer "B.Cu") (net 123))
  (segment (start 124.7 135.846228) (end 124.7 165.35) (width 0.1) (layer "B.Cu") (net 123))
  (segment (start 124.7 165.35) (end 127.99 168.64) (width 0.1) (layer "B.Cu") (net 123))
  (segment (start 80.974104 146.305696) (end 80.974104 144.055696) (width 0.25) (layer "F.Cu") (net 124))
  (segment (start 81.3791 143.6507) (end 83.139 143.6507) (width 0.25) (layer "F.Cu") (net 124))
  (segment (start 80.974104 144.055696) (end 81.3791 143.6507) (width 0.25) (layer "F.Cu") (net 124))
  (segment (start 81.3791 134.7507) (end 80.97701 135.15279) (width 0.25) (layer "F.Cu") (net 124))
  (segment (start 80.97701 135.15279) (end 80.97701 137.405696) (width 0.25) (layer "F.Cu") (net 124))
  (segment (start 83.139 134.7507) (end 81.3791 134.7507) (width 0.25) (layer "F.Cu") (net 124))
  (segment (start 77.572 154.34712) (end 77.572 151.853176) (width 0.15) (layer "F.Cu") (net 124))
  (segment (start 80.97701 137.405696) (end 80.97701 141.62701) (width 0.2) (layer "F.Cu") (net 124))
  (segment (start 80.97701 141.62701) (end 81 141.65) (width 0.2) (layer "F.Cu") (net 124))
  (via (at 80.974104 146.305696) (size 0.5) (drill 0.2) (layers "F.Cu" "B.Cu") (net 124))
  (via (at 77.552 151.83212) (size 0.5) (drill 0.2) (layers "F.Cu" "B.Cu") (net 124))
  (via (at 80.97701 137.405696) (size 0.5) (drill 0.2) (layers "F.Cu" "B.Cu") (net 124))
  (via (at 81 141.65) (size 0.5) (drill 0.2) (layers "F.Cu" "B.Cu") (net 124))
  (via (at 80.974104 144.055696) (size 0.5) (drill 0.2) (layers "F.Cu" "B.Cu") (net 124))
  (segment (start 77.552 149.998) (end 80.974104 146.575896) (width 0.15) (layer "In5.Cu") (net 124))
  (segment (start 77.552 151.83212) (end 77.552 149.998) (width 0.15) (layer "In5.Cu") (net 124))
  (segment (start 80.974104 146.575896) (end 80.974104 146.305696) (width 0.15) (layer "In5.Cu") (net 124))
  (segment (start 80.9741 146.3057) (end 80.9741 147.3207) (width 0.25) (layer "B.Cu") (net 124))
  (segment (start 80.9741 137.4057) (end 80.9741 138.4207) (width 0.25) (layer "B.Cu") (net 124))
  (segment (start 81 141.65) (end 80.974104 141.675896) (width 0.2) (layer "B.Cu") (net 124))
  (segment (start 80.974104 141.675896) (end 80.974104 144.055696) (width 0.2) (layer "B.Cu") (net 124))
  (segment (start 82.127 136.0207) (end 83.139 136.0207) (width 0.25) (layer "F.Cu") (net 125))
  (segment (start 81.974112 136.173588) (end 82.127 136.0207) (width 0.25) (layer "F.Cu") (net 125))
  (segment (start 81.974112 137.405688) (end 81.974112 136.173588) (width 0.25) (layer "F.Cu") (net 125))
  (segment (start 75.072 154.34712) (end 75.072 152.25212) (width 0.15) (layer "F.Cu") (net 125))
  (via (at 75.052 152.23212) (size 0.5) (drill 0.2) (layers "F.Cu" "B.Cu") (net 125))
  (via (at 81.974112 137.405688) (size 0.5) (drill 0.2) (layers "F.Cu" "B.Cu") (net 125))
  (segment (start 75.052 152.23212) (end 75.052 144.3278) (width 0.15) (layer "In5.Cu") (net 125))
  (segment (start 75.052 144.3278) (end 81.974112 137.405688) (width 0.15) (layer "In5.Cu") (net 125))
  (segment (start 81.9741 137.4057) (end 81.9741 138.4207) (width 0.25) (layer "B.Cu") (net 125))
  (segment (start 77.97412 137.40568) (end 77.97412 134.59362) (width 0.25) (layer "F.Cu") (net 126))
  (segment (start 77.97412 134.59362) (end 76.8612 133.4807) (width 0.25) (layer "F.Cu") (net 126))
  (segment (start 76.8612 133.4807) (end 75.8492 133.4807) (width 0.25) (layer "F.Cu") (net 126))
  (segment (start 73.572 154.32212) (end 73.572 151.828176) (width 0.15) (layer "F.Cu") (net 126))
  (via (at 73.552 151.83212) (size 0.5) (drill 0.2) (layers "F.Cu" "B.Cu") (net 126))
  (via (at 77.97412 137.40568) (size 0.5) (drill 0.2) (layers "F.Cu" "B.Cu") (net 126))
  (segment (start 73.552 151.83212) (end 73.552 141.8278) (width 0.15) (layer "In5.Cu") (net 126))
  (segment (start 73.552 141.8278) (end 77.97412 137.40568) (width 0.15) (layer "In5.Cu") (net 126))
  (segment (start 77.9741 137.4057) (end 77.9741 138.4207) (width 0.25) (layer "B.Cu") (net 126))
  (segment (start 76.974106 134.863606) (end 76.8612 134.7507) (width 0.25) (layer "F.Cu") (net 127))
  (segment (start 76.974106 137.405694) (end 76.974106 134.863606) (width 0.25) (layer "F.Cu") (net 127))
  (segment (start 76.8612 134.7507) (end 75.8492 134.7507) (width 0.25) (layer "F.Cu") (net 127))
  (segment (start 73.072 154.32212) (end 73.072 152.22712) (width 0.15) (layer "F.Cu") (net 127))
  (via (at 73.052 152.23212) (size 0.5) (drill 0.2) (layers "F.Cu" "B.Cu") (net 127))
  (via (at 76.974106 137.405694) (size 0.5) (drill 0.2) (layers "F.Cu" "B.Cu") (net 127))
  (segment (start 73.1 141.2798) (end 76.974106 137.405694) (width 0.15) (layer "In5.Cu") (net 127))
  (segment (start 73.052 141.3278) (end 73.1 141.2798) (width 0.15) (layer "In5.Cu") (net 127))
  (segment (start 73.052 152.23212) (end 73.052 141.3278) (width 0.15) (layer "In5.Cu") (net 127))
  (segment (start 76.9741 137.4057) (end 76.9741 138.4207) (width 0.25) (layer "B.Cu") (net 127))
  (segment (start 79.974102 137.405702) (end 79.974102 134.405698) (width 0.25) (layer "F.Cu") (net 128))
  (segment (start 79.974102 134.405698) (end 80.8991 133.4807) (width 0.25) (layer "F.Cu") (net 128))
  (segment (start 80.8991 133.4807) (end 83.139 133.4807) (width 0.25) (layer "F.Cu") (net 128))
  (segment (start 74.572 154.32212) (end 74.572 151.82712) (width 0.15) (layer "F.Cu") (net 128))
  (via (at 74.552 151.83212) (size 0.5) (drill 0.2) (layers "F.Cu" "B.Cu") (net 128))
  (via (at 79.974102 137.405702) (size 0.5) (drill 0.2) (layers "F.Cu" "B.Cu") (net 128))
  (segment (start 74.552 142.827804) (end 79.974102 137.405702) (width 0.15) (layer "In5.Cu") (net 128))
  (segment (start 74.552 151.83212) (end 74.552 142.827804) (width 0.15) (layer "In5.Cu") (net 128))
  (segment (start 79.9741 137.4057) (end 79.9741 138.4207) (width 0.25) (layer "B.Cu") (net 128))
  (segment (start 78.974094 137.405694) (end 78.974094 134.323594) (width 0.25) (layer "F.Cu") (net 129))
  (segment (start 78.974094 134.323594) (end 76.8612 132.2107) (width 0.25) (layer "F.Cu") (net 129))
  (segment (start 74.072 154.32212) (end 74.072 152.22712) (width 0.15) (layer "F.Cu") (net 129))
  (segment (start 76.8612 132.2107) (end 75.8107 132.2107) (width 0.25) (layer "F.Cu") (net 129))
  (via (at 74.052 152.23212) (size 0.5) (drill 0.2) (layers "F.Cu" "B.Cu") (net 129))
  (via (at 78.974094 137.405694) (size 0.5) (drill 0.2) (layers "F.Cu" "B.Cu") (net 129))
  (segment (start 74.052 142.327788) (end 78.974094 137.405694) (width 0.15) (layer "In5.Cu") (net 129))
  (segment (start 74.052 152.23212) (end 74.052 142.327788) (width 0.15) (layer "In5.Cu") (net 129))
  (segment (start 78.9741 137.4057) (end 78.9741 138.4207) (width 0.25) (layer "B.Cu") (net 129))
  (segment (start 82.127 144.9207) (end 83.139 144.9207) (width 0.25) (layer "F.Cu") (net 130))
  (segment (start 81.974112 145.073588) (end 82.127 144.9207) (width 0.25) (layer "F.Cu") (net 130))
  (segment (start 81.974112 146.305688) (end 81.974112 145.073588) (width 0.25) (layer "F.Cu") (net 130))
  (segment (start 78.072 154.34712) (end 78.075 152.975) (width 0.15) (layer "F.Cu") (net 130))
  (via (at 81.974112 146.305688) (size 0.5) (drill 0.2) (layers "F.Cu" "B.Cu") (net 130))
  (via (at 78.075 152.975) (size 0.5) (drill 0.2) (layers "F.Cu" "B.Cu") (net 130))
  (segment (start 78.025 152.925) (end 78.025 150.2548) (width 0.15) (layer "In5.Cu") (net 130))
  (segment (start 78.025 150.2548) (end 81.974112 146.305688) (width 0.15) (layer "In5.Cu") (net 130))
  (segment (start 78.075 152.975) (end 78.025 152.925) (width 0.15) (layer "In5.Cu") (net 130))
  (segment (start 81.9741 146.3057) (end 81.9741 147.3207) (width 0.25) (layer "B.Cu") (net 130))
  (segment (start 77.97412 146.30568) (end 77.97412 143.49362) (width 0.25) (layer "F.Cu") (net 131))
  (segment (start 77.97412 143.49362) (end 76.8612 142.3807) (width 0.25) (layer "F.Cu") (net 131))
  (segment (start 76.8612 142.3807) (end 75.8492 142.3807) (width 0.25) (layer "F.Cu") (net 131))
  (segment (start 76.072 154.34712) (end 76.072 152.25212) (width 0.15) (layer "F.Cu") (net 131))
  (via (at 77.97412 146.30568) (size 0.5) (drill 0.2) (layers "F.Cu" "B.Cu") (net 131))
  (via (at 76.052 152.23212) (size 0.5) (drill 0.2) (layers "F.Cu" "B.Cu") (net 131))
  (segment (start 76.052 148.2278) (end 77.97412 146.30568) (width 0.15) (layer "In5.Cu") (net 131))
  (segment (start 76.052 152.23212) (end 76.052 148.2278) (width 0.15) (layer "In5.Cu") (net 131))
  (segment (start 77.9741 146.3057) (end 77.9741 147.3207) (width 0.25) (layer "B.Cu") (net 131))
  (segment (start 76.974106 143.763606) (end 76.8612 143.6507) (width 0.25) (layer "F.Cu") (net 132))
  (segment (start 76.974106 146.305694) (end 76.974106 143.763606) (width 0.25) (layer "F.Cu") (net 132))
  (segment (start 76.8612 143.6507) (end 75.8492 143.6507) (width 0.25) (layer "F.Cu") (net 132))
  (segment (start 75.572 154.34712) (end 75.572 151.853176) (width 0.15) (layer "F.Cu") (net 132))
  (via (at 76.974106 146.305694) (size 0.5) (drill 0.2) (layers "F.Cu" "B.Cu") (net 132))
  (via (at 75.552 151.83212) (size 0.5) (drill 0.2) (layers "F.Cu" "B.Cu") (net 132))
  (segment (start 75.552 147.7278) (end 76.974106 146.305694) (width 0.15) (layer "In5.Cu") (net 132))
  (segment (start 75.552 151.83212) (end 75.552 147.7278) (width 0.15) (layer "In5.Cu") (net 132))
  (segment (start 76.9741 146.3057) (end 76.9741 147.3207) (width 0.25) (layer "B.Cu") (net 132))
  (segment (start 79.974102 146.305702) (end 79.974102 143.305698) (width 0.25) (layer "F.Cu") (net 133))
  (segment (start 79.974102 143.305698) (end 80.8991 142.3807) (width 0.25) (layer "F.Cu") (net 133))
  (segment (start 80.8991 142.3807) (end 83.139 142.3807) (width 0.25) (layer "F.Cu") (net 133))
  (segment (start 77.072 154.34712) (end 77.072 152.25212) (width 0.15) (layer "F.Cu") (net 133))
  (via (at 79.974102 146.305702) (size 0.5) (drill 0.2) (layers "F.Cu" "B.Cu") (net 133))
  (via (at 77.052 152.23212) (size 0.5) (drill 0.2) (layers "F.Cu" "B.Cu") (net 133))
  (segment (start 79.974102 146.305702) (end 79.944192 146.305702) (width 0.15) (layer "In5.Cu") (net 133))
  (segment (start 77.052 149.098) (end 79.844298 146.305702) (width 0.15) (layer "In5.Cu") (net 133))
  (segment (start 79.844298 146.305702) (end 79.974102 146.305702) (width 0.15) (layer "In5.Cu") (net 133))
  (segment (start 77.052 152.23212) (end 77.052 149.098) (width 0.15) (layer "In5.Cu") (net 133))
  (segment (start 79.9741 146.3057) (end 79.9741 147.3207) (width 0.25) (layer "B.Cu") (net 133))
  (segment (start 75.8392 141.1107) (end 76.8512 141.1107) (width 0.25) (layer "F.Cu") (net 134))
  (segment (start 76.8612 141.1107) (end 75.8492 141.1107) (width 0.25) (layer "F.Cu") (net 134))
  (segment (start 78.974094 146.305694) (end 78.974094 143.223594) (width 0.25) (layer "F.Cu") (net 134))
  (segment (start 78.974094 143.223594) (end 76.8612 141.1107) (width 0.25) (layer "F.Cu") (net 134))
  (segment (start 76.572 154.34712) (end 76.572 151.85212) (width 0.15) (layer "F.Cu") (net 134))
  (via (at 78.974094 146.305694) (size 0.5) (drill 0.2) (layers "F.Cu" "B.Cu") (net 134))
  (via (at 76.552 151.83212) (size 0.5) (drill 0.2) (layers "F.Cu" "B.Cu") (net 134))
  (segment (start 76.552 148.727788) (end 78.974094 146.305694) (width 0.15) (layer "In5.Cu") (net 134))
  (segment (start 76.552 151.83212) (end 76.552 148.727788) (width 0.15) (layer "In5.Cu") (net 134))
  (segment (start 78.9741 146.3057) (end 78.9741 147.3207) (width 0.25) (layer "B.Cu") (net 134))
  (segment (start 69.724104 137.405696) (end 69.724104 135.155696) (width 0.25) (layer "F.Cu") (net 135))
  (segment (start 70.1291 134.7507) (end 71.889 134.7507) (width 0.25) (layer "F.Cu") (net 135))
  (segment (start 69.724104 135.155696) (end 70.1291 134.7507) (width 0.25) (layer "F.Cu") (net 135))
  (segment (start 69.76789 144.73211) (end 69.76789 146.294592) (width 0.25) (layer "F.Cu") (net 135))
  (segment (start 70.5 143.29) (end 70.5 143) (width 0.2) (layer "F.Cu") (net 135))
  (segment (start 71.8899 143.645) (end 70.855 143.645) (width 0.25) (layer "F.Cu") (net 135))
  (segment (start 70.855 143.645) (end 69.76789 144.73211) (width 0.25) (layer "F.Cu") (net 135))
  (segment (start 70.855 143.645) (end 70.5 143.29) (width 0.2) (layer "F.Cu") (net 135))
  (segment (start 72.072 154.34712) (end 72.072 152.25212) (width 0.15) (layer "F.Cu") (net 135))
  (via (at 69.724104 137.405696) (size 0.5) (drill 0.2) (layers "F.Cu" "B.Cu") (net 135))
  (via (at 72.052 152.23212) (size 0.5) (drill 0.2) (layers "F.Cu" "B.Cu") (net 135))
  (via (at 69.76789 146.294592) (size 0.5) (drill 0.2) (layers "F.Cu" "B.Cu") (net 135))
  (via (at 70.5 143) (size 0.5) (drill 0.2) (layers "F.Cu" "B.Cu") (net 135))
  (segment (start 72.4 144.9) (end 69.45 141.95) (width 0.15) (layer "In5.Cu") (net 135))
  (segment (start 72.052 152.23212) (end 72.052 148.098) (width 0.15) (layer "In5.Cu") (net 135))
  (segment (start 69.45 140.55) (end 69.724104 140.275896) (width 0.15) (layer "In5.Cu") (net 135))
  (segment (start 72.052 148.098) (end 72.4 147.75) (width 0.15) (layer "In5.Cu") (net 135))
  (segment (start 69.724104 140.275896) (end 69.724104 137.405696) (width 0.15) (layer "In5.Cu") (net 135))
  (segment (start 72.4 147.75) (end 72.4 144.9) (width 0.15) (layer "In5.Cu") (net 135))
  (segment (start 69.45 141.95) (end 69.45 140.55) (width 0.15) (layer "In5.Cu") (net 135))
  (segment (start 69.7241 137.4057) (end 69.7241 138.4207) (width 0.25) (layer "B.Cu") (net 135))
  (segment (start 69.725 146.3) (end 69.725 147.315) (width 0.25) (layer "B.Cu") (net 135))
  (segment (start 70.725012 146.299988) (end 70.725012 145.067888) (width 0.25) (layer "F.Cu") (net 136))
  (segment (start 70.725012 145.067888) (end 70.8779 144.915) (width 0.25) (layer "F.Cu") (net 136))
  (segment (start 70.8779 144.915) (end 71.8899 144.915) (width 0.25) (layer "F.Cu") (net 136))
  (segment (start 71.577 158.00622) (end 71.577 156.60712) (width 0.15) (layer "F.Cu") (net 136))
  (via (at 70.725012 146.299988) (size 0.5) (drill 0.2) (layers "F.Cu" "B.Cu") (net 136))
  (via (at 71.577 156.60712) (size 0.5) (drill 0.2) (layers "F.Cu" "B.Cu") (net 136))
  (segment (start 71.577 156.60712) (end 71.577 156.320283) (width 0.15) (layer "In5.Cu") (net 136))
  (segment (start 68.175 152.918283) (end 68.175 148.85) (width 0.15) (layer "In5.Cu") (net 136))
  (segment (start 71.577 156.320283) (end 68.175 152.918283) (width 0.15) (layer "In5.Cu") (net 136))
  (segment (start 68.175 148.85) (end 68.2 148.825) (width 0.15) (layer "In5.Cu") (net 136))
  (segment (start 68.2 148.825) (end 70.725012 146.299988) (width 0.15) (layer "In5.Cu") (net 136))
  (segment (start 70.725 146.3) (end 70.725 147.315) (width 0.25) (layer "B.Cu") (net 136))
  (segment (start 66.72502 146.29998) (end 66.72502 143.48792) (width 0.25) (layer "F.Cu") (net 137))
  (segment (start 66.72502 143.48792) (end 65.6121 142.375) (width 0.25) (layer "F.Cu") (net 137))
  (segment (start 65.6121 142.375) (end 64.6001 142.375) (width 0.25) (layer "F.Cu") (net 137))
  (segment (start 70.077 158.00622) (end 70.077 157.00712) (width 0.15) (layer "F.Cu") (net 137))
  (via (at 66.72502 146.29998) (size 0.5) (drill 0.2) (layers "F.Cu" "B.Cu") (net 137))
  (via (at 70.077 157.00712) (size 0.5) (drill 0.2) (layers "F.Cu" "B.Cu") (net 137))
  (segment (start 70.077 157.00712) (end 70.077 156.262721) (width 0.15) (layer "In5.Cu") (net 137))
  (segment (start 70.077 156.262721) (end 66.75002 152.935741) (width 0.15) (layer "In5.Cu") (net 137))
  (segment (start 66.75002 152.935741) (end 66.75002 146.32498) (width 0.15) (layer "In5.Cu") (net 137))
  (segment (start 66.75002 146.32498) (end 66.72502 146.29998) (width 0.15) (layer "In5.Cu") (net 137))
  (segment (start 66.725 146.3) (end 66.725 147.315) (width 0.25) (layer "B.Cu") (net 137))
  (segment (start 65.725006 146.299994) (end 65.725006 143.757906) (width 0.25) (layer "F.Cu") (net 138))
  (segment (start 65.725006 143.757906) (end 65.6121 143.645) (width 0.25) (layer "F.Cu") (net 138))
  (segment (start 65.6121 143.645) (end 64.6001 143.645) (width 0.25) (layer "F.Cu") (net 138))
  (segment (start 69.577 158.00622) (end 69.577 156.60712) (width 0.15) (layer "F.Cu") (net 138))
  (via (at 65.725006 146.299994) (size 0.5) (drill 0.2) (layers "F.Cu" "B.Cu") (net 138))
  (via (at 69.577 156.60712) (size 0.5) (drill 0.2) (layers "F.Cu" "B.Cu") (net 138))
  (segment (start 69.577 156.60712) (end 69.577 156.187) (width 0.15) (layer "In5.Cu") (net 138))
  (segment (start 65.750006 152.360006) (end 65.750006 146.324994) (width 0.15) (layer "In5.Cu") (net 138))
  (segment (start 65.750006 146.324994) (end 65.725006 146.299994) (width 0.15) (layer "In5.Cu") (net 138))
  (segment (start 69.577 156.187) (end 65.750006 152.360006) (width 0.15) (layer "In5.Cu") (net 138))
  (segment (start 65.725 146.3) (end 65.725 147.315) (width 0.25) (layer "B.Cu") (net 138))
  (segment (start 71.077 158.00622) (end 71.077 157.00712) (width 0.15) (layer "F.Cu") (net 139))
  (segment (start 71.8899 142.375) (end 70.375 142.375) (width 0.25) (layer "F.Cu") (net 139))
  (segment (start 70.375 142.375) (end 68.70362 144.04638) (width 0.25) (layer "F.Cu") (net 139))
  (segment (start 68.70362 144.04638) (end 68.70362 146.27862) (width 0.25) (layer "F.Cu") (net 139))
  (via (at 68.70362 146.27862) (size 0.5) (drill 0.2) (layers "F.Cu" "B.Cu") (net 139))
  (via (at 71.077 157.00712) (size 0.5) (drill 0.2) (layers "F.Cu" "B.Cu") (net 139))
  (segment (start 71.077 156.331398) (end 71.077 157.00712) (width 0.15) (layer "In5.Cu") (net 139))
  (segment (start 67.725 152.979398) (end 71.077 156.331398) (width 0.15) (layer "In5.Cu") (net 139))
  (segment (start 68.70362 147.84638) (end 67.725 148.825) (width 0.15) (layer "In5.Cu") (net 139))
  (segment (start 68.70362 146.27862) (end 68.70362 147.84638) (width 0.15) (layer "In5.Cu") (net 139))
  (segment (start 67.725 148.825) (end 67.725 152.979398) (width 0.15) (layer "In5.Cu") (net 139))
  (segment (start 68.725 146.3) (end 68.725 147.315) (width 0.25) (layer "B.Cu") (net 139))
  (segment (start 67.724994 146.299994) (end 67.724994 143.217894) (width 0.25) (layer "F.Cu") (net 140))
  (segment (start 67.724994 143.217894) (end 65.6121 141.105) (width 0.25) (layer "F.Cu") (net 140))
  (segment (start 65.6121 141.105) (end 64.6001 141.105) (width 0.25) (layer "F.Cu") (net 140))
  (segment (start 70.577 158.00622) (end 70.577 156.60712) (width 0.15) (layer "F.Cu") (net 140))
  (via (at 67.724994 146.299994) (size 0.5) (drill 0.2) (layers "F.Cu" "B.Cu") (net 140))
  (via (at 70.577 156.60712) (size 0.5) (drill 0.2) (layers "F.Cu" "B.Cu") (net 140))
  (segment (start 67.603676 153.303676) (end 67.25 152.95) (width 0.15) (layer "In5.Cu") (net 140))
  (segment (start 67.25 148.7) (end 67.724994 148.225006) (width 0.15) (layer "In5.Cu") (net 140))
  (segment (start 70.577 156.255676) (end 67.625 153.303676) (width 0.15) (layer "In5.Cu") (net 140))
  (segment (start 70.577 156.60712) (end 70.577 156.255676) (width 0.15) (layer "In5.Cu") (net 140))
  (segment (start 67.625 153.303676) (end 67.603676 153.303676) (width 0.15) (layer "In5.Cu") (net 140))
  (segment (start 67.25 152.95) (end 67.25 148.7) (width 0.15) (layer "In5.Cu") (net 140))
  (segment (start 67.724994 148.225006) (end 67.724994 146.299994) (width 0.15) (layer "In5.Cu") (net 140))
  (segment (start 67.725 146.3) (end 67.725 147.315) (width 0.25) (layer "B.Cu") (net 140))
  (segment (start 70.877 136.0207) (end 71.889 136.0207) (width 0.25) (layer "F.Cu") (net 141))
  (segment (start 70.724112 136.173588) (end 70.877 136.0207) (width 0.25) (layer "F.Cu") (net 141))
  (segment (start 70.724112 137.405688) (end 70.724112 136.173588) (width 0.25) (layer "F.Cu") (net 141))
  (segment (start 72.572 154.34712) (end 72.572 151.85212) (width 0.15) (layer "F.Cu") (net 141))
  (via (at 70.724112 137.405688) (size 0.5) (drill 0.2) (layers "F.Cu" "B.Cu") (net 141))
  (via (at 72.552 151.83212) (size 0.5) (drill 0.2) (layers "F.Cu" "B.Cu") (net 141))
  (segment (start 72.7 143.05) (end 70.724112 141.074112) (width 0.15) (layer "In5.Cu") (net 141))
  (segment (start 72.552 151.83212) (end 72.552 148.048) (width 0.15) (layer "In5.Cu") (net 141))
  (segment (start 72.7 147.9) (end 72.7 143.05) (width 0.15) (layer "In5.Cu") (net 141))
  (segment (start 70.724112 141.074112) (end 70.724112 137.405688) (width 0.15) (layer "In5.Cu") (net 141))
  (segment (start 72.552 148.048) (end 72.7 147.9) (width 0.15) (layer "In5.Cu") (net 141))
  (segment (start 70.7241 137.4057) (end 70.7241 138.4207) (width 0.25) (layer "B.Cu") (net 141))
  (segment (start 66.72412 137.40568) (end 66.72412 134.59362) (width 0.25) (layer "F.Cu") (net 142))
  (segment (start 66.72412 134.59362) (end 65.6112 133.4807) (width 0.25) (layer "F.Cu") (net 142))
  (segment (start 65.6112 133.4807) (end 64.5992 133.4807) (width 0.25) (layer "F.Cu") (net 142))
  (segment (start 70.572 154.34712) (end 70.572 151.85212) (width 0.15) (layer "F.Cu") (net 142))
  (segment (start 70.572 151.85212) (end 70.552 151.83212) (width 0.15) (layer "F.Cu") (net 142))
  (via (at 66.72412 137.40568) (size 0.5) (drill 0.2) (layers "F.Cu" "B.Cu") (net 142))
  (via (at 70.552 151.83212) (size 0.5) (drill 0.2) (layers "F.Cu" "B.Cu") (net 142))
  (segment (start 70.552 148.198) (end 71.5 147.25) (width 0.15) (layer "In5.Cu") (net 142))
  (segment (start 71.5 147.25) (end 71.5 145.8) (width 0.15) (layer "In5.Cu") (net 142))
  (segment (start 71.5 145.8) (end 66.72412 141.02412) (width 0.15) (layer "In5.Cu") (net 142))
  (segment (start 70.552 151.83212) (end 70.552 148.198) (width 0.15) (layer "In5.Cu") (net 142))
  (segment (start 66.72412 141.02412) (end 66.72412 137.40568) (width 0.15) (layer "In5.Cu") (net 142))
  (segment (start 66.7241 137.4057) (end 66.7241 138.4207) (width 0.25) (layer "B.Cu") (net 142))
  (segment (start 65.724106 134.863606) (end 65.6112 134.7507) (width 0.25) (layer "F.Cu") (net 143))
  (segment (start 65.724106 137.405694) (end 65.724106 134.863606) (width 0.25) (layer "F.Cu") (net 143))
  (segment (start 65.6112 134.7507) (end 64.5992 134.7507) (width 0.25) (layer "F.Cu") (net 143))
  (segment (start 70.072 154.34712) (end 70.072 152.25212) (width 0.15) (layer "F.Cu") (net 143))
  (segment (start 70.072 152.25212) (end 70.052 152.23212) (width 0.15) (layer "F.Cu") (net 143))
  (via (at 65.724106 137.405694) (size 0.5) (drill 0.2) (layers "F.Cu" "B.Cu") (net 143))
  (via (at 70.052 152.23212) (size 0.5) (drill 0.2) (layers "F.Cu" "B.Cu") (net 143))
  (segment (start 65.724106 140.524106) (end 65.724106 137.405694) (width 0.15) (layer "In5.Cu") (net 143))
  (segment (start 71.2 146) (end 65.724106 140.524106) (width 0.15) (layer "In5.Cu") (net 143))
  (segment (start 70.052 152.23212) (end 70.052 148.148) (width 0.15) (layer "In5.Cu") (net 143))
  (segment (start 70.052 148.148) (end 71.2 147) (width 0.15) (layer "In5.Cu") (net 143))
  (segment (start 71.2 147) (end 71.2 146) (width 0.15) (layer "In5.Cu") (net 143))
  (segment (start 65.7241 137.4057) (end 65.7241 138.4207) (width 0.25) (layer "B.Cu") (net 143))
  (segment (start 68.724102 137.405702) (end 68.724102 134.405698) (width 0.25) (layer "F.Cu") (net 144))
  (segment (start 68.724102 134.405698) (end 69.6491 133.4807) (width 0.25) (layer "F.Cu") (net 144))
  (segment (start 69.6491 133.4807) (end 71.889 133.4807) (width 0.25) (layer "F.Cu") (net 144))
  (segment (start 71.572 154.34712) (end 71.572 151.853176) (width 0.15) (layer "F.Cu") (net 144))
  (via (at 68.724102 137.405702) (size 0.5) (drill 0.2) (layers "F.Cu" "B.Cu") (net 144))
  (via (at 71.552 151.83212) (size 0.5) (drill 0.2) (layers "F.Cu" "B.Cu") (net 144))
  (segment (start 71.552 151.83212) (end 71.552 148.148) (width 0.15) (layer "In5.Cu") (net 144))
  (segment (start 72.1 145.35) (end 68.724102 141.974102) (width 0.15) (layer "In5.Cu") (net 144))
  (segment (start 68.724102 141.974102) (end 68.724102 137.405702) (width 0.15) (layer "In5.Cu") (net 144))
  (segment (start 72.1 147.6) (end 72.1 145.35) (width 0.15) (layer "In5.Cu") (net 144))
  (segment (start 71.552 148.148) (end 72.1 147.6) (width 0.15) (layer "In5.Cu") (net 144))
  (segment (start 68.7241 137.4057) (end 68.7241 138.4207) (width 0.25) (layer "B.Cu") (net 144))
  (segment (start 67.724094 137.405694) (end 67.724094 134.323594) (width 0.25) (layer "F.Cu") (net 145))
  (segment (start 67.724094 134.323594) (end 65.6112 132.2107) (width 0.25) (layer "F.Cu") (net 145))
  (segment (start 71.072 154.34712) (end 71.072 152.25212) (width 0.15) (layer "F.Cu") (net 145))
  (segment (start 65.6112 132.2107) (end 64.6607 132.2107) (width 0.25) (layer "F.Cu") (net 145))
  (via (at 67.724094 137.405694) (size 0.5) (drill 0.2) (layers "F.Cu" "B.Cu") (net 145))
  (via (at 71.052 152.23212) (size 0.5) (drill 0.2) (layers "F.Cu" "B.Cu") (net 145))
  (segment (start 71.8 145.6) (end 67.724094 141.524094) (width 0.15) (layer "In5.Cu") (net 145))
  (segment (start 71.052 148.198) (end 71.8 147.45) (width 0.15) (layer "In5.Cu") (net 145))
  (segment (start 67.724094 141.524094) (end 67.724094 137.405694) (width 0.15) (layer "In5.Cu") (net 145))
  (segment (start 71.8 147.45) (end 71.8 145.6) (width 0.15) (layer "In5.Cu") (net 145))
  (segment (start 71.052 152.23212) (end 71.052 148.198) (width 0.15) (layer "In5.Cu") (net 145))
  (segment (start 67.7241 137.4057) (end 67.7241 138.4207) (width 0.25) (layer "B.Cu") (net 145))
  (segment (start 102.257397 87.281416) (end 102.244292 87.302272) (width 0.11) (layer "F.Cu") (net 146))
  (segment (start 102.295671 86.569106) (end 102.318921 86.577242) (width 0.11) (layer "F.Cu") (net 146))
  (segment (start 102.318921 86.577242) (end 102.343399 86.58) (width 0.11) (layer "F.Cu") (net 146))
  (segment (start 104.5 82.624436) (end 104.5 84.125564) (width 0.11) (layer "F.Cu") (net 146))
  (segment (start 103.285564 82.13) (end 104.005564 82.13) (width 0.11) (layer "F.Cu") (net 146))
  (segment (start 102.244292 86.422272) (end 102.236156 86.445522) (width 0.11) (layer "F.Cu") (net 146))
  (segment (start 102.802204 86.118257) (end 102.779208 86.183976) (width 0.11) (layer "F.Cu") (net 146))
  (segment (start 103.144859 86.587795) (end 103.210578 86.610791) (width 0.11) (layer "F.Cu") (net 146))
  (segment (start 102.257397 86.401416) (end 102.244292 86.422272) (width 0.11) (layer "F.Cu") (net 146))
  (segment (start 102.236156 87.374477) (end 102.244292 87.397727) (width 0.11) (layer "F.Cu") (net 146))
  (segment (start 102.257397 86.538583) (end 102.274815 86.556001) (width 0.11) (layer "F.Cu") (net 146))
  (segment (start 102.568257 87.467795) (end 102.633976 87.490791) (width 0.11) (layer "F.Cu") (net 146))
  (segment (start 102.499068 86.36) (end 102.343399 86.36) (width 0.11) (layer "F.Cu") (net 146))
  (segment (start 103.378806 86.998257) (end 103.35581 87.063976) (width 0.11) (layer "F.Cu") (net 146))
  (segment (start 102.318921 87.242757) (end 102.295671 87.250893) (width 0.11) (layer "F.Cu") (net 146))
  (segment (start 102.236156 87.325522) (end 102.233399 87.35) (width 0.11) (layer "F.Cu") (net 146))
  (segment (start 103.098 81.746) (end 103.098 81.942436) (width 0.11) (layer "F.Cu") (net 146))
  (segment (start 102.233399 86.47) (end 102.236156 86.494477) (width 0.11) (layer "F.Cu") (net 146))
  (segment (start 102.802204 87.701742) (end 102.81 87.770931) (width 0.11) (layer "F.Cu") (net 146))
  (segment (start 102.742164 86.242931) (end 102.692931 86.292164) (width 0.11) (layer "F.Cu") (net 146))
  (segment (start 102.236156 86.445522) (end 102.233399 86.47) (width 0.11) (layer "F.Cu") (net 146))
  (segment (start 103.098 81.942436) (end 103.285564 82.13) (width 0.11) (layer "F.Cu") (net 146))
  (segment (start 103.07567 87.24) (end 102.343399 87.24) (width 0.11) (layer "F.Cu") (net 146))
  (segment (start 102.499068 87.46) (end 102.568257 87.467795) (width 0.11) (layer "F.Cu") (net 146))
  (segment (start 102.295671 86.370893) (end 102.274815 86.383998) (width 0.11) (layer "F.Cu") (net 146))
  (segment (start 103.210578 86.610791) (end 103.269533 86.647835) (width 0.11) (layer "F.Cu") (net 146))
  (segment (start 102.779208 87.636023) (end 102.802204 87.701742) (width 0.11) (layer "F.Cu") (net 146))
  (segment (start 102.633976 86.329208) (end 102.568257 86.352204) (width 0.11) (layer "F.Cu") (net 146))
  (segment (start 102.244292 86.517727) (end 102.257397 86.538583) (width 0.11) (layer "F.Cu") (net 146))
  (segment (start 103.386601 86.890931) (end 103.386601 86.929068) (width 0.11) (layer "F.Cu") (net 146))
  (segment (start 103.378806 86.821742) (end 103.386601 86.890931) (width 0.11) (layer "F.Cu") (net 146))
  (segment (start 102.81 92.882851) (end 102.95 93.022851) (width 0.11) (layer "F.Cu") (net 146))
  (segment (start 103.269533 87.172164) (end 103.210578 87.209208) (width 0.11) (layer "F.Cu") (net 146))
  (segment (start 102.274815 87.436001) (end 102.295671 87.449106) (width 0.11) (layer "F.Cu") (net 146))
  (segment (start 102.343399 86.36) (end 102.318921 86.362757) (width 0.11) (layer "F.Cu") (net 146))
  (segment (start 102.318921 86.362757) (end 102.295671 86.370893) (width 0.11) (layer "F.Cu") (net 146))
  (segment (start 103.386601 86.929068) (end 103.378806 86.998257) (width 0.11) (layer "F.Cu") (net 146))
  (segment (start 102.295671 87.250893) (end 102.274815 87.263998) (width 0.11) (layer "F.Cu") (net 146))
  (segment (start 104.004 80.84) (end 103.098 81.746) (width 0.11) (layer "F.Cu") (net 146))
  (segment (start 102.233399 87.35) (end 102.236156 87.374477) (width 0.11) (layer "F.Cu") (net 146))
  (segment (start 103.07567 86.58) (end 103.144859 86.587795) (width 0.11) (layer "F.Cu") (net 146))
  (segment (start 103.144859 87.232204) (end 103.07567 87.24) (width 0.11) (layer "F.Cu") (net 146))
  (segment (start 102.779208 86.183976) (end 102.742164 86.242931) (width 0.11) (layer "F.Cu") (net 146))
  (segment (start 102.274815 86.383998) (end 102.257397 86.401416) (width 0.11) (layer "F.Cu") (net 146))
  (segment (start 102.244292 87.302272) (end 102.236156 87.325522) (width 0.11) (layer "F.Cu") (net 146))
  (segment (start 102.81 87.770931) (end 102.81 92.882851) (width 0.11) (layer "F.Cu") (net 146))
  (segment (start 102.81 85.815564) (end 102.81 86.049068) (width 0.11) (layer "F.Cu") (net 146))
  (segment (start 102.318921 87.457242) (end 102.343399 87.46) (width 0.11) (layer "F.Cu") (net 146))
  (segment (start 102.568257 86.352204) (end 102.499068 86.36) (width 0.11) (layer "F.Cu") (net 146))
  (segment (start 103.210578 87.209208) (end 103.144859 87.232204) (width 0.11) (layer "F.Cu") (net 146))
  (segment (start 103.35581 87.063976) (end 103.318766 87.122931) (width 0.11) (layer "F.Cu") (net 146))
  (segment (start 103.269533 86.647835) (end 103.318766 86.697068) (width 0.11) (layer "F.Cu") (net 146))
  (segment (start 102.343399 87.46) (end 102.499068 87.46) (width 0.11) (layer "F.Cu") (net 146))
  (segment (start 102.236156 86.494477) (end 102.244292 86.517727) (width 0.11) (layer "F.Cu") (net 146))
  (segment (start 102.257397 87.418583) (end 102.274815 87.436001) (width 0.11) (layer "F.Cu") (net 146))
  (segment (start 103.318766 86.697068) (end 103.35581 86.756023) (width 0.11) (layer "F.Cu") (net 146))
  (segment (start 102.692931 86.292164) (end 102.633976 86.329208) (width 0.11) (layer "F.Cu") (net 146))
  (segment (start 102.633976 87.490791) (end 102.692931 87.527835) (width 0.11) (layer "F.Cu") (net 146))
  (segment (start 103.35581 86.756023) (end 103.378806 86.821742) (width 0.11) (layer "F.Cu") (net 146))
  (segment (start 102.742164 87.577068) (end 102.779208 87.636023) (width 0.11) (layer "F.Cu") (net 146))
  (segment (start 102.343399 86.58) (end 103.07567 86.58) (width 0.11) (layer "F.Cu") (net 146))
  (segment (start 104.005564 82.13) (end 104.5 82.624436) (width 0.11) (layer "F.Cu") (net 146))
  (segment (start 102.274815 87.263998) (end 102.257397 87.281416) (width 0.11) (layer "F.Cu") (net 146))
  (segment (start 102.274815 86.556001) (end 102.295671 86.569106) (width 0.11) (layer "F.Cu") (net 146))
  (segment (start 102.295671 87.449106) (end 102.318921 87.457242) (width 0.11) (layer "F.Cu") (net 146))
  (segment (start 102.81 86.049068) (end 102.802204 86.118257) (width 0.11) (layer "F.Cu") (net 146))
  (segment (start 103.318766 87.122931) (end 103.269533 87.172164) (width 0.11) (layer "F.Cu") (net 146))
  (segment (start 102.244292 87.397727) (end 102.257397 87.418583) (width 0.11) (layer "F.Cu") (net 146))
  (segment (start 102.692931 87.527835) (end 102.742164 87.577068) (width 0.11) (layer "F.Cu") (net 146))
  (segment (start 104.5 84.125564) (end 102.81 85.815564) (width 0.11) (layer "F.Cu") (net 146))
  (segment (start 102.343399 87.24) (end 102.318921 87.242757) (width 0.11) (layer "F.Cu") (net 146))
  (segment (start 105.274855 84.895082) (end 105.292726 84.923523) (width 0.11) (layer "F.Cu") (net 147))
  (segment (start 105.376622 82.88376) (end 105.344918 82.894854) (width 0.11) (layer "F.Cu") (net 147))
  (segment (start 105.292726 84.136476) (end 105.274855 84.164917) (width 0.11) (layer "F.Cu") (net 147))
  (segment (start 105.698895 82.795082) (end 105.681024 82.823523) (width 0.11) (layer "F.Cu") (net 147))
  (segment (start 105.316477 83.512725) (end 105.292726 83.536476) (width 0.11) (layer "F.Cu") (net 147))
  (segment (start 105.709989 83.363378) (end 105.698895 83.395082) (width 0.11) (layer "F.Cu") (net 147))
  (segment (start 105.344918 82.894854) (end 105.316477 82.912725) (width 0.11) (layer "F.Cu") (net 147))
  (segment (start 105.344918 84.094854) (end 105.316477 84.112725) (width 0.11) (layer "F.Cu") (net 147))
  (segment (start 105.292726 84.736476) (end 105.274855 84.764917) (width 0.11) (layer "F.Cu") (net 147))
  (segment (start 105.698895 82.664917) (end 105.709989 82.696621) (width 0.11) (layer "F.Cu") (net 147))
  (segment (start 105.274855 83.564917) (end 105.263761 83.596621) (width 0.11) (layer "F.Cu") (net 147))
  (segment (start 105.376622 84.976239) (end 105.41 84.98) (width 0.11) (layer "F.Cu") (net 147))
  (segment (start 105.344918 83.765145) (end 105.376622 83.776239) (width 0.11) (layer "F.Cu") (net 147))
  (segment (start 105.344918 84.965145) (end 105.376622 84.976239) (width 0.11) (layer "F.Cu") (net 147))
  (segment (start 105.597128 83.476239) (end 105.563749 83.48) (width 0.11) (layer "F.Cu") (net 147))
  (segment (start 105.41 84.68) (end 105.376622 84.68376) (width 0.11) (layer "F.Cu") (net 147))
  (segment (start 105.681024 84.436476) (end 105.698895 84.464917) (width 0.11) (layer "F.Cu") (net 147))
  (segment (start 105.597128 82.876239) (end 105.563749 82.88) (width 0.11) (layer "F.Cu") (net 147))
  (segment (start 105.657273 82.247274) (end 105.628832 82.265145) (width 0.11) (layer "F.Cu") (net 147))
  (segment (start 105.709989 84.496621) (end 105.713749 84.53) (width 0.11) (layer "F.Cu") (net 147))
  (segment (start 105.316477 84.112725) (end 105.292726 84.136476) (width 0.11) (layer "F.Cu") (net 147))
  (segment (start 105.681024 84.623523) (end 105.657273 84.647274) (width 0.11) (layer "F.Cu") (net 147))
  (segment (start 105.563749 82.58) (end 105.597128 82.58376) (width 0.11) (layer "F.Cu") (net 147))
  (segment (start 105.274855 84.164917) (end 105.263761 84.196621) (width 0.11) (layer "F.Cu") (net 147))
  (segment (start 105.657273 83.212725) (end 105.681024 83.236476) (width 0.11) (layer "F.Cu") (net 147))
  (segment (start 105.681024 85.223523) (end 105.657273 85.247274) (width 0.11) (layer "F.Cu") (net 147))
  (segment (start 105.713749 83.33) (end 105.709989 83.363378) (width 0.11) (layer "F.Cu") (net 147))
  (segment (start 105.41 82.28) (end 105.376622 82.28376) (width 0.11) (layer "F.Cu") (net 147))
  (segment (start 105.376622 82.576239) (end 105.41 82.58) (width 0.11) (layer "F.Cu") (net 147))
  (segment (start 105.344918 82.565145) (end 105.376622 82.576239) (width 0.11) (layer "F.Cu") (net 147))
  (segment (start 105.41 81.98) (end 105.563749 81.98) (width 0.11) (layer "F.Cu") (net 147))
  (segment (start 105.376622 81.976239) (end 105.41 81.98) (width 0.11) (layer "F.Cu") (net 147))
  (segment (start 105.597128 83.78376) (end 105.628832 83.794854) (width 0.11) (layer "F.Cu") (net 147))
  (segment (start 105.713749 82.13) (end 105.709989 82.163378) (width 0.11) (layer "F.Cu") (net 147))
  (segment (start 105.274855 83.095082) (end 105.292726 83.123523) (width 0.11) (layer "F.Cu") (net 147))
  (segment (start 105.563749 84.98) (end 105.597128 84.98376) (width 0.11) (layer "F.Cu") (net 147))
  (segment (start 105.376622 84.68376) (end 105.344918 84.694854) (width 0.11) (layer "F.Cu") (net 147))
  (segment (start 105.263761 84.796621) (end 105.26 84.83) (width 0.11) (layer "F.Cu") (net 147))
  (segment (start 105.26 83.03) (end 105.263761 83.063378) (width 0.11) (layer "F.Cu") (net 147))
  (segment (start 105.376622 83.776239) (end 105.41 83.78) (width 0.11) (layer "F.Cu") (net 147))
  (segment (start 105.709989 84.563378) (end 105.698895 84.595082) (width 0.11) (layer "F.Cu") (net 147))
  (segment (start 105.316477 84.347274) (end 105.344918 84.365145) (width 0.11) (layer "F.Cu") (net 147))
  (segment (start 106.036 80.84) (end 105.26 81.616) (width 0.11) (layer "F.Cu") (net 147))
  (segment (start 105.274855 81.895082) (end 105.292726 81.923523) (width 0.11) (layer "F.Cu") (net 147))
  (segment (start 105.628832 83.794854) (end 105.657273 83.812725) (width 0.11) (layer "F.Cu") (net 147))
  (segment (start 103.81 90.895564) (end 103.81 92.882851) (width 0.11) (layer "F.Cu") (net 147))
  (segment (start 105.698895 83.864917) (end 105.709989 83.896621) (width 0.11) (layer "F.Cu") (net 147))
  (segment (start 105.628832 84.665145) (end 105.597128 84.676239) (width 0.11) (layer "F.Cu") (net 147))
  (segment (start 105.681024 82.823523) (end 105.657273 82.847274) (width 0.11) (layer "F.Cu") (net 147))
  (segment (start 105.681024 82.036476) (end 105.698895 82.064917) (width 0.11) (layer "F.Cu") (net 147))
  (segment (start 105.563749 83.18) (end 105.597128 83.18376) (width 0.11) (layer "F.Cu") (net 147))
  (segment (start 105.681024 83.236476) (end 105.698895 83.264917) (width 0.11) (layer "F.Cu") (net 147))
  (segment (start 105.26 84.83) (end 105.263761 84.863378) (width 0.11) (layer "F.Cu") (net 147))
  (segment (start 105.563749 84.08) (end 105.41 84.08) (width 0.11) (layer "F.Cu") (net 147))
  (segment (start 105.263761 83.663378) (end 105.274855 83.695082) (width 0.11) (layer "F.Cu") (net 147))
  (segment (start 105.316477 83.747274) (end 105.344918 83.765145) (width 0.11) (layer "F.Cu") (net 147))
  (segment (start 105.376622 83.48376) (end 105.344918 83.494854) (width 0.11) (layer "F.Cu") (net 147))
  (segment (start 105.41 84.98) (end 105.563749 84.98) (width 0.11) (layer "F.Cu") (net 147))
  (segment (start 105.376622 85.28376) (end 105.344918 85.294854) (width 0.11) (layer "F.Cu") (net 147))
  (segment (start 105.709989 82.763378) (end 105.698895 82.795082) (width 0.11) (layer "F.Cu") (net 147))
  (segment (start 105.709989 85.096621) (end 105.713749 85.13) (width 0.11) (layer "F.Cu") (net 147))
  (segment (start 105.344918 82.294854) (end 105.316477 82.312725) (width 0.11) (layer "F.Cu") (net 147))
  (segment (start 105.292726 82.523523) (end 105.316477 82.547274) (width 0.11) (layer "F.Cu") (net 147))
  (segment (start 105.628832 84.994854) (end 105.657273 85.012725) (width 0.11) (layer "F.Cu") (net 147))
  (segment (start 105.26 84.23) (end 105.263761 84.263378) (width 0.11) (layer "F.Cu") (net 147))
  (segment (start 105.263761 84.196621) (end 105.26 84.23) (width 0.11) (layer "F.Cu") (net 147))
  (segment (start 105.292726 83.723523) (end 105.316477 83.747274) (width 0.11) (layer "F.Cu") (net 147))
  (segment (start 105.292726 83.123523) (end 105.316477 83.147274) (width 0.11) (layer "F.Cu") (net 147))
  (segment (start 105.628832 84.394854) (end 105.657273 84.412725) (width 0.11) (layer "F.Cu") (net 147))
  (segment (start 105.41 83.18) (end 105.563749 83.18) (width 0.11) (layer "F.Cu") (net 147))
  (segment (start 105.628832 83.194854) (end 105.657273 83.212725) (width 0.11) (layer "F.Cu") (net 147))
  (segment (start 105.698895 84.595082) (end 105.681024 84.623523) (width 0.11) (layer "F.Cu") (net 147))
  (segment (start 105.597128 84.98376) (end 105.628832 84.994854) (width 0.11) (layer "F.Cu") (net 147))
  (segment (start 105.713749 83.93) (end 105.709989 83.963378) (width 0.11) (layer "F.Cu") (net 147))
  (segment (start 105.709989 85.163378) (end 105.698895 85.195082) (width 0.11) (layer "F.Cu") (net 147))
  (segment (start 105.316477 82.547274) (end 105.344918 82.565145) (width 0.11) (layer "F.Cu") (net 147))
  (segment (start 105.26 89.445564) (end 103.81 90.895564) (width 0.11) (layer "F.Cu") (net 147))
  (segment (start 105.657273 83.447274) (end 105.628832 83.465145) (width 0.11) (layer "F.Cu") (net 147))
  (segment (start 105.263761 82.396621) (end 105.26 82.43) (width 0.11) (layer "F.Cu") (net 147))
  (segment (start 105.597128 85.276239) (end 105.563749 85.28) (width 0.11) (layer "F.Cu") (net 147))
  (segment (start 105.274855 84.295082) (end 105.292726 84.323523) (width 0.11) (layer "F.Cu") (net 147))
  (segment (start 105.41 82.88) (end 105.376622 82.88376) (width 0.11) (layer "F.Cu") (net 147))
  (segment (start 105.263761 85.396621) (end 105.26 85.43) (width 0.11) (layer "F.Cu") (net 147))
  (segment (start 105.698895 85.195082) (end 105.681024 85.223523) (width 0.11) (layer "F.Cu") (net 147))
  (segment (start 105.709989 82.696621) (end 105.713749 82.73) (width 0.11) (layer "F.Cu") (net 147))
  (segment (start 105.376622 83.176239) (end 105.41 83.18) (width 0.11) (layer "F.Cu") (net 147))
  (segment (start 105.41 83.78) (end 105.563749 83.78) (width 0.11) (layer "F.Cu") (net 147))
  (segment (start 105.292726 82.936476) (end 105.274855 82.964917) (width 0.11) (layer "F.Cu") (net 147))
  (segment (start 105.263761 82.463378) (end 105.274855 82.495082) (width 0.11) (layer "F.Cu") (net 147))
  (segment (start 105.263761 81.863378) (end 105.274855 81.895082) (width 0.11) (layer "F.Cu") (net 147))
  (segment (start 105.698895 85.064917) (end 105.709989 85.096621) (width 0.11) (layer "F.Cu") (net 147))
  (segment (start 105.316477 84.947274) (end 105.344918 84.965145) (width 0.11) (layer "F.Cu") (net 147))
  (segment (start 105.657273 84.647274) (end 105.628832 84.665145) (width 0.11) (layer "F.Cu") (net 147))
  (segment (start 105.681024 83.836476) (end 105.698895 83.864917) (width 0.11) (layer "F.Cu") (net 147))
  (segment (start 105.698895 84.464917) (end 105.709989 84.496621) (width 0.11) (layer "F.Cu") (net 147))
  (segment (start 105.263761 84.863378) (end 105.274855 84.895082) (width 0.11) (layer "F.Cu") (net 147))
  (segment (start 105.657273 83.812725) (end 105.681024 83.836476) (width 0.11) (layer "F.Cu") (net 147))
  (segment (start 105.316477 81.947274) (end 105.344918 81.965145) (width 0.11) (layer "F.Cu") (net 147))
  (segment (start 105.263761 84.263378) (end 105.274855 84.295082) (width 0.11) (layer "F.Cu") (net 147))
  (segment (start 105.274855 82.364917) (end 105.263761 82.396621) (width 0.11) (layer "F.Cu") (net 147))
  (segment (start 105.597128 84.38376) (end 105.628832 84.394854) (width 0.11) (layer "F.Cu") (net 147))
  (segment (start 105.292726 84.923523) (end 105.316477 84.947274) (width 0.11) (layer "F.Cu") (net 147))
  (segment (start 105.41 83.48) (end 105.376622 83.48376) (width 0.11) (layer "F.Cu") (net 147))
  (segment (start 105.597128 81.98376) (end 105.628832 81.994854) (width 0.11) (layer "F.Cu") (net 147))
  (segment (start 105.563749 84.38) (end 105.597128 84.38376) (width 0.11) (layer "F.Cu") (net 147))
  (segment (start 105.344918 83.165145) (end 105.376622 83.176239) (width 0.11) (layer "F.Cu") (net 147))
  (segment (start 105.657273 82.612725) (end 105.681024 82.636476) (width 0.11) (layer "F.Cu") (net 147))
  (segment (start 105.681024 84.023523) (end 105.657273 84.047274) (width 0.11) (layer "F.Cu") (net 147))
  (segment (start 105.292726 81.923523) (end 105.316477 81.947274) (width 0.11) (layer "F.Cu") (net 147))
  (segment (start 105.316477 85.312725) (end 105.292726 85.336476) (width 0.11) (layer "F.Cu") (net 147))
  (segment (start 105.709989 83.296621) (end 105.713749 83.33) (width 0.11) (layer "F.Cu") (net 147))
  (segment (start 105.681024 82.636476) (end 105.698895 82.664917) (width 0.11) (layer "F.Cu") (net 147))
  (segment (start 105.263761 83.063378) (end 105.274855 83.095082) (width 0.11) (layer "F.Cu") (net 147))
  (segment (start 105.344918 81.965145) (end 105.376622 81.976239) (width 0.11) (layer "F.Cu") (net 147))
  (segment (start 105.263761 83.596621) (end 105.26 83.63) (width 0.11) (layer "F.Cu") (net 147))
  (segment (start 105.274855 83.695082) (end 105.292726 83.723523) (width 0.11) (layer "F.Cu") (net 147))
  (segment (start 105.713749 85.13) (end 105.709989 85.163378) (width 0.11) (layer "F.Cu") (net 147))
  (segment (start 105.628832 82.865145) (end 105.597128 82.876239) (width 0.11) (layer "F.Cu") (net 147))
  (segment (start 105.376622 84.376239) (end 105.41 84.38) (width 0.11) (layer "F.Cu") (net 147))
  (segment (start 105.563749 82.28) (end 105.41 82.28) (width 0.11) (layer "F.Cu") (net 147))
  (segment (start 105.657273 85.012725) (end 105.681024 85.036476) (width 0.11) (layer "F.Cu") (net 147))
  (segment (start 105.41 85.28) (end 105.376622 85.28376) (width 0.11) (layer "F.Cu") (net 147))
  (segment (start 105.263761 82.996621) (end 105.26 83.03) (width 0.11) (layer "F.Cu") (net 147))
  (segment (start 105.292726 84.323523) (end 105.316477 84.347274) (width 0.11) (layer "F.Cu") (net 147))
  (segment (start 105.713749 84.53) (end 105.709989 84.563378) (width 0.11) (layer "F.Cu") (net 147))
  (segment (start 105.597128 84.676239) (end 105.563749 84.68) (width 0.11) (layer "F.Cu") (net 147))
  (segment (start 105.698895 83.264917) (end 105.709989 83.296621) (width 0.11) (layer "F.Cu") (net 147))
  (segment (start 105.316477 84.712725) (end 105.292726 84.736476) (width 0.11) (layer "F.Cu") (net 147))
  (segment (start 105.628832 81.994854) (end 105.657273 82.012725) (width 0.11) (layer "F.Cu") (net 147))
  (segment (start 105.344918 85.294854) (end 105.316477 85.312725) (width 0.11) (layer "F.Cu") (net 147))
  (segment (start 105.657273 84.047274) (end 105.628832 84.065145) (width 0.11) (layer "F.Cu") (net 147))
  (segment (start 105.563749 83.48) (end 105.41 83.48) (width 0.11) (layer "F.Cu") (net 147))
  (segment (start 105.26 81.83) (end 105.263761 81.863378) (width 0.11) (layer "F.Cu") (net 147))
  (segment (start 105.41 82.58) (end 105.563749 82.58) (width 0.11) (layer "F.Cu") (net 147))
  (segment (start 105.657273 85.247274) (end 105.628832 85.265145) (width 0.11) (layer "F.Cu") (net 147))
  (segment (start 105.316477 82.312725) (end 105.292726 82.336476) (width 0.11) (layer "F.Cu") (net 147))
  (segment (start 105.274855 84.764917) (end 105.263761 84.796621) (width 0.11) (layer "F.Cu") (net 147))
  (segment (start 105.698895 83.395082) (end 105.681024 83.423523) (width 0.11) (layer "F.Cu") (net 147))
  (segment (start 105.657273 84.412725) (end 105.681024 84.436476) (width 0.11) (layer "F.Cu") (net 147))
  (segment (start 105.628832 82.265145) (end 105.597128 82.276239) (width 0.11) (layer "F.Cu") (net 147))
  (segment (start 105.681024 83.423523) (end 105.657273 83.447274) (width 0.11) (layer "F.Cu") (net 147))
  (segment (start 105.292726 82.336476) (end 105.274855 82.364917) (width 0.11) (layer "F.Cu") (net 147))
  (segment (start 105.274855 82.495082) (end 105.292726 82.523523) (width 0.11) (layer "F.Cu") (net 147))
  (segment (start 105.628832 84.065145) (end 105.597128 84.076239) (width 0.11) (layer "F.Cu") (net 147))
  (segment (start 105.316477 82.912725) (end 105.292726 82.936476) (width 0.11) (layer "F.Cu") (net 147))
  (segment (start 105.563749 84.68) (end 105.41 84.68) (width 0.11) (layer "F.Cu") (net 147))
  (segment (start 105.657273 82.012725) (end 105.681024 82.036476) (width 0.11) (layer "F.Cu") (net 147))
  (segment (start 105.597128 82.58376) (end 105.628832 82.594854) (width 0.11) (layer "F.Cu") (net 147))
  (segment (start 105.563749 82.88) (end 105.41 82.88) (width 0.11) (layer "F.Cu") (net 147))
  (segment (start 105.563749 81.98) (end 105.597128 81.98376) (width 0.11) (layer "F.Cu") (net 147))
  (segment (start 105.563749 83.78) (end 105.597128 83.78376) (width 0.11) (layer "F.Cu") (net 147))
  (segment (start 105.709989 83.896621) (end 105.713749 83.93) (width 0.11) (layer "F.Cu") (net 147))
  (segment (start 105.709989 82.096621) (end 105.713749 82.13) (width 0.11) (layer "F.Cu") (net 147))
  (segment (start 103.81 92.882851) (end 103.95 93.022851) (width 0.11) (layer "F.Cu") (net 147))
  (segment (start 105.274855 85.364917) (end 105.263761 85.396621) (width 0.11) (layer "F.Cu") (net 147))
  (segment (start 105.274855 82.964917) (end 105.263761 82.996621) (width 0.11) (layer "F.Cu") (net 147))
  (segment (start 105.628832 85.265145) (end 105.597128 85.276239) (width 0.11) (layer "F.Cu") (net 147))
  (segment (start 105.26 83.63) (end 105.263761 83.663378) (width 0.11) (layer "F.Cu") (net 147))
  (segment (start 105.26 82.43) (end 105.263761 82.463378) (width 0.11) (layer "F.Cu") (net 147))
  (segment (start 105.41 84.38) (end 105.563749 84.38) (width 0.11) (layer "F.Cu") (net 147))
  (segment (start 105.709989 83.963378) (end 105.698895 83.995082) (width 0.11) (layer "F.Cu") (net 147))
  (segment (start 105.344918 84.365145) (end 105.376622 84.376239) (width 0.11) (layer "F.Cu") (net 147))
  (segment (start 105.344918 84.694854) (end 105.316477 84.712725) (width 0.11) (layer "F.Cu") (net 147))
  (segment (start 105.376622 82.28376) (end 105.344918 82.294854) (width 0.11) (layer "F.Cu") (net 147))
  (segment (start 105.698895 82.064917) (end 105.709989 82.096621) (width 0.11) (layer "F.Cu") (net 147))
  (segment (start 105.681024 85.036476) (end 105.698895 85.064917) (width 0.11) (layer "F.Cu") (net 147))
  (segment (start 105.657273 82.847274) (end 105.628832 82.865145) (width 0.11) (layer "F.Cu") (net 147))
  (segment (start 105.344918 83.494854) (end 105.316477 83.512725) (width 0.11) (layer "F.Cu") (net 147))
  (segment (start 105.709989 82.163378) (end 105.698895 82.195082) (width 0.11) (layer "F.Cu") (net 147))
  (segment (start 105.292726 85.336476) (end 105.274855 85.364917) (width 0.11) (layer "F.Cu") (net 147))
  (segment (start 105.292726 83.536476) (end 105.274855 83.564917) (width 0.11) (layer "F.Cu") (net 147))
  (segment (start 105.713749 82.73) (end 105.709989 82.763378) (width 0.11) (layer "F.Cu") (net 147))
  (segment (start 105.597128 84.076239) (end 105.563749 84.08) (width 0.11) (layer "F.Cu") (net 147))
  (segment (start 105.628832 82.594854) (end 105.657273 82.612725) (width 0.11) (layer "F.Cu") (net 147))
  (segment (start 105.316477 83.147274) (end 105.344918 83.165145) (width 0.11) (layer "F.Cu") (net 147))
  (segment (start 105.628832 83.465145) (end 105.597128 83.476239) (width 0.11) (layer "F.Cu") (net 147))
  (segment (start 105.597128 82.276239) (end 105.563749 82.28) (width 0.11) (layer "F.Cu") (net 147))
  (segment (start 105.563749 85.28) (end 105.41 85.28) (width 0.11) (layer "F.Cu") (net 147))
  (segment (start 105.26 81.616) (end 105.26 81.83) (width 0.11) (layer "F.Cu") (net 147))
  (segment (start 105.376622 84.08376) (end 105.344918 84.094854) (width 0.11) (layer "F.Cu") (net 147))
  (segment (start 105.26 85.43) (end 105.26 89.445564) (width 0.11) (layer "F.Cu") (net 147))
  (segment (start 105.597128 83.18376) (end 105.628832 83.194854) (width 0.11) (layer "F.Cu") (net 147))
  (segment (start 105.681024 82.223523) (end 105.657273 82.247274) (width 0.11) (layer "F.Cu") (net 147))
  (segment (start 105.41 84.08) (end 105.376622 84.08376) (width 0.11) (layer "F.Cu") (net 147))
  (segment (start 105.698895 82.195082) (end 105.681024 82.223523) (width 0.11) (layer "F.Cu") (net 147))
  (segment (start 105.698895 83.995082) (end 105.681024 84.023523) (width 0.11) (layer "F.Cu") (net 147))
  (segment (start 107.631055 86.741998) (end 107.613637 86.759416) (width 0.11) (layer "F.Cu") (net 148))
  (segment (start 108.766361 87.287068) (end 108.758566 87.356257) (width 0.11) (layer "F.Cu") (net 148))
  (segment (start 108.73557 87.114023) (end 108.758566 87.179742) (width 0.11) (layer "F.Cu") (net 148))
  (segment (start 108.698526 85.720931) (end 108.649293 85.770164) (width 0.11) (layer "F.Cu") (net 148))
  (segment (start 108.649293 86.125835) (end 108.698526 86.175068) (width 0.11) (layer "F.Cu") (net 148))
  (segment (start 108.698526 87.480931) (end 108.649293 87.530164) (width 0.11) (layer "F.Cu") (net 148))
  (segment (start 108.766361 85.488931) (end 108.766361 85.527068) (width 0.11) (layer "F.Cu") (net 148))
  (segment (start 107.592396 85.043522) (end 107.589639 85.068) (width 0.11) (layer "F.Cu") (net 148))
  (segment (start 108.590338 87.567208) (end 108.524619 87.590204) (width 0.11) (layer "F.Cu") (net 148))
  (segment (start 108.590338 85.208791) (end 108.649293 85.245835) (width 0.11) (layer "F.Cu") (net 148))
  (segment (start 108.188894 87.660272) (end 108.180758 87.683522) (width 0.11) (layer "F.Cu") (net 148))
  (segment (start 107.699639 86.938) (end 108.45543 86.938) (width 0.11) (layer "F.Cu") (net 148))
  (segment (start 108.766361 85.527068) (end 108.758566 85.596257) (width 0.11) (layer "F.Cu") (net 148))
  (segment (start 108.178 88.977564) (end 105.31 91.845564) (width 0.11) (layer "F.Cu") (net 148))
  (segment (start 107.867068 84.958) (end 107.699639 84.958) (width 0.11) (layer "F.Cu") (net 148))
  (segment (start 108.524619 86.065795) (end 108.590338 86.088791) (width 0.11) (layer "F.Cu") (net 148))
  (segment (start 107.699639 86.718) (end 107.675161 86.720757) (width 0.11) (layer "F.Cu") (net 148))
  (segment (start 107.592396 85.923522) (end 107.589639 85.948) (width 0.11) (layer "F.Cu") (net 148))
  (segment (start 108.180758 87.683522) (end 108.178 87.708) (width 0.11) (layer "F.Cu") (net 148))
  (segment (start 108.758566 86.476257) (end 108.73557 86.541976) (width 0.11) (layer "F.Cu") (net 148))
  (segment (start 107.631055 86.914001) (end 107.651911 86.927106) (width 0.11) (layer "F.Cu") (net 148))
  (segment (start 107.651911 84.968893) (end 107.631055 84.981998) (width 0.11) (layer "F.Cu") (net 148))
  (segment (start 108.758566 87.356257) (end 108.73557 87.421976) (width 0.11) (layer "F.Cu") (net 148))
  (segment (start 108.698526 87.055068) (end 108.73557 87.114023) (width 0.11) (layer "F.Cu") (net 148))
  (segment (start 107.600532 85.995727) (end 107.613637 86.016583) (width 0.11) (layer "F.Cu") (net 148))
  (segment (start 108.73557 85.661976) (end 108.698526 85.720931) (width 0.11) (layer "F.Cu") (net 148))
  (segment (start 108.758566 85.419742) (end 108.766361 85.488931) (width 0.11) (layer "F.Cu") (net 148))
  (segment (start 107.651911 85.848893) (end 107.631055 85.861998) (width 0.11) (layer "F.Cu") (net 148))
  (segment (start 108.590338 86.687208) (end 108.524619 86.710204) (width 0.11) (layer "F.Cu") (net 148))
  (segment (start 107.936257 84.950204) (end 107.867068 84.958) (width 0.11) (layer "F.Cu") (net 148))
  (segment (start 107.651911 86.047106) (end 107.675161 86.055242) (width 0.11) (layer "F.Cu") (net 148))
  (segment (start 108.288 87.598) (end 108.263523 87.600757) (width 0.11) (layer "F.Cu") (net 148))
  (segment (start 109.084 83.38) (end 108.178 84.286) (width 0.11) (layer "F.Cu") (net 148))
  (segment (start 108.758566 85.596257) (end 108.73557 85.661976) (width 0.11) (layer "F.Cu") (net 148))
  (segment (start 108.590338 85.807208) (end 108.524619 85.830204) (width 0.11) (layer "F.Cu") (net 148))
  (segment (start 108.45543 85.178) (end 108.524619 85.185795) (width 0.11) (layer "F.Cu") (net 148))
  (segment (start 108.524619 85.830204) (end 108.45543 85.838) (width 0.11) (layer "F.Cu") (net 148))
  (segment (start 108.649293 86.650164) (end 108.590338 86.687208) (width 0.11) (layer "F.Cu") (net 148))
  (segment (start 108.524619 86.945795) (end 108.590338 86.968791) (width 0.11) (layer "F.Cu") (net 148))
  (segment (start 108.45543 86.938) (end 108.524619 86.945795) (width 0.11) (layer "F.Cu") (net 148))
  (segment (start 107.613637 86.896583) (end 107.631055 86.914001) (width 0.11) (layer "F.Cu") (net 148))
  (segment (start 107.613637 86.016583) (end 107.631055 86.034001) (width 0.11) (layer "F.Cu") (net 148))
  (segment (start 107.613637 84.999416) (end 107.600532 85.020272) (width 0.11) (layer "F.Cu") (net 148))
  (segment (start 108.698526 85.295068) (end 108.73557 85.354023) (width 0.11) (layer "F.Cu") (net 148))
  (segment (start 107.589639 86.828) (end 107.592396 86.852477) (width 0.11) (layer "F.Cu") (net 148))
  (segment (start 108.590338 86.088791) (end 108.649293 86.125835) (width 0.11) (layer "F.Cu") (net 148))
  (segment (start 108.178 87.708) (end 108.178 88.977564) (width 0.11) (layer "F.Cu") (net 148))
  (segment (start 108.73557 85.354023) (end 108.758566 85.419742) (width 0.11) (layer "F.Cu") (net 148))
  (segment (start 107.631055 85.861998) (end 107.613637 85.879416) (width 0.11) (layer "F.Cu") (net 148))
  (segment (start 108.73557 86.234023) (end 108.758566 86.299742) (width 0.11) (layer "F.Cu") (net 148))
  (segment (start 108.698526 86.600931) (end 108.649293 86.650164) (width 0.11) (layer "F.Cu") (net 148))
  (segment (start 107.592396 86.803522) (end 107.589639 86.828) (width 0.11) (layer "F.Cu") (net 148))
  (segment (start 107.675161 84.960757) (end 107.651911 84.968893) (width 0.11) (layer "F.Cu") (net 148))
  (segment (start 108.219417 87.621998) (end 108.201999 87.639416) (width 0.11) (layer "F.Cu") (net 148))
  (segment (start 108.110164 84.840931) (end 108.060931 84.890164) (width 0.11) (layer "F.Cu") (net 148))
  (segment (start 107.600532 86.875727) (end 107.613637 86.896583) (width 0.11) (layer "F.Cu") (net 148))
  (segment (start 107.675161 86.720757) (end 107.651911 86.728893) (width 0.11) (layer "F.Cu") (net 148))
  (segment (start 107.675161 85.840757) (end 107.651911 85.848893) (width 0.11) (layer "F.Cu") (net 148))
  (segment (start 108.524619 87.590204) (end 108.45543 87.598) (width 0.11) (layer "F.Cu") (net 148))
  (segment (start 108.240273 87.608893) (end 108.219417 87.621998) (width 0.11) (layer "F.Cu") (net 148))
  (segment (start 107.651911 85.167106) (end 107.675161 85.175242) (width 0.11) (layer "F.Cu") (net 148))
  (segment (start 107.631055 84.981998) (end 107.613637 84.999416) (width 0.11) (layer "F.Cu") (net 148))
  (segment (start 107.699639 85.838) (end 107.675161 85.840757) (width 0.11) (layer "F.Cu") (net 148))
  (segment (start 107.699639 84.958) (end 107.675161 84.960757) (width 0.11) (layer "F.Cu") (net 148))
  (segment (start 108.766361 87.248931) (end 108.766361 87.287068) (width 0.11) (layer "F.Cu") (net 148))
  (segment (start 108.263523 87.600757) (end 108.240273 87.608893) (width 0.11) (layer "F.Cu") (net 148))
  (segment (start 107.631055 85.154001) (end 107.651911 85.167106) (width 0.11) (layer "F.Cu") (net 148))
  (segment (start 107.651911 86.728893) (end 107.631055 86.741998) (width 0.11) (layer "F.Cu") (net 148))
  (segment (start 108.45543 86.718) (end 107.699639 86.718) (width 0.11) (layer "F.Cu") (net 148))
  (segment (start 107.675161 86.055242) (end 107.699639 86.058) (width 0.11) (layer "F.Cu") (net 148))
  (segment (start 107.600532 85.115727) (end 107.613637 85.136583) (width 0.11) (layer "F.Cu") (net 148))
  (segment (start 107.589639 85.068) (end 107.592396 85.092477) (width 0.11) (layer "F.Cu") (net 148))
  (segment (start 108.170204 84.716257) (end 108.147208 84.781976) (width 0.11) (layer "F.Cu") (net 148))
  (segment (start 108.649293 87.005835) (end 108.698526 87.055068) (width 0.11) (layer "F.Cu") (net 148))
  (segment (start 107.600532 86.780272) (end 107.592396 86.803522) (width 0.11) (layer "F.Cu") (net 148))
  (segment (start 108.178 84.286) (end 108.178 84.647068) (width 0.11) (layer "F.Cu") (net 148))
  (segment (start 107.592396 85.972477) (end 107.600532 85.995727) (width 0.11) (layer "F.Cu") (net 148))
  (segment (start 105.31 91.845564) (end 105.31 92.882851) (width 0.11) (layer "F.Cu") (net 148))
  (segment (start 108.524619 86.710204) (end 108.45543 86.718) (width 0.11) (layer "F.Cu") (net 148))
  (segment (start 108.524619 85.185795) (end 108.590338 85.208791) (width 0.11) (layer "F.Cu") (net 148))
  (segment (start 108.73557 87.421976) (end 108.698526 87.480931) (width 0.11) (layer "F.Cu") (net 148))
  (segment (start 108.45543 86.058) (end 108.524619 86.065795) (width 0.11) (layer "F.Cu") (net 148))
  (segment (start 108.73557 86.541976) (end 108.698526 86.600931) (width 0.11) (layer "F.Cu") (net 148))
  (segment (start 107.613637 86.759416) (end 107.600532 86.780272) (width 0.11) (layer "F.Cu") (net 148))
  (segment (start 108.698526 86.175068) (end 108.73557 86.234023) (width 0.11) (layer "F.Cu") (net 148))
  (segment (start 108.766361 86.407068) (end 108.758566 86.476257) (width 0.11) (layer "F.Cu") (net 148))
  (segment (start 107.699639 85.178) (end 108.45543 85.178) (width 0.11) (layer "F.Cu") (net 148))
  (segment (start 108.766361 86.368931) (end 108.766361 86.407068) (width 0.11) (layer "F.Cu") (net 148))
  (segment (start 108.178 84.647068) (end 108.170204 84.716257) (width 0.11) (layer "F.Cu") (net 148))
  (segment (start 108.147208 84.781976) (end 108.110164 84.840931) (width 0.11) (layer "F.Cu") (net 148))
  (segment (start 108.649293 85.245835) (end 108.698526 85.295068) (width 0.11) (layer "F.Cu") (net 148))
  (segment (start 107.651911 86.927106) (end 107.675161 86.935242) (width 0.11) (layer "F.Cu") (net 148))
  (segment (start 107.600532 85.020272) (end 107.592396 85.043522) (width 0.11) (layer "F.Cu") (net 148))
  (segment (start 107.631055 86.034001) (end 107.651911 86.047106) (width 0.11) (layer "F.Cu") (net 148))
  (segment (start 108.201999 87.639416) (end 108.188894 87.660272) (width 0.11) (layer "F.Cu") (net 148))
  (segment (start 107.613637 85.136583) (end 107.631055 85.154001) (width 0.11) (layer "F.Cu") (net 148))
  (segment (start 107.600532 85.900272) (end 107.592396 85.923522) (width 0.11) (layer "F.Cu") (net 148))
  (segment (start 107.675161 85.175242) (end 107.699639 85.178) (width 0.11) (layer "F.Cu") (net 148))
  (segment (start 107.592396 85.092477) (end 107.600532 85.115727) (width 0.11) (layer "F.Cu") (net 148))
  (segment (start 108.758566 87.179742) (end 108.766361 87.248931) (width 0.11) (layer "F.Cu") (net 148))
  (segment (start 107.675161 86.935242) (end 107.699639 86.938) (width 0.11) (layer "F.Cu") (net 148))
  (segment (start 108.649293 85.770164) (end 108.590338 85.807208) (width 0.11) (layer "F.Cu") (net 148))
  (segment (start 105.31 92.882851) (end 105.45 93.022851) (width 0.11) (layer "F.Cu") (net 148))
  (segment (start 108.060931 84.890164) (end 108.001976 84.927208) (width 0.11) (layer "F.Cu") (net 148))
  (segment (start 108.590338 86.968791) (end 108.649293 87.005835) (width 0.11) (layer "F.Cu") (net 148))
  (segment (start 107.613637 85.879416) (end 107.600532 85.900272) (width 0.11) (layer "F.Cu") (net 148))
  (segment (start 108.45543 85.838) (end 107.699639 85.838) (width 0.11) (layer "F.Cu") (net 148))
  (segment (start 108.001976 84.927208) (end 107.936257 84.950204) (width 0.11) (layer "F.Cu") (net 148))
  (segment (start 108.649293 87.530164) (end 108.590338 87.567208) (width 0.11) (layer "F.Cu") (net 148))
  (segment (start 107.699639 86.058) (end 108.45543 86.058) (width 0.11) (layer "F.Cu") (net 148))
  (segment (start 108.45543 87.598) (end 108.288 87.598) (width 0.11) (layer "F.Cu") (net 148))
  (segment (start 107.592396 86.852477) (end 107.600532 86.875727) (width 0.11) (layer "F.Cu") (net 148))
  (segment (start 108.758566 86.299742) (end 108.766361 86.368931) (width 0.11) (layer "F.Cu") (net 148))
  (segment (start 107.589639 85.948) (end 107.592396 85.972477) (width 0.11) (layer "F.Cu") (net 148))
  (segment (start 100.662144 85.766621) (end 100.665904 85.8) (width 0.11) (layer "F.Cu") (net 149))
  (segment (start 100.213761 85.533378) (end 100.224855 85.565082) (width 0.11) (layer "F.Cu") (net 149))
  (segment (start 100.326622 85.95376) (end 100.294918 85.964854) (width 0.11) (layer "F.Cu") (net 149))
  (segment (start 100.21 84.9) (end 100.213761 84.933378) (width 0.11) (layer "F.Cu") (net 149))
  (segment (start 100.662144 84.633378) (end 100.65105 84.665082) (width 0.11) (layer "F.Cu") (net 149))
  (segment (start 100.294918 87.764854) (end 100.266477 87.782725) (width 0.11) (layer "F.Cu") (net 149))
  (segment (start 100.213761 84.866621) (end 100.21 84.9) (width 0.11) (layer "F.Cu") (net 149))
  (segment (start 100.633179 87.506476) (end 100.65105 87.534917) (width 0.11) (layer "F.Cu") (net 149))
  (segment (start 100.768706 89.288257) (end 100.74571 89.353976) (width 0.11) (layer "F.Cu") (net 149))
  (segment (start 100.242726 87.806476) (end 100.224855 87.834917) (width 0.11) (layer "F.Cu") (net 149))
  (segment (start 100.74571 89.046023) (end 100.768706 89.111742) (width 0.11) (layer "F.Cu") (net 149))
  (segment (start 100.294918 84.764854) (end 100.266477 84.782725) (width 0.11) (layer "F.Cu") (net 149))
  (segment (start 100.092931 88.582164) (end 100.033976 88.619208) (width 0.11) (layer "F.Cu") (net 149))
  (segment (start 100.662144 86.966621) (end 100.665904 87) (width 0.11) (layer "F.Cu") (net 149))
  (segment (start 100.662144 85.233378) (end 100.65105 85.265082) (width 0.11) (layer "F.Cu") (net 149))
  (segment (start 100.65105 85.734917) (end 100.662144 85.766621) (width 0.11) (layer "F.Cu") (net 149))
  (segment (start 100.580987 85.064854) (end 100.609428 85.082725) (width 0.11) (layer "F.Cu") (net 149))
  (segment (start 100.549283 87.45376) (end 100.580987 87.464854) (width 0.11) (layer "F.Cu") (net 149))
  (segment (start 100.21 85.5) (end 100.213761 85.533378) (width 0.11) (layer "F.Cu") (net 149))
  (segment (start 100.609428 86.882725) (end 100.633179 86.906476) (width 0.11) (layer "F.Cu") (net 149))
  (segment (start 100.36 87.75) (end 100.326622 87.75376) (width 0.11) (layer "F.Cu") (net 149))
  (segment (start 99.654392 88.712272) (end 99.646256 88.735522) (width 0.11) (layer "F.Cu") (net 149))
  (segment (start 100.776501 89.180931) (end 100.776501 89.219068) (width 0.11) (layer "F.Cu") (net 149))
  (segment (start 100.242726 85.406476) (end 100.224855 85.434917) (width 0.11) (layer "F.Cu") (net 149))
  (segment (start 100.776501 89.219068) (end 100.768706 89.288257) (width 0.11) (layer "F.Cu") (net 149))
  (segment (start 100.266477 87.417274) (end 100.294918 87.435145) (width 0.11) (layer "F.Cu") (net 149))
  (segment (start 100.21 84.3) (end 100.213761 84.333378) (width 0.11) (layer "F.Cu") (net 149))
  (segment (start 99.684915 89.553998) (end 99.667497 89.571416) (width 0.11) (layer "F.Cu") (net 149))
  (segment (start 100.633179 87.093523) (end 100.609428 87.117274) (width 0.11) (layer "F.Cu") (net 149))
  (segment (start 100.609428 85.917274) (end 100.580987 85.935145) (width 0.11) (layer "F.Cu") (net 149))
  (segment (start 101.31 92.882851) (end 101.45 93.022851) (width 0.11) (layer "F.Cu") (net 149))
  (segment (start 100.662144 87.033378) (end 100.65105 87.065082) (width 0.11) (layer "F.Cu") (net 149))
  (segment (start 99.753499 88.87) (end 100.46557 88.87) (width 0.11) (layer "F.Cu") (net 149))
  (segment (start 100.224855 87.365082) (end 100.242726 87.393523) (width 0.11) (layer "F.Cu") (net 149))
  (segment (start 100.242726 86.006476) (end 100.224855 86.034917) (width 0.11) (layer "F.Cu") (net 149))
  (segment (start 100.549283 87.746239) (end 100.515904 87.75) (width 0.11) (layer "F.Cu") (net 149))
  (segment (start 100.609428 85.317274) (end 100.580987 85.335145) (width 0.11) (layer "F.Cu") (net 149))
  (segment (start 100.266477 84.417274) (end 100.294918 84.435145) (width 0.11) (layer "F.Cu") (net 149))
  (segment (start 100.294918 85.964854) (end 100.266477 85.982725) (width 0.11) (layer "F.Cu") (net 149))
  (segment (start 99.729021 88.652757) (end 99.705771 88.660893) (width 0.11) (layer "F.Cu") (net 149))
  (segment (start 100.515904 85.95) (end 100.36 85.95) (width 0.11) (layer "F.Cu") (net 149))
  (segment (start 100.294918 86.235145) (end 100.326622 86.246239) (width 0.11) (layer "F.Cu") (net 149))
  (segment (start 100.266477 85.017274) (end 100.294918 85.035145) (width 0.11) (layer "F.Cu") (net 149))
  (segment (start 100.224855 86.165082) (end 100.242726 86.193523) (width 0.11) (layer "F.Cu") (net 149))
  (segment (start 100.515904 84.45) (end 100.549283 84.45376) (width 0.11) (layer "F.Cu") (net 149))
  (segment (start 100.142164 89.867068) (end 100.179208 89.926023) (width 0.11) (layer "F.Cu") (net 149))
  (segment (start 100.36 85.65) (end 100.515904 85.65) (width 0.11) (layer "F.Cu") (net 149))
  (segment (start 100.515904 86.25) (end 100.549283 86.25376) (width 0.11) (layer "F.Cu") (net 149))
  (segment (start 100.65105 86.934917) (end 100.662144 86.966621) (width 0.11) (layer "F.Cu") (net 149))
  (segment (start 100.224855 84.834917) (end 100.213761 84.866621) (width 0.11) (layer "F.Cu") (net 149))
  (segment (start 100.662144 84.566621) (end 100.665904 84.6) (width 0.11) (layer "F.Cu") (net 149))
  (segment (start 100.224855 87.234917) (end 100.213761 87.266621) (width 0.11) (layer "F.Cu") (net 149))
  (segment (start 100.213761 87.266621) (end 100.21 87.3) (width 0.11) (layer "F.Cu") (net 149))
  (segment (start 100.549283 86.85376) (end 100.580987 86.864854) (width 0.11) (layer "F.Cu") (net 149))
  (segment (start 100.665904 87.6) (end 100.662144 87.633378) (width 0.11) (layer "F.Cu") (net 149))
  (segment (start 100.242726 87.393523) (end 100.266477 87.417274) (width 0.11) (layer "F.Cu") (net 149))
  (segment (start 100.36 86.25) (end 100.515904 86.25) (width 0.11) (layer "F.Cu") (net 149))
  (segment (start 100.326622 84.75376) (end 100.294918 84.764854) (width 0.11) (layer "F.Cu") (net 149))
  (segment (start 100.662144 87.566621) (end 100.665904 87.6) (width 0.11) (layer "F.Cu") (net 149))
  (segment (start 100.21 86.1) (end 100.213761 86.133378) (width 0.11) (layer "F.Cu") (net 149))
  (segment (start 100.580987 84.464854) (end 100.609428 84.482725) (width 0.11) (layer "F.Cu") (net 149))
  (segment (start 100.213761 87.866621) (end 100.21 87.9) (width 0.11) (layer "F.Cu") (net 149))
  (segment (start 99.667497 89.708583) (end 99.684915 89.726001) (width 0.11) (layer "F.Cu") (net 149))
  (segment (start 100.224855 84.965082) (end 100.242726 84.993523) (width 0.11) (layer "F.Cu") (net 149))
  (segment (start 100.609428 86.517274) (end 100.580987 86.535145) (width 0.11) (layer "F.Cu") (net 149))
  (segment (start 100.242726 86.193523) (end 100.266477 86.217274) (width 0.11) (layer "F.Cu") (net 149))
  (segment (start 100.213761 86.133378) (end 100.224855 86.165082) (width 0.11) (layer "F.Cu") (net 149))
  (segment (start 100.213761 84.333378) (end 100.224855 84.365082) (width 0.11) (layer "F.Cu") (net 149))
  (segment (start 100.36 84.45) (end 100.515904 84.45) (width 0.11) (layer "F.Cu") (net 149))
  (segment (start 100.326622 86.846239) (end 100.36 86.85) (width 0.11) (layer "F.Cu") (net 149))
  (segment (start 99.667497 88.828583) (end 99.684915 88.846001) (width 0.11) (layer "F.Cu") (net 149))
  (segment (start 100.202204 88.408257) (end 100.179208 88.473976) (width 0.11) (layer "F.Cu") (net 149))
  (segment (start 100.549283 84.746239) (end 100.515904 84.75) (width 0.11) (layer "F.Cu") (net 149))
  (segment (start 100.580987 86.864854) (end 100.609428 86.882725) (width 0.11) (layer "F.Cu") (net 149))
  (segment (start 100.294918 85.035145) (end 100.326622 85.046239) (width 0.11) (layer "F.Cu") (net 149))
  (segment (start 99.667497 88.691416) (end 99.654392 88.712272) (width 0.11) (layer "F.Cu") (net 149))
  (segment (start 100.224855 87.834917) (end 100.213761 87.866621) (width 0.11) (layer "F.Cu") (net 149))
  (segment (start 99.968257 88.642204) (end 99.899068 88.65) (width 0.11) (layer "F.Cu") (net 149))
  (segment (start 100.224855 85.565082) (end 100.242726 85.593523) (width 0.11) (layer "F.Cu") (net 149))
  (segment (start 100.633179 85.106476) (end 100.65105 85.134917) (width 0.11) (layer "F.Cu") (net 149))
  (segment (start 100.633179 85.893523) (end 100.609428 85.917274) (width 0.11) (layer "F.Cu") (net 149))
  (segment (start 100.242726 87.206476) (end 100.224855 87.234917) (width 0.11) (layer "F.Cu") (net 149))
  (segment (start 100.662144 86.433378) (end 100.65105 86.465082) (width 0.11) (layer "F.Cu") (net 149))
  (segment (start 100.534759 88.877795) (end 100.600478 88.900791) (width 0.11) (layer "F.Cu") (net 149))
  (segment (start 100.21 84.126) (end 100.21 84.3) (width 0.11) (layer "F.Cu") (net 149))
  (segment (start 100.213761 86.066621) (end 100.21 86.1) (width 0.11) (layer "F.Cu") (net 149))
  (segment (start 100.21 86.7) (end 100.213761 86.733378) (width 0.11) (layer "F.Cu") (net 149))
  (segment (start 100.580987 87.735145) (end 100.549283 87.746239) (width 0.11) (layer "F.Cu") (net 149))
  (segment (start 100.580987 85.335145) (end 100.549283 85.346239) (width 0.11) (layer "F.Cu") (net 149))
  (segment (start 100.213761 87.333378) (end 100.224855 87.365082) (width 0.11) (layer "F.Cu") (net 149))
  (segment (start 100.65105 86.334917) (end 100.662144 86.366621) (width 0.11) (layer "F.Cu") (net 149))
  (segment (start 100.326622 87.446239) (end 100.36 87.45) (width 0.11) (layer "F.Cu") (net 149))
  (segment (start 100.224855 86.034917) (end 100.213761 86.066621) (width 0.11) (layer "F.Cu") (net 149))
  (segment (start 100.600478 88.900791) (end 100.659433 88.937835) (width 0.11) (layer "F.Cu") (net 149))
  (segment (start 99.729021 88.867242) (end 99.753499 88.87) (width 0.11) (layer "F.Cu") (net 149))
  (segment (start 100.74571 89.353976) (end 100.708666 89.412931) (width 0.11) (layer "F.Cu") (net 149))
  (segment (start 100.21 88.339068) (end 100.202204 88.408257) (width 0.11) (layer "F.Cu") (net 149))
  (segment (start 99.729021 89.747242) (end 99.753499 89.75) (width 0.11) (layer "F.Cu") (net 149))
  (segment (start 100.659433 89.462164) (end 100.600478 89.499208) (width 0.11) (layer "F.Cu") (net 149))
  (segment (start 100.768706 89.111742) (end 100.776501 89.180931) (width 0.11) (layer "F.Cu") (net 149))
  (segment (start 100.179208 89.926023) (end 100.202204 89.991742) (width 0.11) (layer "F.Cu") (net 149))
  (segment (start 100.213761 86.733378) (end 100.224855 86.765082) (width 0.11) (layer "F.Cu") (net 149))
  (segment (start 100.242726 85.593523) (end 100.266477 85.617274) (width 0.11) (layer "F.Cu") (net 149))
  (segment (start 99.899068 89.75) (end 99.968257 89.757795) (width 0.11) (layer "F.Cu") (net 149))
  (segment (start 100.609428 84.717274) (end 100.580987 84.735145) (width 0.11) (layer "F.Cu") (net 149))
  (segment (start 100.36 85.35) (end 100.326622 85.35376) (width 0.11) (layer "F.Cu") (net 149))
  (segment (start 100.294918 86.835145) (end 100.326622 86.846239) (width 0.11) (layer "F.Cu") (net 149))
  (segment (start 100.326622 84.446239) (end 100.36 84.45) (width 0.11) (layer "F.Cu") (net 149))
  (segment (start 100.294918 86.564854) (end 100.266477 86.582725) (width 0.11) (layer "F.Cu") (net 149))
  (segment (start 99.646256 89.664477) (end 99.654392 89.687727) (width 0.11) (layer "F.Cu") (net 149))
  (segment (start 100.36 85.05) (end 100.515904 85.05) (width 0.11) (layer "F.Cu") (net 149))
  (segment (start 100.21 90.060931) (end 100.21 90.444436) (width 0.11) (layer "F.Cu") (net 149))
  (segment (start 100.515904 87.45) (end 100.549283 87.45376) (width 0.11) (layer "F.Cu") (net 149))
  (segment (start 100.609428 87.482725) (end 100.633179 87.506476) (width 0.11) (layer "F.Cu") (net 149))
  (segment (start 100.224855 86.765082) (end 100.242726 86.793523) (width 0.11) (layer "F.Cu") (net 149))
  (segment (start 100.242726 86.606476) (end 100.224855 86.634917) (width 0.11) (layer "F.Cu") (net 149))
  (segment (start 100.242726 86.793523) (end 100.266477 86.817274) (width 0.11) (layer "F.Cu") (net 149))
  (segment (start 100.665904 85.2) (end 100.662144 85.233378) (width 0.11) (layer "F.Cu") (net 149))
  (segment (start 100.600478 89.499208) (end 100.534759 89.522204) (width 0.11) (layer "F.Cu") (net 149))
  (segment (start 100.224855 85.434917) (end 100.213761 85.466621) (width 0.11) (layer "F.Cu") (net 149))
  (segment (start 100.549283 85.05376) (end 100.580987 85.064854) (width 0.11) (layer "F.Cu") (net 149))
  (segment (start 100.549283 84.45376) (end 100.580987 84.464854) (width 0.11) (layer "F.Cu") (net 149))
  (segment (start 100.266477 86.582725) (end 100.242726 86.606476) (width 0.11) (layer "F.Cu") (net 149))
  (segment (start 100.515904 84.75) (end 100.36 84.75) (width 0.11) (layer "F.Cu") (net 149))
  (segment (start 100.202204 89.991742) (end 100.21 90.060931) (width 0.11) (layer "F.Cu") (net 149))
  (segment (start 99.643499 89.64) (end 99.646256 89.664477) (width 0.11) (layer "F.Cu") (net 149))
  (segment (start 99.684915 88.673998) (end 99.667497 88.691416) (width 0.11) (layer "F.Cu") (net 149))
  (segment (start 100.515904 85.05) (end 100.549283 85.05376) (width 0.11) (layer "F.Cu") (net 149))
  (segment (start 99.643499 88.76) (end 99.646256 88.784477) (width 0.11) (layer "F.Cu") (net 149))
  (segment (start 99.753499 89.75) (end 99.899068 89.75) (width 0.11) (layer "F.Cu") (net 149))
  (segment (start 100.326622 85.646239) (end 100.36 85.65) (width 0.11) (layer "F.Cu") (net 149))
  (segment (start 100.609428 87.117274) (end 100.580987 87.135145) (width 0.11) (layer "F.Cu") (net 149))
  (segment (start 100.665904 87) (end 100.662144 87.033378) (width 0.11) (layer "F.Cu") (net 149))
  (segment (start 100.65105 85.134917) (end 100.662144 85.166621) (width 0.11) (layer "F.Cu") (net 149))
  (segment (start 100.213761 84.933378) (end 100.224855 84.965082) (width 0.11) (layer "F.Cu") (net 149))
  (segment (start 100.65105 87.065082) (end 100.633179 87.093523) (width 0.11) (layer "F.Cu") (net 149))
  (segment (start 100.665904 86.4) (end 100.662144 86.433378) (width 0.11) (layer "F.Cu") (net 149))
  (segment (start 100.549283 85.946239) (end 100.515904 85.95) (width 0.11) (layer "F.Cu") (net 149))
  (segment (start 100.549283 86.25376) (end 100.580987 86.264854) (width 0.11) (layer "F.Cu") (net 149))
  (segment (start 99.705771 88.660893) (end 99.684915 88.673998) (width 0.11) (layer "F.Cu") (net 149))
  (segment (start 100.224855 86.634917) (end 100.213761 86.666621) (width 0.11) (layer "F.Cu") (net 149))
  (segment (start 100.515904 85.35) (end 100.36 85.35) (width 0.11) (layer "F.Cu") (net 149))
  (segment (start 100.213761 85.466621) (end 100.21 85.5) (width 0.11) (layer "F.Cu") (net 149))
  (segment (start 99.705771 88.859106) (end 99.729021 88.867242) (width 0.11) (layer "F.Cu") (net 149))
  (segment (start 100.549283 85.65376) (end 100.580987 85.664854) (width 0.11) (layer "F.Cu") (net 149))
  (segment (start 100.65105 86.465082) (end 100.633179 86.493523) (width 0.11) (layer "F.Cu") (net 149))
  (segment (start 100.515904 86.85) (end 100.549283 86.85376) (width 0.11) (layer "F.Cu") (net 149))
  (segment (start 100.633179 86.906476) (end 100.65105 86.934917) (width 0.11) (layer "F.Cu") (net 149))
  (segment (start 100.65105 84.665082) (end 100.633179 84.693523) (width 0.11) (layer "F.Cu") (net 149))
  (segment (start 100.609428 85.082725) (end 100.633179 85.106476) (width 0.11) (layer "F.Cu") (net 149))
  (segment (start 100.266477 86.217274) (end 100.294918 86.235145) (width 0.11) (layer "F.Cu") (net 149))
  (segment (start 100.266477 84.782725) (end 100.242726 84.806476) (width 0.11) (layer "F.Cu") (net 149))
  (segment (start 100.580987 86.535145) (end 100.549283 86.546239) (width 0.11) (layer "F.Cu") (net 149))
  (segment (start 100.326622 86.246239) (end 100.36 86.25) (width 0.11) (layer "F.Cu") (net 149))
  (segment (start 100.633179 85.293523) (end 100.609428 85.317274) (width 0.11) (layer "F.Cu") (net 149))
  (segment (start 100.515904 87.15) (end 100.36 87.15) (width 0.11) (layer "F.Cu") (net 149))
  (segment (start 100.266477 86.817274) (end 100.294918 86.835145) (width 0.11) (layer "F.Cu") (net 149))
  (segment (start 100.092931 89.817835) (end 100.142164 89.867068) (width 0.11) (layer "F.Cu") (net 149))
  (segment (start 100.266477 85.382725) (end 100.242726 85.406476) (width 0.11) (layer "F.Cu") (net 149))
  (segment (start 100.36 86.85) (end 100.515904 86.85) (width 0.11) (layer "F.Cu") (net 149))
  (segment (start 100.633179 84.506476) (end 100.65105 84.534917) (width 0.11) (layer "F.Cu") (net 149))
  (segment (start 100.033976 89.780791) (end 100.092931 89.817835) (width 0.11) (layer "F.Cu") (net 149))
  (segment (start 100.662144 87.633378) (end 100.65105 87.665082) (width 0.11) (layer "F.Cu") (net 149))
  (segment (start 100.266477 87.782725) (end 100.242726 87.806476) (width 0.11) (layer "F.Cu") (net 149))
  (segment (start 99.654392 89.592272) (end 99.646256 89.615522) (width 0.11) (layer "F.Cu") (net 149))
  (segment (start 99.654392 88.807727) (end 99.667497 88.828583) (width 0.11) (layer "F.Cu") (net 149))
  (segment (start 100.633179 86.493523) (end 100.609428 86.517274) (width 0.11) (layer "F.Cu") (net 149))
  (segment (start 100.633179 86.306476) (end 100.65105 86.334917) (width 0.11) (layer "F.Cu") (net 149))
  (segment (start 100.36 86.55) (end 100.326622 86.55376) (width 0.11) (layer "F.Cu") (net 149))
  (segment (start 100.609428 85.682725) (end 100.633179 85.706476) (width 0.11) (layer "F.Cu") (net 149))
  (segment (start 99.729021 89.532757) (end 99.705771 89.540893) (width 0.11) (layer "F.Cu") (net 149))
  (segment (start 100.21 87.9) (end 100.21 88.339068) (width 0.11) (layer "F.Cu") (net 149))
  (segment (start 99.646256 88.784477) (end 99.654392 88.807727) (width 0.11) (layer "F.Cu") (net 149))
  (segment (start 100.294918 87.435145) (end 100.326622 87.446239) (width 0.11) (layer "F.Cu") (net 149))
  (segment (start 100.326622 86.55376) (end 100.294918 86.564854) (width 0.11) (layer "F.Cu") (net 149))
  (segment (start 100.242726 84.806476) (end 100.224855 84.834917) (width 0.11) (layer "F.Cu") (net 149))
  (segment (start 99.646256 89.615522) (end 99.643499 89.64) (width 0.11) (layer "F.Cu") (net 149))
  (segment (start 100.515904 87.75) (end 100.36 87.75) (width 0.11) (layer "F.Cu") (net 149))
  (segment (start 99.705771 89.540893) (end 99.684915 89.553998) (width 0.11) (layer "F.Cu") (net 149))
  (segment (start 100.549283 85.346239) (end 100.515904 85.35) (width 0.11) (layer "F.Cu") (net 149))
  (segment (start 100.665904 85.8) (end 100.662144 85.833378) (width 0.11) (layer "F.Cu") (net 149))
  (segment (start 100.142164 88.532931) (end 100.092931 88.582164) (width 0.11) (layer "F.Cu") (net 149))
  (segment (start 100.580987 87.464854) (end 100.609428 87.482725) (width 0.11) (layer "F.Cu") (net 149))
  (segment (start 100.21 87.3) (end 100.213761 87.333378) (width 0.11) (layer "F.Cu") (net 149))
  (segment (start 100.65105 85.865082) (end 100.633179 85.893523) (width 0.11) (layer "F.Cu") (net 149))
  (segment (start 100.549283 87.146239) (end 100.515904 87.15) (width 0.11) (layer "F.Cu") (net 149))
  (segment (start 100.36 87.45) (end 100.515904 87.45) (width 0.11) (layer "F.Cu") (net 149))
  (segment (start 99.684915 88.846001) (end 99.705771 88.859106) (width 0.11) (layer "F.Cu") (net 149))
  (segment (start 100.633179 84.693523) (end 100.609428 84.717274) (width 0.11) (layer "F.Cu") (net 149))
  (segment (start 100.36 85.95) (end 100.326622 85.95376) (width 0.11) (layer "F.Cu") (net 149))
  (segment (start 99.646256 88.735522) (end 99.643499 88.76) (width 0.11) (layer "F.Cu") (net 149))
  (segment (start 100.515904 85.65) (end 100.549283 85.65376) (width 0.11) (layer "F.Cu") (net 149))
  (segment (start 100.242726 84.993523) (end 100.266477 85.017274) (width 0.11) (layer "F.Cu") (net 149))
  (segment (start 100.580987 84.735145) (end 100.549283 84.746239) (width 0.11) (layer "F.Cu") (net 149))
  (segment (start 100.266477 85.982725) (end 100.242726 86.006476) (width 0.11) (layer "F.Cu") (net 149))
  (segment (start 100.708666 88.987068) (end 100.74571 89.046023) (width 0.11) (layer "F.Cu") (net 149))
  (segment (start 100.609428 87.717274) (end 100.580987 87.735145) (width 0.11) (layer "F.Cu") (net 149))
  (segment (start 100.609428 84.482725) (end 100.633179 84.506476) (width 0.11) (layer "F.Cu") (net 149))
  (segment (start 100.609428 86.282725) (end 100.633179 86.306476) (width 0.11) (layer "F.Cu") (net 149))
  (segment (start 100.36 87.15) (end 100.326622 87.15376) (width 0.11) (layer "F.Cu") (net 149))
  (segment (start 100.580987 87.135145) (end 100.549283 87.146239) (width 0.11) (layer "F.Cu") (net 149))
  (segment (start 100.326622 87.15376) (end 100.294918 87.164854) (width 0.11) (layer "F.Cu") (net 149))
  (segment (start 100.549283 86.546239) (end 100.515904 86.55) (width 0.11) (layer "F.Cu") (net 149))
  (segment (start 100.633179 87.693523) (end 100.609428 87.717274) (width 0.11) (layer "F.Cu") (net 149))
  (segment (start 100.033976 88.619208) (end 99.968257 88.642204) (width 0.11) (layer "F.Cu") (net 149))
  (segment (start 100.46557 89.53) (end 99.753499 89.53) (width 0.11) (layer "F.Cu") (net 149))
  (segment (start 100.580987 86.264854) (end 100.609428 86.282725) (width 0.11) (layer "F.Cu") (net 149))
  (segment (start 100.294918 84.435145) (end 100.326622 84.446239) (width 0.11) (layer "F.Cu") (net 149))
  (segment (start 100.266477 85.617274) (end 100.294918 85.635145) (width 0.11) (layer "F.Cu") (net 149))
  (segment (start 100.242726 84.393523) (end 100.266477 84.417274) (width 0.11) (layer "F.Cu") (net 149))
  (segment (start 100.65105 87.665082) (end 100.633179 87.693523) (width 0.11) (layer "F.Cu") (net 149))
  (segment (start 100.21 90.444436) (end 101.31 91.544436) (width 0.11) (layer "F.Cu") (net 149))
  (segment (start 100.534759 89.522204) (end 100.46557 89.53) (width 0.11) (layer "F.Cu") (net 149))
  (segment (start 100.266477 87.182725) (end 100.242726 87.206476) (width 0.11) (layer "F.Cu") (net 149))
  (segment (start 100.326622 85.046239) (end 100.36 85.05) (width 0.11) (layer "F.Cu") (net 149))
  (segment (start 100.515904 86.55) (end 100.36 86.55) (width 0.11) (layer "F.Cu") (net 149))
  (segment (start 99.753499 89.53) (end 99.729021 89.532757) (width 0.11) (layer "F.Cu") (net 149))
  (segment (start 100.665904 84.6) (end 100.662144 84.633378) (width 0.11) (layer "F.Cu") (net 149))
  (segment (start 100.294918 85.635145) (end 100.326622 85.646239) (width 0.11) (layer "F.Cu") (net 149))
  (segment (start 100.179208 88.473976) (end 100.142164 88.532931) (width 0.11) (layer "F.Cu") (net 149))
  (segment (start 99.899068 88.65) (end 99.753499 88.65) (width 0.11) (layer "F.Cu") (net 149))
  (segment (start 100.294918 87.164854) (end 100.266477 87.182725) (width 0.11) (layer "F.Cu") (net 149))
  (segment (start 100.662144 86.366621) (end 100.665904 86.4) (width 0.11) (layer "F.Cu") (net 149))
  (segment (start 99.705771 89.739106) (end 99.729021 89.747242) (width 0.11) (layer "F.Cu") (net 149))
  (segment (start 100.633179 85.706476) (end 100.65105 85.734917) (width 0.11) (layer "F.Cu") (net 149))
  (segment (start 100.65105 85.265082) (end 100.633179 85.293523) (width 0.11) (layer "F.Cu") (net 149))
  (segment (start 100.956 83.38) (end 100.21 84.126) (width 0.11) (layer "F.Cu") (net 149))
  (segment (start 99.667497 89.571416) (end 99.654392 89.592272) (width 0.11) (layer "F.Cu") (net 149))
  (segment (start 100.662144 85.166621) (end 100.665904 85.2) (width 0.11) (layer "F.Cu") (net 149))
  (segment (start 100.326622 87.75376) (end 100.294918 87.764854) (width 0.11) (layer "F.Cu") (net 149))
  (segment (start 100.46557 88.87) (end 100.534759 88.877795) (width 0.11) (layer "F.Cu") (net 149))
  (segment (start 100.36 84.75) (end 100.326622 84.75376) (width 0.11) (layer "F.Cu") (net 149))
  (segment (start 99.753499 88.65) (end 99.729021 88.652757) (width 0.11) (layer "F.Cu") (net 149))
  (segment (start 100.65105 87.534917) (end 100.662144 87.566621) (width 0.11) (layer "F.Cu") (net 149))
  (segment (start 100.326622 85.35376) (end 100.294918 85.364854) (width 0.11) (layer "F.Cu") (net 149))
  (segment (start 100.659433 88.937835) (end 100.708666 88.987068) (width 0.11) (layer "F.Cu") (net 149))
  (segment (start 100.708666 89.412931) (end 100.659433 89.462164) (width 0.11) (layer "F.Cu") (net 149))
  (segment (start 100.213761 86.666621) (end 100.21 86.7) (width 0.11) (layer "F.Cu") (net 149))
  (segment (start 100.580987 85.935145) (end 100.549283 85.946239) (width 0.11) (layer "F.Cu") (net 149))
  (segment (start 99.684915 89.726001) (end 99.705771 89.739106) (width 0.11) (layer "F.Cu") (net 149))
  (segment (start 99.968257 89.757795) (end 100.033976 89.780791) (width 0.11) (layer "F.Cu") (net 149))
  (segment (start 100.224855 84.365082) (end 100.242726 84.393523) (width 0.11) (layer "F.Cu") (net 149))
  (segment (start 100.65105 84.534917) (end 100.662144 84.566621) (width 0.11) (layer "F.Cu") (net 149))
  (segment (start 99.654392 89.687727) (end 99.667497 89.708583) (width 0.11) (layer "F.Cu") (net 149))
  (segment (start 100.580987 85.664854) (end 100.609428 85.682725) (width 0.11) (layer "F.Cu") (net 149))
  (segment (start 100.294918 85.364854) (end 100.266477 85.382725) (width 0.11) (layer "F.Cu") (net 149))
  (segment (start 100.662144 85.833378) (end 100.65105 85.865082) (width 0.11) (layer "F.Cu") (net 149))
  (segment (start 101.31 91.544436) (end 101.31 92.882851) (width 0.11) (layer "F.Cu") (net 149))
  (segment (start 105.51 79.81) (end 107.038 79.81) (width 0.11) (layer "F.Cu") (net 150))
  (segment (start 105.04 89.354436) (end 105.04 80.28) (width 0.11) (layer "F.Cu") (net 150))
  (segment (start 103.59 92.882851) (end 103.59 90.804436) (width 0.11) (layer "F.Cu") (net 150))
  (segment (start 105.04 80.28) (end 105.51 79.81) (width 0.11) (layer "F.Cu") (net 150))
  (segment (start 103.59 90.804436) (end 105.04 89.354436) (width 0.11) (layer "F.Cu") (net 150))
  (segment (start 103.45 93.022851) (end 103.59 92.882851) (width 0.11) (layer "F.Cu") (net 150))
  (segment (start 107.038 79.81) (end 108.068 80.84) (width 0.11) (layer "F.Cu") (net 150))
  (segment (start 108.134024 87.408791) (end 108.075069 87.445835) (width 0.11) (layer "F.Cu") (net 151))
  (segment (start 107.872477 84.735242) (end 107.848 84.738) (width 0.11) (layer "F.Cu") (net 151))
  (segment (start 107.947106 84.675727) (end 107.934001 84.696583) (width 0.11) (layer "F.Cu") (net 151))
  (segment (start 108.535468 85.555727) (end 108.522363 85.576583) (width 0.11) (layer "F.Cu") (net 151))
  (segment (start 107.545662 85.367208) (end 107.611381 85.390204) (width 0.11) (layer "F.Cu") (net 151))
  (segment (start 108.484089 86.487106) (end 108.460839 86.495242) (width 0.11) (layer "F.Cu") (net 151))
  (segment (start 108.484089 85.408893) (end 108.504945 85.421998) (width 0.11) (layer "F.Cu") (net 151))
  (segment (start 108.543604 86.412477) (end 108.535468 86.435727) (width 0.11) (layer "F.Cu") (net 151))
  (segment (start 107.486707 86.565835) (end 107.437474 86.615068) (width 0.11) (layer "F.Cu") (net 151))
  (segment (start 107.68057 87.158) (end 108.436361 87.158) (width 0.11) (layer "F.Cu") (net 151))
  (segment (start 108.436361 85.618) (end 107.68057 85.618) (width 0.11) (layer "F.Cu") (net 151))
  (segment (start 108.522363 87.336583) (end 108.504945 87.354001) (width 0.11) (layer "F.Cu") (net 151))
  (segment (start 108.436361 86.498) (end 107.68057 86.498) (width 0.11) (layer "F.Cu") (net 151))
  (segment (start 107.916583 84.714001) (end 107.895727 84.727106) (width 0.11) (layer "F.Cu") (net 151))
  (segment (start 108.504945 86.474001) (end 108.484089 86.487106) (width 0.11) (layer "F.Cu") (net 151))
  (segment (start 107.40043 85.794023) (end 107.377434 85.859742) (width 0.11) (layer "F.Cu") (net 151))
  (segment (start 108.460839 86.495242) (end 108.436361 86.498) (width 0.11) (layer "F.Cu") (net 151))
  (segment (start 107.377434 86.739742) (end 107.369639 86.808931) (width 0.11) (layer "F.Cu") (net 151))
  (segment (start 107.437474 87.040931) (end 107.486707 87.090164) (width 0.11) (layer "F.Cu") (net 151))
  (segment (start 107.377434 85.859742) (end 107.369639 85.928931) (width 0.11) (layer "F.Cu") (net 151))
  (segment (start 107.40043 86.981976) (end 107.437474 87.040931) (width 0.11) (layer "F.Cu") (net 151))
  (segment (start 108.504945 87.181998) (end 108.522363 87.199416) (width 0.11) (layer "F.Cu") (net 151))
  (segment (start 108.460839 87.160757) (end 108.484089 87.168893) (width 0.11) (layer "F.Cu") (net 151))
  (segment (start 107.545662 87.127208) (end 107.611381 87.150204) (width 0.11) (layer "F.Cu") (net 151))
  (segment (start 107.486707 86.210164) (end 107.545662 86.247208) (width 0.11) (layer "F.Cu") (net 151))
  (segment (start 108.504945 85.594001) (end 108.484089 85.607106) (width 0.11) (layer "F.Cu") (net 151))
  (segment (start 107.052 83.38) (end 107.958 84.286) (width 0.11) (layer "F.Cu") (net 151))
  (segment (start 107.377434 86.036257) (end 107.40043 86.101976) (width 0.11) (layer "F.Cu") (net 151))
  (segment (start 108.460839 85.400757) (end 108.484089 85.408893) (width 0.11) (layer "F.Cu") (net 151))
  (segment (start 107.369639 85.048931) (end 107.369639 85.087068) (width 0.11) (layer "F.Cu") (net 151))
  (segment (start 108.535468 86.340272) (end 108.543604 86.363522) (width 0.11) (layer "F.Cu") (net 151))
  (segment (start 108.484089 85.607106) (end 108.460839 85.615242) (width 0.11) (layer "F.Cu") (net 151))
  (segment (start 108.522363 86.319416) (end 108.535468 86.340272) (width 0.11) (layer "F.Cu") (net 151))
  (segment (start 108.543604 85.532477) (end 108.535468 85.555727) (width 0.11) (layer "F.Cu") (net 151))
  (segment (start 107.377434 84.979742) (end 107.369639 85.048931) (width 0.11) (layer "F.Cu") (net 151))
  (segment (start 108.522363 85.576583) (end 108.504945 85.594001) (width 0.11) (layer "F.Cu") (net 151))
  (segment (start 107.955242 84.652477) (end 107.947106 84.675727) (width 0.11) (layer "F.Cu") (net 151))
  (segment (start 107.369639 86.808931) (end 107.369639 86.847068) (width 0.11) (layer "F.Cu") (net 151))
  (segment (start 108.535468 87.220272) (end 108.543604 87.243522) (width 0.11) (layer "F.Cu") (net 151))
  (segment (start 107.437474 86.615068) (end 107.40043 86.674023) (width 0.11) (layer "F.Cu") (net 151))
  (segment (start 108.504945 87.354001) (end 108.484089 87.367106) (width 0.11) (layer "F.Cu") (net 151))
  (segment (start 107.437474 85.735068) (end 107.40043 85.794023) (width 0.11) (layer "F.Cu") (net 151))
  (segment (start 107.68057 86.278) (end 108.436361 86.278) (width 0.11) (layer "F.Cu") (net 151))
  (segment (start 108.543604 87.243522) (end 108.546361 87.268) (width 0.11) (layer "F.Cu") (net 151))
  (segment (start 108.546361 86.388) (end 108.543604 86.412477) (width 0.11) (layer "F.Cu") (net 151))
  (segment (start 107.545662 86.528791) (end 107.486707 86.565835) (width 0.11) (layer "F.Cu") (net 151))
  (segment (start 107.68057 84.738) (end 107.611381 84.745795) (width 0.11) (layer "F.Cu") (net 151))
  (segment (start 107.486707 85.685835) (end 107.437474 85.735068) (width 0.11) (layer "F.Cu") (net 151))
  (segment (start 108.460839 87.375242) (end 108.436361 87.378) (width 0.11) (layer "F.Cu") (net 151))
  (segment (start 108.436361 87.158) (end 108.460839 87.160757) (width 0.11) (layer "F.Cu") (net 151))
  (segment (start 108.522363 87.199416) (end 108.535468 87.220272) (width 0.11) (layer "F.Cu") (net 151))
  (segment (start 107.545662 84.768791) (end 107.486707 84.805835) (width 0.11) (layer "F.Cu") (net 151))
  (segment (start 108.484089 87.367106) (end 108.460839 87.375242) (width 0.11) (layer "F.Cu") (net 151))
  (segment (start 108.268932 87.378) (end 108.199743 87.385795) (width 0.11) (layer "F.Cu") (net 151))
  (segment (start 107.848 84.738) (end 107.68057 84.738) (width 0.11) (layer "F.Cu") (net 151))
  (segment (start 107.611381 87.150204) (end 107.68057 87.158) (width 0.11) (layer "F.Cu") (net 151))
  (segment (start 108.535468 86.435727) (end 108.522363 86.456583) (width 0.11) (layer "F.Cu") (net 151))
  (segment (start 108.460839 85.615242) (end 108.436361 85.618) (width 0.11) (layer "F.Cu") (net 151))
  (segment (start 107.611381 85.390204) (end 107.68057 85.398) (width 0.11) (layer "F.Cu") (net 151))
  (segment (start 108.522363 86.456583) (end 108.504945 86.474001) (width 0.11) (layer "F.Cu") (net 151))
  (segment (start 107.611381 86.505795) (end 107.545662 86.528791) (width 0.11) (layer "F.Cu") (net 151))
  (segment (start 108.075069 87.445835) (end 108.025836 87.495068) (width 0.11) (layer "F.Cu") (net 151))
  (segment (start 107.958 87.688931) (end 107.958 88.886436) (width 0.11) (layer "F.Cu") (net 151))
  (segment (start 107.369639 85.087068) (end 107.377434 85.156257) (width 0.11) (layer "F.Cu") (net 151))
  (segment (start 108.484089 87.168893) (end 108.504945 87.181998) (width 0.11) (layer "F.Cu") (net 151))
  (segment (start 107.958 84.286) (end 107.958 84.628) (width 0.11) (layer "F.Cu") (net 151))
  (segment (start 107.611381 84.745795) (end 107.545662 84.768791) (width 0.11) (layer "F.Cu") (net 151))
  (segment (start 108.504945 85.421998) (end 108.522363 85.439416) (width 0.11) (layer "F.Cu") (net 151))
  (segment (start 107.895727 84.727106) (end 107.872477 84.735242) (width 0.11) (layer "F.Cu") (net 151))
  (segment (start 107.68057 86.498) (end 107.611381 86.505795) (width 0.11) (layer "F.Cu") (net 151))
  (segment (start 108.436361 86.278) (end 108.460839 86.280757) (width 0.11) (layer "F.Cu") (net 151))
  (segment (start 108.543604 87.292477) (end 108.535468 87.315727) (width 0.11) (layer "F.Cu") (net 151))
  (segment (start 108.504945 86.301998) (end 108.522363 86.319416) (width 0.11) (layer "F.Cu") (net 151))
  (segment (start 107.437474 85.280931) (end 107.486707 85.330164) (width 0.11) (layer "F.Cu") (net 151))
  (segment (start 107.437474 84.855068) (end 107.40043 84.914023) (width 0.11) (layer "F.Cu") (net 151))
  (segment (start 107.369639 85.967068) (end 107.377434 86.036257) (width 0.11) (layer "F.Cu") (net 151))
  (segment (start 107.958 88.886436) (end 105.09 91.754436) (width 0.11) (layer "F.Cu") (net 151))
  (segment (start 107.40043 84.914023) (end 107.377434 84.979742) (width 0.11) (layer "F.Cu") (net 151))
  (segment (start 107.486707 87.090164) (end 107.545662 87.127208) (width 0.11) (layer "F.Cu") (net 151))
  (segment (start 108.546361 87.268) (end 108.543604 87.292477) (width 0.11) (layer "F.Cu") (net 151))
  (segment (start 107.545662 86.247208) (end 107.611381 86.270204) (width 0.11) (layer "F.Cu") (net 151))
  (segment (start 107.369639 85.928931) (end 107.369639 85.967068) (width 0.11) (layer "F.Cu") (net 151))
  (segment (start 107.40043 86.674023) (end 107.377434 86.739742) (width 0.11) (layer "F.Cu") (net 151))
  (segment (start 105.09 91.754436) (end 105.09 92.882851) (width 0.11) (layer "F.Cu") (net 151))
  (segment (start 108.535468 85.460272) (end 108.543604 85.483522) (width 0.11) (layer "F.Cu") (net 151))
  (segment (start 108.522363 85.439416) (end 108.535468 85.460272) (width 0.11) (layer "F.Cu") (net 151))
  (segment (start 107.437474 86.160931) (end 107.486707 86.210164) (width 0.11) (layer "F.Cu") (net 151))
  (segment (start 107.40043 86.101976) (end 107.437474 86.160931) (width 0.11) (layer "F.Cu") (net 151))
  (segment (start 107.934001 84.696583) (end 107.916583 84.714001) (width 0.11) (layer "F.Cu") (net 151))
  (segment (start 107.369639 86.847068) (end 107.377434 86.916257) (width 0.11) (layer "F.Cu") (net 151))
  (segment (start 105.09 92.882851) (end 104.95 93.022851) (width 0.11) (layer "F.Cu") (net 151))
  (segment (start 107.545662 85.648791) (end 107.486707 85.685835) (width 0.11) (layer "F.Cu") (net 151))
  (segment (start 108.543604 85.483522) (end 108.546361 85.508) (width 0.11) (layer "F.Cu") (net 151))
  (segment (start 107.988792 87.554023) (end 107.965796 87.619742) (width 0.11) (layer "F.Cu") (net 151))
  (segment (start 108.436361 85.398) (end 108.460839 85.400757) (width 0.11) (layer "F.Cu") (net 151))
  (segment (start 107.68057 85.618) (end 107.611381 85.625795) (width 0.11) (layer "F.Cu") (net 151))
  (segment (start 108.543604 86.363522) (end 108.546361 86.388) (width 0.11) (layer "F.Cu") (net 151))
  (segment (start 107.68057 85.398) (end 108.436361 85.398) (width 0.11) (layer "F.Cu") (net 151))
  (segment (start 108.436361 87.378) (end 108.268932 87.378) (width 0.11) (layer "F.Cu") (net 151))
  (segment (start 108.025836 87.495068) (end 107.988792 87.554023) (width 0.11) (layer "F.Cu") (net 151))
  (segment (start 107.40043 85.221976) (end 107.437474 85.280931) (width 0.11) (layer "F.Cu") (net 151))
  (segment (start 107.611381 85.625795) (end 107.545662 85.648791) (width 0.11) (layer "F.Cu") (net 151))
  (segment (start 107.377434 86.916257) (end 107.40043 86.981976) (width 0.11) (layer "F.Cu") (net 151))
  (segment (start 107.377434 85.156257) (end 107.40043 85.221976) (width 0.11) (layer "F.Cu") (net 151))
  (segment (start 108.484089 86.288893) (end 108.504945 86.301998) (width 0.11) (layer "F.Cu") (net 151))
  (segment (start 107.486707 84.805835) (end 107.437474 84.855068) (width 0.11) (layer "F.Cu") (net 151))
  (segment (start 107.965796 87.619742) (end 107.958 87.688931) (width 0.11) (layer "F.Cu") (net 151))
  (segment (start 108.199743 87.385795) (end 108.134024 87.408791) (width 0.11) (layer "F.Cu") (net 151))
  (segment (start 108.546361 85.508) (end 108.543604 85.532477) (width 0.11) (layer "F.Cu") (net 151))
  (segment (start 108.535468 87.315727) (end 108.522363 87.336583) (width 0.11) (layer "F.Cu") (net 151))
  (segment (start 107.486707 85.330164) (end 107.545662 85.367208) (width 0.11) (layer "F.Cu") (net 151))
  (segment (start 107.958 84.628) (end 107.955242 84.652477) (width 0.11) (layer "F.Cu") (net 151))
  (segment (start 108.460839 86.280757) (end 108.484089 86.288893) (width 0.11) (layer "F.Cu") (net 151))
  (segment (start 107.611381 86.270204) (end 107.68057 86.278) (width 0.11) (layer "F.Cu") (net 151))
  (segment (start 103.163844 86.885522) (end 103.166601 86.91) (width 0.11) (layer "F.Cu") (net 152))
  (segment (start 102.04419 87.503976) (end 102.081234 87.562931) (width 0.11) (layer "F.Cu") (net 152))
  (segment (start 102.013399 86.489068) (end 102.021194 86.558257) (width 0.11) (layer "F.Cu") (net 152))
  (segment (start 102.579106 87.742272) (end 102.587242 87.765522) (width 0.11) (layer "F.Cu") (net 152))
  (segment (start 102.130467 87.612164) (end 102.189422 87.649208) (width 0.11) (layer "F.Cu") (net 152))
  (segment (start 102.48 87.68) (end 102.504477 87.682757) (width 0.11) (layer "F.Cu") (net 152))
  (segment (start 102.255141 86.792204) (end 102.32433 86.8) (width 0.11) (layer "F.Cu") (net 152))
  (segment (start 103.194436 82.35) (end 103.914436 82.35) (width 0.11) (layer "F.Cu") (net 152))
  (segment (start 102.527727 86.129106) (end 102.504477 86.137242) (width 0.11) (layer "F.Cu") (net 152))
  (segment (start 102.081234 87.137068) (end 102.04419 87.196023) (width 0.11) (layer "F.Cu") (net 152))
  (segment (start 103.081079 87.017242) (end 103.056601 87.02) (width 0.11) (layer "F.Cu") (net 152))
  (segment (start 102.04419 87.196023) (end 102.021194 87.261742) (width 0.11) (layer "F.Cu") (net 152))
  (segment (start 103.155708 86.957727) (end 103.142603 86.978583) (width 0.11) (layer "F.Cu") (net 152))
  (segment (start 102.548583 87.703998) (end 102.566001 87.721416) (width 0.11) (layer "F.Cu") (net 152))
  (segment (start 102.566001 87.721416) (end 102.579106 87.742272) (width 0.11) (layer "F.Cu") (net 152))
  (segment (start 102.013399 86.450931) (end 102.013399 86.489068) (width 0.11) (layer "F.Cu") (net 152))
  (segment (start 103.166601 86.91) (end 103.163844 86.934477) (width 0.11) (layer "F.Cu") (net 152))
  (segment (start 102.021194 86.558257) (end 102.04419 86.623976) (width 0.11) (layer "F.Cu") (net 152))
  (segment (start 102.081234 86.682931) (end 102.130467 86.732164) (width 0.11) (layer "F.Cu") (net 152))
  (segment (start 102.59 86.03) (end 102.587242 86.054477) (width 0.11) (layer "F.Cu") (net 152))
  (segment (start 102.04419 86.623976) (end 102.081234 86.682931) (width 0.11) (layer "F.Cu") (net 152))
  (segment (start 104.28 84.034436) (end 102.59 85.724436) (width 0.11) (layer "F.Cu") (net 152))
  (segment (start 102.013399 87.330931) (end 102.013399 87.369068) (width 0.11) (layer "F.Cu") (net 152))
  (segment (start 103.125185 86.823998) (end 103.142603 86.841416) (width 0.11) (layer "F.Cu") (net 152))
  (segment (start 102.081234 87.562931) (end 102.130467 87.612164) (width 0.11) (layer "F.Cu") (net 152))
  (segment (start 102.081234 86.257068) (end 102.04419 86.316023) (width 0.11) (layer "F.Cu") (net 152))
  (segment (start 102.130467 86.732164) (end 102.189422 86.769208) (width 0.11) (layer "F.Cu") (net 152))
  (segment (start 102.548583 86.116001) (end 102.527727 86.129106) (width 0.11) (layer "F.Cu") (net 152))
  (segment (start 103.081079 86.802757) (end 103.104329 86.810893) (width 0.11) (layer "F.Cu") (net 152))
  (segment (start 102.189422 87.050791) (end 102.130467 87.087835) (width 0.11) (layer "F.Cu") (net 152))
  (segment (start 102.255141 86.147795) (end 102.189422 86.170791) (width 0.11) (layer "F.Cu") (net 152))
  (segment (start 102.587242 86.054477) (end 102.579106 86.077727) (width 0.11) (layer "F.Cu") (net 152))
  (segment (start 102.04419 86.316023) (end 102.021194 86.381742) (width 0.11) (layer "F.Cu") (net 152))
  (segment (start 104.28 82.715564) (end 104.28 84.034436) (width 0.11) (layer "F.Cu") (net 152))
  (segment (start 103.142603 86.978583) (end 103.125185 86.996001) (width 0.11) (layer "F.Cu") (net 152))
  (segment (start 102.32433 87.02) (end 102.255141 87.027795) (width 0.11) (layer "F.Cu") (net 152))
  (segment (start 102.255141 87.672204) (end 102.32433 87.68) (width 0.11) (layer "F.Cu") (net 152))
  (segment (start 102.566001 86.098583) (end 102.548583 86.116001) (width 0.11) (layer "F.Cu") (net 152))
  (segment (start 102.587242 87.765522) (end 102.59 87.79) (width 0.11) (layer "F.Cu") (net 152))
  (segment (start 102.32433 86.14) (end 102.255141 86.147795) (width 0.11) (layer "F.Cu") (net 152))
  (segment (start 102.189422 86.170791) (end 102.130467 86.207835) (width 0.11) (layer "F.Cu") (net 152))
  (segment (start 102.48 86.14) (end 102.32433 86.14) (width 0.11) (layer "F.Cu") (net 152))
  (segment (start 102.189422 87.649208) (end 102.255141 87.672204) (width 0.11) (layer "F.Cu") (net 152))
  (segment (start 102.013399 87.369068) (end 102.021194 87.438257) (width 0.11) (layer "F.Cu") (net 152))
  (segment (start 102.021194 87.261742) (end 102.013399 87.330931) (width 0.11) (layer "F.Cu") (net 152))
  (segment (start 103.104329 87.009106) (end 103.081079 87.017242) (width 0.11) (layer "F.Cu") (net 152))
  (segment (start 103.056601 86.8) (end 103.081079 86.802757) (width 0.11) (layer "F.Cu") (net 152))
  (segment (start 102.878 82.033564) (end 103.194436 82.35) (width 0.11) (layer "F.Cu") (net 152))
  (segment (start 102.504477 87.682757) (end 102.527727 87.690893) (width 0.11) (layer "F.Cu") (net 152))
  (segment (start 102.130467 86.207835) (end 102.081234 86.257068) (width 0.11) (layer "F.Cu") (net 152))
  (segment (start 102.021194 87.438257) (end 102.04419 87.503976) (width 0.11) (layer "F.Cu") (net 152))
  (segment (start 102.59 85.724436) (end 102.59 86.03) (width 0.11) (layer "F.Cu") (net 152))
  (segment (start 102.255141 87.027795) (end 102.189422 87.050791) (width 0.11) (layer "F.Cu") (net 152))
  (segment (start 103.155708 86.862272) (end 103.163844 86.885522) (width 0.11) (layer "F.Cu") (net 152))
  (segment (start 102.504477 86.137242) (end 102.48 86.14) (width 0.11) (layer "F.Cu") (net 152))
  (segment (start 102.32433 87.68) (end 102.48 87.68) (width 0.11) (layer "F.Cu") (net 152))
  (segment (start 102.189422 86.769208) (end 102.255141 86.792204) (width 0.11) (layer "F.Cu") (net 152))
  (segment (start 102.130467 87.087835) (end 102.081234 87.137068) (width 0.11) (layer "F.Cu") (net 152))
  (segment (start 103.056601 87.02) (end 102.32433 87.02) (width 0.11) (layer "F.Cu") (net 152))
  (segment (start 103.914436 82.35) (end 104.28 82.715564) (width 0.11) (layer "F.Cu") (net 152))
  (segment (start 103.163844 86.934477) (end 103.155708 86.957727) (width 0.11) (layer "F.Cu") (net 152))
  (segment (start 102.021194 86.381742) (end 102.013399 86.450931) (width 0.11) (layer "F.Cu") (net 152))
  (segment (start 102.579106 86.077727) (end 102.566001 86.098583) (width 0.11) (layer "F.Cu") (net 152))
  (segment (start 101.972 80.84) (end 102.878 81.746) (width 0.11) (layer "F.Cu") (net 152))
  (segment (start 102.878 81.746) (end 102.878 82.033564) (width 0.11) (layer "F.Cu") (net 152))
  (segment (start 102.32433 86.8) (end 103.056601 86.8) (width 0.11) (layer "F.Cu") (net 152))
  (segment (start 102.527727 87.690893) (end 102.548583 87.703998) (width 0.11) (layer "F.Cu") (net 152))
  (segment (start 102.59 92.882851) (end 102.45 93.022851) (width 0.11) (layer "F.Cu") (net 152))
  (segment (start 103.104329 86.810893) (end 103.125185 86.823998) (width 0.11) (layer "F.Cu") (net 152))
  (segment (start 103.142603 86.841416) (end 103.155708 86.862272) (width 0.11) (layer "F.Cu") (net 152))
  (segment (start 103.125185 86.996001) (end 103.104329 87.009106) (width 0.11) (layer "F.Cu") (net 152))
  (segment (start 102.59 87.79) (end 102.59 92.882851) (width 0.11) (layer "F.Cu") (net 152))
  (segment (start 99.45429 89.486023) (end 99.431294 89.551742) (width 0.11) (layer "F.Cu") (net 153))
  (segment (start 100.470979 89.307242) (end 100.446501 89.31) (width 0.11) (layer "F.Cu") (net 153))
  (segment (start 99.45429 88.606023) (end 99.431294 88.671742) (width 0.11) (layer "F.Cu") (net 153))
  (segment (start 99.966001 90.011416) (end 99.979106 90.032272) (width 0.11) (layer "F.Cu") (net 153))
  (segment (start 99.431294 89.551742) (end 99.423499 89.620931) (width 0.11) (layer "F.Cu") (net 153))
  (segment (start 99.927727 89.980893) (end 99.948583 89.993998) (width 0.11) (layer "F.Cu") (net 153))
  (segment (start 100.515085 89.113998) (end 100.532503 89.131416) (width 0.11) (layer "F.Cu") (net 153))
  (segment (start 99.431294 88.671742) (end 99.423499 88.740931) (width 0.11) (layer "F.Cu") (net 153))
  (segment (start 99.88 88.43) (end 99.73443 88.43) (width 0.11) (layer "F.Cu") (net 153))
  (segment (start 100.515085 89.286001) (end 100.494229 89.299106) (width 0.11) (layer "F.Cu") (net 153))
  (segment (start 99.99 90.08) (end 99.99 90.535564) (width 0.11) (layer "F.Cu") (net 153))
  (segment (start 99.423499 89.659068) (end 99.431294 89.728257) (width 0.11) (layer "F.Cu") (net 153))
  (segment (start 99.665241 89.962204) (end 99.73443 89.97) (width 0.11) (layer "F.Cu") (net 153))
  (segment (start 99.904477 89.972757) (end 99.927727 89.980893) (width 0.11) (layer "F.Cu") (net 153))
  (segment (start 99.423499 88.779068) (end 99.431294 88.848257) (width 0.11) (layer "F.Cu") (net 153))
  (segment (start 100.494229 89.100893) (end 100.515085 89.113998) (width 0.11) (layer "F.Cu") (net 153))
  (segment (start 99.665241 89.082204) (end 99.73443 89.09) (width 0.11) (layer "F.Cu") (net 153))
  (segment (start 101.09 91.635564) (end 101.09 92.882851) (width 0.11) (layer "F.Cu") (net 153))
  (segment (start 101.09 92.882851) (end 100.95 93.022851) (width 0.11) (layer "F.Cu") (net 153))
  (segment (start 99.987242 90.055522) (end 99.99 90.08) (width 0.11) (layer "F.Cu") (net 153))
  (segment (start 99.599522 89.340791) (end 99.540567 89.377835) (width 0.11) (layer "F.Cu") (net 153))
  (segment (start 99.73443 89.09) (end 100.446501 89.09) (width 0.11) (layer "F.Cu") (net 153))
  (segment (start 99.904477 88.427242) (end 99.88 88.43) (width 0.11) (layer "F.Cu") (net 153))
  (segment (start 99.491334 88.547068) (end 99.45429 88.606023) (width 0.11) (layer "F.Cu") (net 153))
  (segment (start 99.927727 88.419106) (end 99.904477 88.427242) (width 0.11) (layer "F.Cu") (net 153))
  (segment (start 99.491334 89.852931) (end 99.540567 89.902164) (width 0.11) (layer "F.Cu") (net 153))
  (segment (start 100.553744 89.175522) (end 100.556501 89.2) (width 0.11) (layer "F.Cu") (net 153))
  (segment (start 100.532503 89.268583) (end 100.515085 89.286001) (width 0.11) (layer "F.Cu") (net 153))
  (segment (start 99.540567 89.022164) (end 99.599522 89.059208) (width 0.11) (layer "F.Cu") (net 153))
  (segment (start 99.599522 89.939208) (end 99.665241 89.962204) (width 0.11) (layer "F.Cu") (net 153))
  (segment (start 99.540567 88.497835) (end 99.491334 88.547068) (width 0.11) (layer "F.Cu") (net 153))
  (segment (start 100.41 82.34) (end 99.99 82.76) (width 0.11) (layer "F.Cu") (net 153))
  (segment (start 100.545608 89.152272) (end 100.553744 89.175522) (width 0.11) (layer "F.Cu") (net 153))
  (segment (start 99.73443 88.43) (end 99.665241 88.437795) (width 0.11) (layer "F.Cu") (net 153))
  (segment (start 99.45429 88.913976) (end 99.491334 88.972931) (width 0.11) (layer "F.Cu") (net 153))
  (segment (start 99.540567 89.902164) (end 99.599522 89.939208) (width 0.11) (layer "F.Cu") (net 153))
  (segment (start 99.423499 88.740931) (end 99.423499 88.779068) (width 0.11) (layer "F.Cu") (net 153))
  (segment (start 99.979106 88.367727) (end 99.966001 88.388583) (width 0.11) (layer "F.Cu") (net 153))
  (segment (start 99.540567 89.377835) (end 99.491334 89.427068) (width 0.11) (layer "F.Cu") (net 153))
  (segment (start 100.545608 89.247727) (end 100.532503 89.268583) (width 0.11) (layer "F.Cu") (net 153))
  (segment (start 99.491334 88.972931) (end 99.540567 89.022164) (width 0.11) (layer "F.Cu") (net 153))
  (segment (start 99.431294 88.848257) (end 99.45429 88.913976) (width 0.11) (layer "F.Cu") (net 153))
  (segment (start 100.446501 89.09) (end 100.470979 89.092757) (width 0.11) (layer "F.Cu") (net 153))
  (segment (start 99.665241 88.437795) (end 99.599522 88.460791) (width 0.11) (layer "F.Cu") (net 153))
  (segment (start 99.99 90.535564) (end 101.09 91.635564) (width 0.11) (layer "F.Cu") (net 153))
  (segment (start 99.599522 88.460791) (end 99.540567 88.497835) (width 0.11) (layer "F.Cu") (net 153))
  (segment (start 99.979106 90.032272) (end 99.987242 90.055522) (width 0.11) (layer "F.Cu") (net 153))
  (segment (start 102.988 83.38) (end 101.948 82.34) (width 0.11) (layer "F.Cu") (net 153))
  (segment (start 99.665241 89.317795) (end 99.599522 89.340791) (width 0.11) (layer "F.Cu") (net 153))
  (segment (start 99.88 89.97) (end 99.904477 89.972757) (width 0.11) (layer "F.Cu") (net 153))
  (segment (start 99.99 82.76) (end 99.99 88.32) (width 0.11) (layer "F.Cu") (net 153))
  (segment (start 99.599522 89.059208) (end 99.665241 89.082204) (width 0.11) (layer "F.Cu") (net 153))
  (segment (start 100.446501 89.31) (end 99.73443 89.31) (width 0.11) (layer "F.Cu") (net 153))
  (segment (start 99.491334 89.427068) (end 99.45429 89.486023) (width 0.11) (layer "F.Cu") (net 153))
  (segment (start 99.423499 89.620931) (end 99.423499 89.659068) (width 0.11) (layer "F.Cu") (net 153))
  (segment (start 99.948583 89.993998) (end 99.966001 90.011416) (width 0.11) (layer "F.Cu") (net 153))
  (segment (start 99.99 88.32) (end 99.987242 88.344477) (width 0.11) (layer "F.Cu") (net 153))
  (segment (start 99.987242 88.344477) (end 99.979106 88.367727) (width 0.11) (layer "F.Cu") (net 153))
  (segment (start 100.553744 89.224477) (end 100.545608 89.247727) (width 0.11) (layer "F.Cu") (net 153))
  (segment (start 99.73443 89.97) (end 99.88 89.97) (width 0.11) (layer "F.Cu") (net 153))
  (segment (start 99.431294 89.728257) (end 99.45429 89.793976) (width 0.11) (layer "F.Cu") (net 153))
  (segment (start 99.73443 89.31) (end 99.665241 89.317795) (width 0.11) (layer "F.Cu") (net 153))
  (segment (start 99.966001 88.388583) (end 99.948583 88.406001) (width 0.11) (layer "F.Cu") (net 153))
  (segment (start 99.948583 88.406001) (end 99.927727 88.419106) (width 0.11) (layer "F.Cu") (net 153))
  (segment (start 100.556501 89.2) (end 100.553744 89.224477) (width 0.11) (layer "F.Cu") (net 153))
  (segment (start 101.948 82.34) (end 100.41 82.34) (width 0.11) (layer "F.Cu") (net 153))
  (segment (start 99.45429 89.793976) (end 99.491334 89.852931) (width 0.11) (layer "F.Cu") (net 153))
  (segment (start 100.470979 89.092757) (end 100.494229 89.100893) (width 0.11) (layer "F.Cu") (net 153))
  (segment (start 100.532503 89.131416) (end 100.545608 89.152272) (width 0.11) (layer "F.Cu") (net 153))
  (segment (start 100.494229 89.299106) (end 100.470979 89.307242) (width 0.11) (layer "F.Cu") (net 153))
  (segment (start 103.95 99.877149) (end 103.95 102.75) (width 0.15) (layer "F.Cu") (net 154))
  (segment (start 104 108.15) (end 104 107.429998) (width 0.15) (layer "F.Cu") (net 154))
  (segment (start 104 102.8) (end 104 103.515) (width 0.15) (layer "F.Cu") (net 154))
  (segment (start 103.95 102.75) (end 104 102.8) (width 0.15) (layer "F.Cu") (net 154))
  (via (at 104 102.8) (size 0.5) (drill 0.2) (layers "F.Cu" "B.Cu") (net 154))
  (via (at 104 107.429998) (size 0.5) (drill 0.2) (layers "F.Cu" "B.Cu") (net 154))
  (segment (start 104.003761 105.266621) (end 104 105.3) (width 0.15) (layer "In5.Cu") (net 154))
  (segment (start 103.554198 103.466621) (end 103.550438 103.5) (width 0.15) (layer "In5.Cu") (net 154))
  (segment (start 103.565292 104.634917) (end 103.554198 104.666621) (width 0.15) (layer "In5.Cu") (net 154))
  (segment (start 103.583163 104.006476) (end 103.565292 104.034917) (width 0.15) (layer "In5.Cu") (net 154))
  (segment (start 104.445802 105.033378) (end 104.434708 105.065082) (width 0.15) (layer "In5.Cu") (net 154))
  (segment (start 103.700438 104.55) (end 103.667059 104.55376) (width 0.15) (layer "In5.Cu") (net 154))
  (segment (start 104.393086 104.517274) (end 104.364645 104.535145) (width 0.15) (layer "In5.Cu") (net 154))
  (segment (start 104.434708 104.465082) (end 104.416837 104.493523) (width 0.15) (layer "In5.Cu") (net 154))
  (segment (start 104.332941 104.25376) (end 104.364645 104.264854) (width 0.15) (layer "In5.Cu") (net 154))
  (segment (start 103.635355 103.635145) (end 103.667059 103.646239) (width 0.15) (layer "In5.Cu") (net 154))
  (segment (start 103.85 103.35) (end 103.700438 103.35) (width 0.15) (layer "In5.Cu") (net 154))
  (segment (start 104.364645 105.135145) (end 104.332941 105.146239) (width 0.15) (layer "In5.Cu") (net 154))
  (segment (start 104.416837 104.493523) (end 104.393086 104.517274) (width 0.15) (layer "In5.Cu") (net 154))
  (segment (start 103.967274 103.293523) (end 103.943523 103.317274) (width 0.15) (layer "In5.Cu") (net 154))
  (segment (start 104.393086 104.882725) (end 104.416837 104.906476) (width 0.15) (layer "In5.Cu") (net 154))
  (segment (start 103.554198 103.533378) (end 103.565292 103.565082) (width 0.15) (layer "In5.Cu") (net 154))
  (segment (start 103.583163 103.406476) (end 103.565292 103.434917) (width 0.15) (layer "In5.Cu") (net 154))
  (segment (start 104 105.3) (end 104 107.429998) (width 0.15) (layer "In5.Cu") (net 154))
  (segment (start 104.15 105.15) (end 104.116622 105.15376) (width 0.15) (layer "In5.Cu") (net 154))
  (segment (start 104.332941 103.946239) (end 104.299562 103.95) (width 0.15) (layer "In5.Cu") (net 154))
  (segment (start 103.667059 103.95376) (end 103.635355 103.964854) (width 0.15) (layer "In5.Cu") (net 154))
  (segment (start 103.554198 104.133378) (end 103.565292 104.165082) (width 0.15) (layer "In5.Cu") (net 154))
  (segment (start 104.364645 104.264854) (end 104.393086 104.282725) (width 0.15) (layer "In5.Cu") (net 154))
  (segment (start 103.606914 103.617274) (end 103.635355 103.635145) (width 0.15) (layer "In5.Cu") (net 154))
  (segment (start 103.915082 103.335145) (end 103.883378 103.346239) (width 0.15) (layer "In5.Cu") (net 154))
  (segment (start 104.332941 105.146239) (end 104.299562 105.15) (width 0.15) (layer "In5.Cu") (net 154))
  (segment (start 104.416837 105.093523) (end 104.393086 105.117274) (width 0.15) (layer "In5.Cu") (net 154))
  (segment (start 103.606914 104.817274) (end 103.635355 104.835145) (width 0.15) (layer "In5.Cu") (net 154))
  (segment (start 104.364645 103.935145) (end 104.332941 103.946239) (width 0.15) (layer "In5.Cu") (net 154))
  (segment (start 103.700438 104.85) (end 104.299562 104.85) (width 0.15) (layer "In5.Cu") (net 154))
  (segment (start 103.635355 104.835145) (end 103.667059 104.846239) (width 0.15) (layer "In5.Cu") (net 154))
  (segment (start 104.445802 104.966621) (end 104.449562 105) (width 0.15) (layer "In5.Cu") (net 154))
  (segment (start 103.667059 104.55376) (end 103.635355 104.564854) (width 0.15) (layer "In5.Cu") (net 154))
  (segment (start 104.445802 104.366621) (end 104.449562 104.4) (width 0.15) (layer "In5.Cu") (net 154))
  (segment (start 104.364645 103.664854) (end 104.393086 103.682725) (width 0.15) (layer "In5.Cu") (net 154))
  (segment (start 103.550438 103.5) (end 103.554198 103.533378) (width 0.15) (layer "In5.Cu") (net 154))
  (segment (start 104.449562 104.4) (end 104.445802 104.433378) (width 0.15) (layer "In5.Cu") (net 154))
  (segment (start 104.299562 104.55) (end 103.700438 104.55) (width 0.15) (layer "In5.Cu") (net 154))
  (segment (start 104.393086 105.117274) (end 104.364645 105.135145) (width 0.15) (layer "In5.Cu") (net 154))
  (segment (start 103.635355 103.364854) (end 103.606914 103.382725) (width 0.15) (layer "In5.Cu") (net 154))
  (segment (start 104.393086 103.682725) (end 104.416837 103.706476) (width 0.15) (layer "In5.Cu") (net 154))
  (segment (start 103.667059 104.846239) (end 103.700438 104.85) (width 0.15) (layer "In5.Cu") (net 154))
  (segment (start 103.667059 103.35376) (end 103.635355 103.364854) (width 0.15) (layer "In5.Cu") (net 154))
  (segment (start 103.554198 104.733378) (end 103.565292 104.765082) (width 0.15) (layer "In5.Cu") (net 154))
  (segment (start 103.700438 103.95) (end 103.667059 103.95376) (width 0.15) (layer "In5.Cu") (net 154))
  (segment (start 104.416837 103.893523) (end 104.393086 103.917274) (width 0.15) (layer "In5.Cu") (net 154))
  (segment (start 103.583163 104.793523) (end 103.606914 104.817274) (width 0.15) (layer "In5.Cu") (net 154))
  (segment (start 103.700438 103.65) (end 104.299562 103.65) (width 0.15) (layer "In5.Cu") (net 154))
  (segment (start 104.434708 103.734917) (end 104.445802 103.766621) (width 0.15) (layer "In5.Cu") (net 154))
  (segment (start 104.299562 105.15) (end 104.15 105.15) (width 0.15) (layer "In5.Cu") (net 154))
  (segment (start 104.299562 103.65) (end 104.332941 103.65376) (width 0.15) (layer "In5.Cu") (net 154))
  (segment (start 103.985145 103.265082) (end 103.967274 103.293523) (width 0.15) (layer "In5.Cu") (net 154))
  (segment (start 104.449562 105) (end 104.445802 105.033378) (width 0.15) (layer "In5.Cu") (net 154))
  (segment (start 104.364645 104.864854) (end 104.393086 104.882725) (width 0.15) (layer "In5.Cu") (net 154))
  (segment (start 104.416837 103.706476) (end 104.434708 103.734917) (width 0.15) (layer "In5.Cu") (net 154))
  (segment (start 104.332941 104.546239) (end 104.299562 104.55) (width 0.15) (layer "In5.Cu") (net 154))
  (segment (start 103.554198 104.666621) (end 103.550438 104.7) (width 0.15) (layer "In5.Cu") (net 154))
  (segment (start 103.883378 103.346239) (end 103.85 103.35) (width 0.15) (layer "In5.Cu") (net 154))
  (segment (start 104.416837 104.306476) (end 104.434708 104.334917) (width 0.15) (layer "In5.Cu") (net 154))
  (segment (start 104.032726 105.206476) (end 104.014855 105.234917) (width 0.15) (layer "In5.Cu") (net 154))
  (segment (start 104.434708 105.065082) (end 104.416837 105.093523) (width 0.15) (layer "In5.Cu") (net 154))
  (segment (start 104.364645 104.535145) (end 104.332941 104.546239) (width 0.15) (layer "In5.Cu") (net 154))
  (segment (start 103.565292 104.765082) (end 103.583163 104.793523) (width 0.15) (layer "In5.Cu") (net 154))
  (segment (start 104 103.2) (end 103.996239 103.233378) (width 0.15) (layer "In5.Cu") (net 154))
  (segment (start 103.606914 104.217274) (end 103.635355 104.235145) (width 0.15) (layer "In5.Cu") (net 154))
  (segment (start 104 102.8) (end 104 103.2) (width 0.15) (layer "In5.Cu") (net 154))
  (segment (start 104.434708 104.934917) (end 104.445802 104.966621) (width 0.15) (layer "In5.Cu") (net 154))
  (segment (start 103.565292 104.034917) (end 103.554198 104.066621) (width 0.15) (layer "In5.Cu") (net 154))
  (segment (start 103.565292 103.434917) (end 103.554198 103.466621) (width 0.15) (layer "In5.Cu") (net 154))
  (segment (start 103.635355 103.964854) (end 103.606914 103.982725) (width 0.15) (layer "In5.Cu") (net 154))
  (segment (start 104.299562 104.25) (end 104.332941 104.25376) (width 0.15) (layer "In5.Cu") (net 154))
  (segment (start 103.565292 104.165082) (end 103.583163 104.193523) (width 0.15) (layer "In5.Cu") (net 154))
  (segment (start 104.416837 104.906476) (end 104.434708 104.934917) (width 0.15) (layer "In5.Cu") (net 154))
  (segment (start 103.606914 103.982725) (end 103.583163 104.006476) (width 0.15) (layer "In5.Cu") (net 154))
  (segment (start 103.583163 104.193523) (end 103.606914 104.217274) (width 0.15) (layer "In5.Cu") (net 154))
  (segment (start 104.393086 104.282725) (end 104.416837 104.306476) (width 0.15) (layer "In5.Cu") (net 154))
  (segment (start 103.583163 104.606476) (end 103.565292 104.634917) (width 0.15) (layer "In5.Cu") (net 154))
  (segment (start 104.299562 103.95) (end 103.700438 103.95) (width 0.15) (layer "In5.Cu") (net 154))
  (segment (start 103.583163 103.593523) (end 103.606914 103.617274) (width 0.15) (layer "In5.Cu") (net 154))
  (segment (start 104.449562 103.8) (end 104.445802 103.833378) (width 0.15) (layer "In5.Cu") (net 154))
  (segment (start 103.943523 103.317274) (end 103.915082 103.335145) (width 0.15) (layer "In5.Cu") (net 154))
  (segment (start 103.635355 104.235145) (end 103.667059 104.246239) (width 0.15) (layer "In5.Cu") (net 154))
  (segment (start 104.393086 103.917274) (end 104.364645 103.935145) (width 0.15) (layer "In5.Cu") (net 154))
  (segment (start 104.434708 103.865082) (end 104.416837 103.893523) (width 0.15) (layer "In5.Cu") (net 154))
  (segment (start 103.550438 104.7) (end 103.554198 104.733378) (width 0.15) (layer "In5.Cu") (net 154))
  (segment (start 104.299562 104.85) (end 104.332941 104.85376) (width 0.15) (layer "In5.Cu") (net 154))
  (segment (start 103.635355 104.564854) (end 103.606914 104.582725) (width 0.15) (layer "In5.Cu") (net 154))
  (segment (start 103.606914 103.382725) (end 103.583163 103.406476) (width 0.15) (layer "In5.Cu") (net 154))
  (segment (start 104.445802 103.833378) (end 104.434708 103.865082) (width 0.15) (layer "In5.Cu") (net 154))
  (segment (start 104.056477 105.182725) (end 104.032726 105.206476) (width 0.15) (layer "In5.Cu") (net 154))
  (segment (start 104.084918 105.164854) (end 104.056477 105.182725) (width 0.15) (layer "In5.Cu") (net 154))
  (segment (start 103.667059 103.646239) (end 103.700438 103.65) (width 0.15) (layer "In5.Cu") (net 154))
  (segment (start 104.434708 104.334917) (end 104.445802 104.366621) (width 0.15) (layer "In5.Cu") (net 154))
  (segment (start 103.606914 104.582725) (end 103.583163 104.606476) (width 0.15) (layer "In5.Cu") (net 154))
  (segment (start 104.445802 104.433378) (end 104.434708 104.465082) (width 0.15) (layer "In5.Cu") (net 154))
  (segment (start 104.332941 104.85376) (end 104.364645 104.864854) (width 0.15) (layer "In5.Cu") (net 154))
  (segment (start 103.667059 104.246239) (end 103.700438 104.25) (width 0.15) (layer "In5.Cu") (net 154))
  (segment (start 104.116622 105.15376) (end 104.084918 105.164854) (width 0.15) (layer "In5.Cu") (net 154))
  (segment (start 104.332941 103.65376) (end 104.364645 103.664854) (width 0.15) (layer "In5.Cu") (net 154))
  (segment (start 104.445802 103.766621) (end 104.449562 103.8) (width 0.15) (layer "In5.Cu") (net 154))
  (segment (start 103.700438 104.25) (end 104.299562 104.25) (width 0.15) (layer "In5.Cu") (net 154))
  (segment (start 104.014855 105.234917) (end 104.003761 105.266621) (width 0.15) (layer "In5.Cu") (net 154))
  (segment (start 103.565292 103.565082) (end 103.583163 103.593523) (width 0.15) (layer "In5.Cu") (net 154))
  (segment (start 103.996239 103.233378) (end 103.985145 103.265082) (width 0.15) (layer "In5.Cu") (net 154))
  (segment (start 103.554198 104.066621) (end 103.550438 104.1) (width 0.15) (layer "In5.Cu") (net 154))
  (segment (start 103.550438 104.1) (end 103.554198 104.133378) (width 0.15) (layer "In5.Cu") (net 154))
  (segment (start 103.700438 103.35) (end 103.667059 103.35376) (width 0.15) (layer "In5.Cu") (net 154))
  (segment (start 103.000006 102.8) (end 103.000006 103.514994) (width 0.15) (layer "F.Cu") (net 155))
  (segment (start 104 110.55) (end 103.6 110.15) (width 0.15) (layer "F.Cu") (net 155))
  (segment (start 103.45 102.350006) (end 103.000006 102.8) (width 0.15) (layer "F.Cu") (net 155))
  (segment (start 103.45 99.877149) (end 103.45 102.350006) (width 0.15) (layer "F.Cu") (net 155))
  (via (at 103.6 110.15) (size 0.5) (drill 0.2) (layers "F.Cu" "B.Cu") (net 155))
  (via (at 103.000006 102.8) (size 0.5) (drill 0.2) (layers "F.Cu" "B.Cu") (net 155))
  (segment (start 102.676051 105.899994) (end 102.642672 105.903754) (width 0.15) (layer "In5.Cu") (net 155))
  (segment (start 103.014861 106.584911) (end 103.003767 106.616615) (width 0.15) (layer "In5.Cu") (net 155))
  (segment (start 103.323961 106.499994) (end 103.150006 106.499994) (width 0.15) (layer "In5.Cu") (net 155))
  (segment (start 103.417485 106.467268) (end 103.389044 106.485139) (width 0.15) (layer "In5.Cu") (net 155))
  (segment (start 102.582527 105.932719) (end 102.558776 105.95647) (width 0.15) (layer "In5.Cu") (net 155))
  (segment (start 103.032732 106.55647) (end 103.014861 106.584911) (width 0.15) (layer "In5.Cu") (net 155))
  (segment (start 103.441236 106.443517) (end 103.417485 106.467268) (width 0.15) (layer "In5.Cu") (net 155))
  (segment (start 103.35734 106.203754) (end 103.389044 106.214848) (width 0.15) (layer "In5.Cu") (net 155))
  (segment (start 102.96728 105.843517) (end 102.943529 105.867268) (width 0.15) (layer "In5.Cu") (net 155))
  (segment (start 103.056483 106.532719) (end 103.032732 106.55647) (width 0.15) (layer "In5.Cu") (net 155))
  (segment (start 103.000006 102.8) (end 103.000006 105.749994) (width 0.15) (layer "In5.Cu") (net 155))
  (segment (start 102.610968 106.185139) (end 102.642672 106.196233) (width 0.15) (layer "In5.Cu") (net 155))
  (segment (start 102.985151 105.815076) (end 102.96728 105.843517) (width 0.15) (layer "In5.Cu") (net 155))
  (segment (start 103.084924 106.514848) (end 103.056483 106.532719) (width 0.15) (layer "In5.Cu") (net 155))
  (segment (start 103.000006 105.749994) (end 102.996245 105.783372) (width 0.15) (layer "In5.Cu") (net 155))
  (segment (start 102.676051 106.199994) (end 103.323961 106.199994) (width 0.15) (layer "In5.Cu") (net 155))
  (segment (start 102.529811 106.016615) (end 102.526051 106.049994) (width 0.15) (layer "In5.Cu") (net 155))
  (segment (start 103.000006 106.649994) (end 103.000006 109.550006) (width 0.15) (layer "In5.Cu") (net 155))
  (segment (start 103.389044 106.214848) (end 103.417485 106.232719) (width 0.15) (layer "In5.Cu") (net 155))
  (segment (start 103.389044 106.485139) (end 103.35734 106.496233) (width 0.15) (layer "In5.Cu") (net 155))
  (segment (start 103.003767 106.616615) (end 103.000006 106.649994) (width 0.15) (layer "In5.Cu") (net 155))
  (segment (start 103.459107 106.284911) (end 103.470201 106.316615) (width 0.15) (layer "In5.Cu") (net 155))
  (segment (start 103.000006 109.550006) (end 103.6 110.15) (width 0.15) (layer "In5.Cu") (net 155))
  (segment (start 103.150006 106.499994) (end 103.116628 106.503754) (width 0.15) (layer "In5.Cu") (net 155))
  (segment (start 102.529811 106.083372) (end 102.540905 106.115076) (width 0.15) (layer "In5.Cu") (net 155))
  (segment (start 102.526051 106.049994) (end 102.529811 106.083372) (width 0.15) (layer "In5.Cu") (net 155))
  (segment (start 103.323961 106.199994) (end 103.35734 106.203754) (width 0.15) (layer "In5.Cu") (net 155))
  (segment (start 103.473961 106.349994) (end 103.470201 106.383372) (width 0.15) (layer "In5.Cu") (net 155))
  (segment (start 102.642672 105.903754) (end 102.610968 105.914848) (width 0.15) (layer "In5.Cu") (net 155))
  (segment (start 103.470201 106.383372) (end 103.459107 106.415076) (width 0.15) (layer "In5.Cu") (net 155))
  (segment (start 102.996245 105.783372) (end 102.985151 105.815076) (width 0.15) (layer "In5.Cu") (net 155))
  (segment (start 103.417485 106.232719) (end 103.441236 106.25647) (width 0.15) (layer "In5.Cu") (net 155))
  (segment (start 102.540905 106.115076) (end 102.558776 106.143517) (width 0.15) (layer "In5.Cu") (net 155))
  (segment (start 102.610968 105.914848) (end 102.582527 105.932719) (width 0.15) (layer "In5.Cu") (net 155))
  (segment (start 103.459107 106.415076) (end 103.441236 106.443517) (width 0.15) (layer "In5.Cu") (net 155))
  (segment (start 102.850006 105.899994) (end 102.676051 105.899994) (width 0.15) (layer "In5.Cu") (net 155))
  (segment (start 102.883384 105.896233) (end 102.850006 105.899994) (width 0.15) (layer "In5.Cu") (net 155))
  (segment (start 102.540905 105.984911) (end 102.529811 106.016615) (width 0.15) (layer "In5.Cu") (net 155))
  (segment (start 103.116628 106.503754) (end 103.084924 106.514848) (width 0.15) (layer "In5.Cu") (net 155))
  (segment (start 102.943529 105.867268) (end 102.915088 105.885139) (width 0.15) (layer "In5.Cu") (net 155))
  (segment (start 103.35734 106.496233) (end 103.323961 106.499994) (width 0.15) (layer "In5.Cu") (net 155))
  (segment (start 102.558776 106.143517) (end 102.582527 106.167268) (width 0.15) (layer "In5.Cu") (net 155))
  (segment (start 103.441236 106.25647) (end 103.459107 106.284911) (width 0.15) (layer "In5.Cu") (net 155))
  (segment (start 102.558776 105.95647) (end 102.540905 105.984911) (width 0.15) (layer "In5.Cu") (net 155))
  (segment (start 102.642672 106.196233) (end 102.676051 106.199994) (width 0.15) (layer "In5.Cu") (net 155))
  (segment (start 103.470201 106.316615) (end 103.473961 106.349994) (width 0.15) (layer "In5.Cu") (net 155))
  (segment (start 102.915088 105.885139) (end 102.883384 105.896233) (width 0.15) (layer "In5.Cu") (net 155))
  (segment (start 102.582527 106.167268) (end 102.610968 106.185139) (width 0.15) (layer "In5.Cu") (net 155))
  (segment (start 101.95 99.877149) (end 101.95 102.75) (width 0.15) (layer "F.Cu") (net 156))
  (segment (start 101.95 102.75) (end 102 102.8) (width 0.15) (layer "F.Cu") (net 156))
  (segment (start 102 102.8) (end 102 103.515) (width 0.15) (layer "F.Cu") (net 156))
  (segment (start 104 111.35) (end 103.6 110.95) (width 0.15) (layer "F.Cu") (net 156))
  (via (at 103.6 110.95) (size 0.5) (drill 0.2) (layers "F.Cu" "B.Cu") (net 156))
  (via (at 102 102.8) (size 0.5) (drill 0.2) (layers "F.Cu" "B.Cu") (net 156))
  (segment (start 102.81 110.95) (end 102 110.14) (width 0.15) (layer "In5.Cu") (net 156))
  (segment (start 102 110.14) (end 102 102.8) (width 0.15) (layer "In5.Cu") (net 156))
  (segment (start 103.6 110.95) (end 102.81 110.95) (width 0.15) (layer "In5.Cu") (net 156))
  (segment (start 97.6 109.75) (end 97.2 109.35) (width 0.15) (layer "F.Cu") (net 157))
  (segment (start 101.45 102.35) (end 101 102.8) (width 0.15) (layer "F.Cu") (net 157))
  (segment (start 101.45 99.877149) (end 101.45 102.35) (width 0.15) (layer "F.Cu") (net 157))
  (segment (start 101 102.8) (end 101 103.515) (width 0.15) (layer "F.Cu") (net 157))
  (via (at 97.2 109.35) (size 0.5) (drill 0.2) (layers "F.Cu" "B.Cu") (net 157))
  (via (at 101 102.8) (size 0.5) (drill 0.2) (layers "F.Cu" "B.Cu") (net 157))
  (segment (start 101 107.2) (end 101 102.8) (width 0.15) (layer "In5.Cu") (net 157))
  (segment (start 97.2 109.35) (end 98.85 109.35) (width 0.15) (layer "In5.Cu") (net 157))
  (segment (start 98.85 109.35) (end 101 107.2) (width 0.15) (layer "In5.Cu") (net 157))
  (segment (start 104 109.75) (end 103.6 109.35) (width 0.15) (layer "F.Cu") (net 158))
  (segment (start 104.45 99.877149) (end 104.45 102.25) (width 0.15) (layer "F.Cu") (net 158))
  (segment (start 105 102.8) (end 105 103.515) (width 0.15) (layer "F.Cu") (net 158))
  (segment (start 104.45 102.25) (end 105 102.8) (width 0.15) (layer "F.Cu") (net 158))
  (via (at 103.6 109.35) (size 0.5) (drill 0.2) (layers "F.Cu" "B.Cu") (net 158))
  (via (at 105 102.8) (size 0.5) (drill 0.2) (layers "F.Cu" "B.Cu") (net 158))
  (segment (start 103.6 109.35) (end 103.6 108.7) (width 0.15) (layer "In5.Cu") (net 158))
  (segment (start 103.6 108.7) (end 105 107.3) (width 0.15) (layer "In5.Cu") (net 158))
  (segment (start 105 107.3) (end 105 102.8) (width 0.15) (layer "In5.Cu") (net 158))
  (segment (start 106 102.8) (end 106 103.515) (width 0.15) (layer "F.Cu") (net 159))
  (segment (start 105.45 99.877149) (end 105.45 102.25) (width 0.15) (layer "F.Cu") (net 159))
  (segment (start 106 106.95) (end 106 106.9) (width 0.15) (layer "F.Cu") (net 159))
  (segment (start 105.45 102.25) (end 106 102.8) (width 0.15) (layer "F.Cu") (net 159))
  (segment (start 104.8 108.15) (end 106 106.95) (width 0.15) (layer "F.Cu") (net 159))
  (via (at 106 102.8) (size 0.5) (drill 0.2) (layers "F.Cu" "B.Cu") (net 159))
  (via (at 106 106.9) (size 0.5) (drill 0.2) (layers "F.Cu" "B.Cu") (net 159))
  (segment (start 106 105.05) (end 106 106.9) (width 0.15) (layer "In5.Cu") (net 159))
  (segment (start 105.985145 104.984917) (end 105.996239 105.016621) (width 0.15) (layer "In5.Cu") (net 159))
  (segment (start 105.653918 103.7) (end 106.246082 103.7) (width 0.15) (layer "In5.Cu") (net 159))
  (segment (start 105.653918 104.9) (end 105.85 104.9) (width 0.15) (layer "In5.Cu") (net 159))
  (segment (start 105.943523 103.367274) (end 105.915082 103.385145) (width 0.15) (layer "In5.Cu") (net 159))
  (segment (start 105.967274 104.956476) (end 105.985145 104.984917) (width 0.15) (layer "In5.Cu") (net 159))
  (segment (start 105.518772 104.815082) (end 105.536643 104.843523) (width 0.15) (layer "In5.Cu") (net 159))
  (segment (start 105.915082 103.385145) (end 105.883378 103.396239) (width 0.15) (layer "In5.Cu") (net 159))
  (segment (start 106.279461 103.996239) (end 106.246082 104) (width 0.15) (layer "In5.Cu") (net 159))
  (segment (start 105.653918 104.6) (end 105.620539 104.60376) (width 0.15) (layer "In5.Cu") (net 159))
  (segment (start 105.507678 103.583378) (end 105.518772 103.615082) (width 0.15) (layer "In5.Cu") (net 159))
  (segment (start 105.653918 103.4) (end 105.620539 103.40376) (width 0.15) (layer "In5.Cu") (net 159))
  (segment (start 105.996239 103.283378) (end 105.985145 103.315082) (width 0.15) (layer "In5.Cu") (net 159))
  (segment (start 105.518772 104.084917) (end 105.507678 104.116621) (width 0.15) (layer "In5.Cu") (net 159))
  (segment (start 106.363357 104.543523) (end 106.339606 104.567274) (width 0.15) (layer "In5.Cu") (net 159))
  (segment (start 105.536643 103.643523) (end 105.560394 103.667274) (width 0.15) (layer "In5.Cu") (net 159))
  (segment (start 105.883378 104.90376) (end 105.915082 104.914854) (width 0.15) (layer "In5.Cu") (net 159))
  (segment (start 106.311165 103.714854) (end 106.339606 103.732725) (width 0.15) (layer "In5.Cu") (net 159))
  (segment (start 105.503918 104.15) (end 105.507678 104.183378) (width 0.15) (layer "In5.Cu") (net 159))
  (segment (start 105.85 104.9) (end 105.883378 104.90376) (width 0.15) (layer "In5.Cu") (net 159))
  (segment (start 105.915082 104.914854) (end 105.943523 104.932725) (width 0.15) (layer "In5.Cu") (net 159))
  (segment (start 105.620539 104.296239) (end 105.653918 104.3) (width 0.15) (layer "In5.Cu") (net 159))
  (segment (start 105.507678 104.116621) (end 105.503918 104.15) (width 0.15) (layer "In5.Cu") (net 159))
  (segment (start 106.339606 104.567274) (end 106.311165 104.585145) (width 0.15) (layer "In5.Cu") (net 159))
  (segment (start 105.85 103.4) (end 105.653918 103.4) (width 0.15) (layer "In5.Cu") (net 159))
  (segment (start 106.381228 103.784917) (end 106.392322 103.816621) (width 0.15) (layer "In5.Cu") (net 159))
  (segment (start 106 103.25) (end 105.996239 103.283378) (width 0.15) (layer "In5.Cu") (net 159))
  (segment (start 105.503918 104.75) (end 105.507678 104.783378) (width 0.15) (layer "In5.Cu") (net 159))
  (segment (start 105.536643 104.656476) (end 105.518772 104.684917) (width 0.15) (layer "In5.Cu") (net 159))
  (segment (start 106.381228 104.384917) (end 106.392322 104.416621) (width 0.15) (layer "In5.Cu") (net 159))
  (segment (start 105.518772 104.215082) (end 105.536643 104.243523) (width 0.15) (layer "In5.Cu") (net 159))
  (segment (start 105.588835 104.885145) (end 105.620539 104.896239) (width 0.15) (layer "In5.Cu") (net 159))
  (segment (start 106 102.8) (end 106 103.25) (width 0.15) (layer "In5.Cu") (net 159))
  (segment (start 106.246082 103.7) (end 106.279461 103.70376) (width 0.15) (layer "In5.Cu") (net 159))
  (segment (start 106.279461 103.70376) (end 106.311165 103.714854) (width 0.15) (layer "In5.Cu") (net 159))
  (segment (start 105.620539 104.896239) (end 105.653918 104.9) (width 0.15) (layer "In5.Cu") (net 159))
  (segment (start 105.560394 104.267274) (end 105.588835 104.285145) (width 0.15) (layer "In5.Cu") (net 159))
  (segment (start 105.560394 104.867274) (end 105.588835 104.885145) (width 0.15) (layer "In5.Cu") (net 159))
  (segment (start 106.279461 104.596239) (end 106.246082 104.6) (width 0.15) (layer "In5.Cu") (net 159))
  (segment (start 105.620539 104.60376) (end 105.588835 104.614854) (width 0.15) (layer "In5.Cu") (net 159))
  (segment (start 106.363357 103.943523) (end 106.339606 103.967274) (width 0.15) (layer "In5.Cu") (net 159))
  (segment (start 105.985145 103.315082) (end 105.967274 103.343523) (width 0.15) (layer "In5.Cu") (net 159))
  (segment (start 105.620539 103.40376) (end 105.588835 103.414854) (width 0.15) (layer "In5.Cu") (net 159))
  (segment (start 105.536643 104.243523) (end 105.560394 104.267274) (width 0.15) (layer "In5.Cu") (net 159))
  (segment (start 105.536643 103.456476) (end 105.518772 103.484917) (width 0.15) (layer "In5.Cu") (net 159))
  (segment (start 106.392322 104.416621) (end 106.396082 104.45) (width 0.15) (layer "In5.Cu") (net 159))
  (segment (start 106.396082 104.45) (end 106.392322 104.483378) (width 0.15) (layer "In5.Cu") (net 159))
  (segment (start 106.339606 103.967274) (end 106.311165 103.985145) (width 0.15) (layer "In5.Cu") (net 159))
  (segment (start 105.507678 104.783378) (end 105.518772 104.815082) (width 0.15) (layer "In5.Cu") (net 159))
  (segment (start 105.518772 103.615082) (end 105.536643 103.643523) (width 0.15) (layer "In5.Cu") (net 159))
  (segment (start 105.996239 105.016621) (end 106 105.05) (width 0.15) (layer "In5.Cu") (net 159))
  (segment (start 105.620539 104.00376) (end 105.588835 104.014854) (width 0.15) (layer "In5.Cu") (net 159))
  (segment (start 105.653918 104.3) (end 106.246082 104.3) (width 0.15) (layer "In5.Cu") (net 159))
  (segment (start 105.518772 104.684917) (end 105.507678 104.716621) (width 0.15) (layer "In5.Cu") (net 159))
  (segment (start 105.503918 103.55) (end 105.507678 103.583378) (width 0.15) (layer "In5.Cu") (net 159))
  (segment (start 105.588835 104.285145) (end 105.620539 104.296239) (width 0.15) (layer "In5.Cu") (net 159))
  (segment (start 106.363357 103.756476) (end 106.381228 103.784917) (width 0.15) (layer "In5.Cu") (net 159))
  (segment (start 105.588835 104.014854) (end 105.560394 104.032725) (width 0.15) (layer "In5.Cu") (net 159))
  (segment (start 106.392322 103.883378) (end 106.381228 103.915082) (width 0.15) (layer "In5.Cu") (net 159))
  (segment (start 105.967274 103.343523) (end 105.943523 103.367274) (width 0.15) (layer "In5.Cu") (net 159))
  (segment (start 105.620539 103.696239) (end 105.653918 103.7) (width 0.15) (layer "In5.Cu") (net 159))
  (segment (start 105.536643 104.843523) (end 105.560394 104.867274) (width 0.15) (layer "In5.Cu") (net 159))
  (segment (start 105.536643 104.056476) (end 105.518772 104.084917) (width 0.15) (layer "In5.Cu") (net 159))
  (segment (start 105.943523 104.932725) (end 105.967274 104.956476) (width 0.15) (layer "In5.Cu") (net 159))
  (segment (start 106.311165 104.585145) (end 106.279461 104.596239) (width 0.15) (layer "In5.Cu") (net 159))
  (segment (start 105.588835 104.614854) (end 105.560394 104.632725) (width 0.15) (layer "In5.Cu") (net 159))
  (segment (start 105.883378 103.396239) (end 105.85 103.4) (width 0.15) (layer "In5.Cu") (net 159))
  (segment (start 105.560394 103.432725) (end 105.536643 103.456476) (width 0.15) (layer "In5.Cu") (net 159))
  (segment (start 105.507678 103.516621) (end 105.503918 103.55) (width 0.15) (layer "In5.Cu") (net 159))
  (segment (start 106.363357 104.356476) (end 106.381228 104.384917) (width 0.15) (layer "In5.Cu") (net 159))
  (segment (start 106.339606 104.332725) (end 106.363357 104.356476) (width 0.15) (layer "In5.Cu") (net 159))
  (segment (start 106.392322 103.816621) (end 106.396082 103.85) (width 0.15) (layer "In5.Cu") (net 159))
  (segment (start 105.588835 103.685145) (end 105.620539 103.696239) (width 0.15) (layer "In5.Cu") (net 159))
  (segment (start 105.518772 103.484917) (end 105.507678 103.516621) (width 0.15) (layer "In5.Cu") (net 159))
  (segment (start 106.381228 103.915082) (end 106.363357 103.943523) (width 0.15) (layer "In5.Cu") (net 159))
  (segment (start 106.381228 104.515082) (end 106.363357 104.543523) (width 0.15) (layer "In5.Cu") (net 159))
  (segment (start 105.507678 104.183378) (end 105.518772 104.215082) (width 0.15) (layer "In5.Cu") (net 159))
  (segment (start 106.246082 104.6) (end 105.653918 104.6) (width 0.15) (layer "In5.Cu") (net 159))
  (segment (start 105.588835 103.414854) (end 105.560394 103.432725) (width 0.15) (layer "In5.Cu") (net 159))
  (segment (start 106.279461 104.30376) (end 106.311165 104.314854) (width 0.15) (layer "In5.Cu") (net 159))
  (segment (start 105.507678 104.716621) (end 105.503918 104.75) (width 0.15) (layer "In5.Cu") (net 159))
  (segment (start 106.339606 103.732725) (end 106.363357 103.756476) (width 0.15) (layer "In5.Cu") (net 159))
  (segment (start 106.246082 104.3) (end 106.279461 104.30376) (width 0.15) (layer "In5.Cu") (net 159))
  (segment (start 106.311165 103.985145) (end 106.279461 103.996239) (width 0.15) (layer "In5.Cu") (net 159))
  (segment (start 105.560394 103.667274) (end 105.588835 103.685145) (width 0.15) (layer "In5.Cu") (net 159))
  (segment (start 106.392322 104.483378) (end 106.381228 104.515082) (width 0.15) (layer "In5.Cu") (net 159))
  (segment (start 105.560394 104.032725) (end 105.536643 104.056476) (width 0.15) (layer "In5.Cu") (net 159))
  (segment (start 106.396082 103.85) (end 106.392322 103.883378) (width 0.15) (layer "In5.Cu") (net 159))
  (segment (start 105.560394 104.632725) (end 105.536643 104.656476) (width 0.15) (layer "In5.Cu") (net 159))
  (segment (start 106.311165 104.314854) (end 106.339606 104.332725) (width 0.15) (layer "In5.Cu") (net 159))
  (segment (start 106.246082 104) (end 105.653918 104) (width 0.15) (layer "In5.Cu") (net 159))
  (segment (start 105.653918 104) (end 105.620539 104.00376) (width 0.15) (layer "In5.Cu") (net 159))
  (segment (start 107.25 97.1) (end 108.4 97.1) (width 0.15) (layer "F.Cu") (net 160))
  (segment (start 107.15 97.2) (end 107.25 97.1) (width 0.15) (layer "F.Cu") (net 160))
  (segment (start 104.8 108.95) (end 105.2 108.55) (width 0.15) (layer "F.Cu") (net 160))
  (segment (start 106.627149 97.2) (end 107.15 97.2) (width 0.15) (layer "F.Cu") (net 160))
  (via (at 107.6 97.05) (size 0.5) (drill 0.2) (layers "F.Cu" "B.Cu") (net 160))
  (via (at 105.2 108.55) (size 0.5) (drill 0.2) (layers "F.Cu" "B.Cu") (net 160))
  (segment (start 106.6 100.41) (end 107.2 101.01) (width 0.15) (layer "In5.Cu") (net 160))
  (segment (start 107.25 97.05) (end 106.6 97.7) (width 0.15) (layer "In5.Cu") (net 160))
  (segment (start 107.6 97.05) (end 107.25 97.05) (width 0.15) (layer "In5.Cu") (net 160))
  (segment (start 105.95 108.55) (end 105.2 108.55) (width 0.15) (layer "In5.Cu") (net 160))
  (segment (start 106.6 97.7) (end 106.6 100.41) (width 0.15) (layer "In5.Cu") (net 160))
  (segment (start 107.2 101.01) (end 107.2 107.3) (width 0.15) (layer "In5.Cu") (net 160))
  (segment (start 107.2 107.3) (end 105.95 108.55) (width 0.15) (layer "In5.Cu") (net 160))
  (segment (start 105.95 101.85) (end 106 101.9) (width 0.15) (layer "F.Cu") (net 161))
  (segment (start 104 108.95) (end 104.4 108.55) (width 0.15) (layer "F.Cu") (net 161))
  (segment (start 105.95 99.877149) (end 105.95 101.85) (width 0.15) (layer "F.Cu") (net 161))
  (via (at 106 101.9) (size 0.5) (drill 0.2) (layers "F.Cu" "B.Cu") (net 161))
  (via (at 104.4 108.55) (size 0.5) (drill 0.2) (layers "F.Cu" "B.Cu") (net 161))
  (segment (start 104.95 108) (end 105.8 108) (width 0.15) (layer "In5.Cu") (net 161))
  (segment (start 104.4 108.55) (end 104.95 108) (width 0.15) (layer "In5.Cu") (net 161))
  (segment (start 106.65 107.15) (end 106.65 102.55) (width 0.15) (layer "In5.Cu") (net 161))
  (segment (start 105.8 108) (end 106.65 107.15) (width 0.15) (layer "In5.Cu") (net 161))
  (segment (start 106.65 102.55) (end 106 101.9) (width 0.15) (layer "In5.Cu") (net 161))
  (segment (start 107 103.515) (end 107.685 103.515) (width 0.15) (layer "F.Cu") (net 162))
  (segment (start 107 100.8) (end 107 103.515) (width 0.15) (layer "F.Cu") (net 162))
  (segment (start 106.6 99.227149) (end 106.6 100.4) (width 0.15) (layer "F.Cu") (net 162))
  (segment (start 104.8 110.55) (end 105.2 110.15) (width 0.15) (layer "F.Cu") (net 162))
  (segment (start 107.685 103.515) (end 107.7 103.5) (width 0.15) (layer "F.Cu") (net 162))
  (segment (start 106.6 100.4) (end 107 100.8) (width 0.15) (layer "F.Cu") (net 162))
  (via (at 105.2 110.15) (size 0.5) (drill 0.2) (layers "F.Cu" "B.Cu") (net 162))
  (via (at 107.7 103.5) (size 0.5) (drill 0.2) (layers "F.Cu" "B.Cu") (net 162))
  (segment (start 105.2 110.15) (end 107.7 107.65) (width 0.15) (layer "In5.Cu") (net 162))
  (segment (start 107.7 107.65) (end 107.7 103.5) (width 0.15) (layer "In5.Cu") (net 162))
  (segment (start 107.3 96.7) (end 107.6 96.4) (width 0.15) (layer "F.Cu") (net 163))
  (segment (start 108.515 96.15) (end 107.849999 96.150001) (width 0.15) (layer "F.Cu") (net 163))
  (segment (start 107.849999 96.150001) (end 107.6 96.4) (width 0.15) (layer "F.Cu") (net 163))
  (segment (start 105.6 110.55) (end 106 110.15) (width 0.15) (layer "F.Cu") (net 163))
  (segment (start 106.627149 96.7) (end 107.3 96.7) (width 0.15) (layer "F.Cu") (net 163))
  (via (at 107.6 96.4) (size 0.5) (drill 0.2) (layers "F.Cu" "B.Cu") (net 163))
  (via (at 106 110.15) (size 0.5) (drill 0.2) (layers "F.Cu" "B.Cu") (net 163))
  (segment (start 108.225002 97.025002) (end 107.6 96.4) (width 0.15) (layer "In5.Cu") (net 163))
  (segment (start 106 110.15) (end 108.225002 107.924998) (width 0.15) (layer "In5.Cu") (net 163))
  (segment (start 108.225002 107.924998) (end 108.225002 97.025002) (width 0.15) (layer "In5.Cu") (net 163))
  (segment (start 108.465 96.65) (end 107.85 96.65) (width 0.15) (layer "B.Cu") (net 163))
  (segment (start 107.85 96.65) (end 107.6 96.4) (width 0.15) (layer "B.Cu") (net 163))
  (segment (start 97.849989 94.865991) (end 97.849989 92.399989) (width 0.2) (layer "F.Cu") (net 164))
  (segment (start 97.849989 92.399989) (end 96.05 90.6) (width 0.2) (layer "F.Cu") (net 164))
  (segment (start 99.772851 95.7) (end 98.683998 95.7) (width 0.2) (layer "F.Cu") (net 164))
  (segment (start 98.683998 95.7) (end 97.849989 94.865991) (width 0.2) (layer "F.Cu") (net 164))
  (via (at 96.05 90.6) (size 0.5) (drill 0.2) (layers "F.Cu" "B.Cu") (net 164))
  (segment (start 96.035 89.75) (end 96.035 90.585) (width 0.2) (layer "B.Cu") (net 164))
  (segment (start 96.035 89.75) (end 96.035 88.5) (width 0.2) (layer "B.Cu") (net 164))
  (segment (start 96.035 90.585) (end 96.05 90.6) (width 0.2) (layer "B.Cu") (net 164))
  (segment (start 99.772851 94.7) (end 98.683998 94.7) (width 0.2) (layer "F.Cu") (net 165))
  (segment (start 98.683998 94.7) (end 98.149999 94.166001) (width 0.2) (layer "F.Cu") (net 165))
  (segment (start 98.149999 94.166001) (end 98.149999 91.699999) (width 0.2) (layer "F.Cu") (net 165))
  (segment (start 98.149999 91.699999) (end 97.05 90.6) (width 0.2) (layer "F.Cu") (net 165))
  (via (at 97.05 90.6) (size 0.5) (drill 0.2) (layers "F.Cu" "B.Cu") (net 165))
  (segment (start 97.015 89.75) (end 97.015 88.52) (width 0.2) (layer "B.Cu") (net 165))
  (segment (start 97.05 90.6) (end 97.05 89.785) (width 0.2) (layer "B.Cu") (net 165))
  (segment (start 74.42 124.185) (end 76.32 124.185) (width 0.3) (layer "F.Cu") (net 166))
  (segment (start 73.8075 123.6075) (end 74.4 124.2) (width 0.2) (layer "F.Cu") (net 166))
  (segment (start 74.82 122.3075) (end 74.82 122.92) (width 0.2) (layer "F.Cu") (net 166))
  (segment (start 75.3 123.4) (end 75.3 124.25) (width 0.2) (layer "F.Cu") (net 166))
  (segment (start 76.32 123.83) (end 77.05 123.1) (width 0.25) (layer "F.Cu") (net 166))
  (segment (start 73.8075 122.3075) (end 73.8075 123.6075) (width 0.2) (layer "F.Cu") (net 166))
  (segment (start 77.05 123.1) (end 77.05 117.3) (width 0.5) (layer "F.Cu") (net 166))
  (segment (start 79.94 114.41) (end 85.884999 114.41) (width 0.5) (layer "F.Cu") (net 166))
  (segment (start 74.82 122.92) (end 75.3 123.4) (width 0.2) (layer "F.Cu") (net 166))
  (segment (start 76.32 124.185) (end 76.32 123.83) (width 0.25) (layer "F.Cu") (net 166))
  (segment (start 77.05 117.3) (end 79.94 114.41) (width 0.5) (layer "F.Cu") (net 166))
  (via (at 77.05 118.55) (size 0.5) (drill 0.2) (layers "F.Cu" "B.Cu") (net 166))
  (via (at 77.05 119.54) (size 0.5) (drill 0.2) (layers "F.Cu" "B.Cu") (net 166))
  (via (at 85 114.41) (size 0.5) (drill 0.2) (layers "F.Cu" "B.Cu") (net 166))
  (via (at 85.99 114.41) (size 0.5) (drill 0.2) (layers "F.Cu" "B.Cu") (net 166))
  (via (at 83.99 114.41) (size 0.5) (drill 0.2) (layers "F.Cu" "B.Cu") (net 166))
  (via (at 83 114.41) (size 0.5) (drill 0.2) (layers "F.Cu" "B.Cu") (net 166))
  (via (at 77.05 121.54) (size 0.5) (drill 0.2) (layers "F.Cu" "B.Cu") (net 166))
  (via (at 77.05 123.1) (size 0.5) (drill 0.2) (layers "F.Cu" "B.Cu") (net 166))
  (via (at 83.63 124.565) (size 0.5) (drill 0.2) (layers "F.Cu" "B.Cu") (net 166))
  (via (at 77.05 120.55) (size 0.5) (drill 0.2) (layers "F.Cu" "B.Cu") (net 166))
  (segment (start 83.045 125.15) (end 83.63 124.565) (width 0.5) (layer "In5.Cu") (net 166))
  (segment (start 80.1 123.35) (end 81.9 125.15) (width 0.5) (layer "In5.Cu") (net 166))
  (segment (start 77.3 123.35) (end 80.1 123.35) (width 0.5) (layer "In5.Cu") (net 166))
  (segment (start 77.05 123.1) (end 77.3 123.35) (width 0.5) (layer "In5.Cu") (net 166))
  (segment (start 81.9 125.15) (end 83.045 125.15) (width 0.5) (layer "In5.Cu") (net 166))
  (segment (start 85.475 124.875) (end 84.975 124.875) (width 0.15) (layer "B.Cu") (net 166))
  (segment (start 84.49 125.495) (end 84.49 124.89) (width 0.15) (layer "B.Cu") (net 166))
  (segment (start 84.49 124.89) (end 84.475 124.875) (width 0.15) (layer "B.Cu") (net 166))
  (segment (start 78.04 119.545) (end 77.055 119.545) (width 0.15) (layer "B.Cu") (net 166))
  (segment (start 84.99 114.42) (end 85 114.41) (width 0.15) (layer "B.Cu") (net 166))
  (segment (start 83.49 124.705) (end 83.63 124.565) (width 0.15) (layer "B.Cu") (net 166))
  (segment (start 83.49 125.495) (end 83.49 124.705) (width 0.15) (layer "B.Cu") (net 166))
  (segment (start 85.5 114.91) (end 85.5 115.4) (width 0.15) (layer "B.Cu") (net 166))
  (segment (start 85.975 124.875) (end 85.475 124.875) (width 0.15) (layer "B.Cu") (net 166))
  (segment (start 85.99 115.4) (end 85.99 114.41) (width 0.15) (layer "B.Cu") (net 166))
  (segment (start 84.1 124.65) (end 83.5 124.65) (width 0.15) (layer "B.Cu") (net 166))
  (segment (start 84.475 124.875) (end 84.325 124.875) (width 0.15) (layer "B.Cu") (net 166))
  (segment (start 77.05 121.54) (end 78.09 121.54) (width 0.15) (layer "B.Cu") (net 166))
  (segment (start 83.6 124.65) (end 83.5 124.65) (width 0.15) (layer "B.Cu") (net 166))
  (segment (start 77.055 119.545) (end 77.05 119.54) (width 0.15) (layer "B.Cu") (net 166))
  (segment (start 83.495 124.65) (end 83.5 124.65) (width 0.15) (layer "B.Cu") (net 166))
  (segment (start 85.99 125.495) (end 85.99 124.89) (width 0.15) (layer "B.Cu") (net 166))
  (segment (start 85.49 125.495) (end 85.49 124.89) (width 0.15) (layer "B.Cu") (net 166))
  (segment (start 77.545 119.045) (end 77.05 119.54) (width 0.15) (layer "B.Cu") (net 166))
  (segment (start 84.99 124.89) (end 84.975 124.875) (width 0.15) (layer "B.Cu") (net 166))
  (segment (start 77.555 118.045) (end 77.05 118.55) (width 0.15) (layer "B.Cu") (net 166))
  (segment (start 77.055 118.545) (end 77.05 118.55) (width 0.15) (layer "B.Cu") (net 166))
  (segment (start 83.02 125.495) (end 83.02 125.175) (width 0.25) (layer "B.Cu") (net 166))
  (segment (start 83.5 114.91) (end 83 114.41) (width 0.15) (layer "B.Cu") (net 166))
  (segment (start 77.555 120.045) (end 77.05 120.55) (width 0.15) (layer "B.Cu") (net 166))
  (segment (start 77.54 121.05) (end 78.05 121.05) (width 0.15) (layer "B.Cu") (net 166))
  (segment (start 84.99 115.4) (end 84.99 114.42) (width 0.15) (layer "B.Cu") (net 166))
  (segment (start 86.49 125.04) (end 86.325 124.875) (width 0.15) (layer "B.Cu") (net 166))
  (segment (start 83.5 115.4) (end 83.5 114.91) (width 0.15) (layer "B.Cu") (net 166))
  (segment (start 84.975 124.875) (end 84.475 124.875) (width 0.15) (layer "B.Cu") (net 166))
  (segment (start 78.04 118.545) (end 77.055 118.545) (width 0.15) (layer "B.Cu") (net 166))
  (segment (start 84.5 114.92) (end 84.5 115.4) (width 0.15) (layer "B.Cu") (net 166))
  (segment (start 84.99 125.495) (end 84.99 124.89) (width 0.15) (layer "B.Cu") (net 166))
  (segment (start 85 114.41) (end 85.5 114.91) (width 0.15) (layer "B.Cu") (net 166))
  (segment (start 82.99 114.42) (end 83 114.41) (width 0.15) (layer "B.Cu") (net 166))
  (segment (start 83.99 125.495) (end 83.99 125.04) (width 0.15) (layer "B.Cu") (net 166))
  (segment (start 77.055 120.545) (end 77.05 120.55) (width 0.15) (layer "B.Cu") (net 166))
  (segment (start 84.325 124.875) (end 84.1 124.65) (width 0.15) (layer "B.Cu") (net 166))
  (segment (start 78.04 120.545) (end 77.055 120.545) (width 0.15) (layer "B.Cu") (net 166))
  (segment (start 83.99 125.04) (end 83.6 124.65) (width 0.15) (layer "B.Cu") (net 166))
  (segment (start 85.49 124.89) (end 85.475 124.875) (width 0.15) (layer "B.Cu") (net 166))
  (segment (start 82.99 115.4) (end 82.99 114.42) (width 0.15) (layer "B.Cu") (net 166))
  (segment (start 83.5 124.65) (end 83.5 125.5) (width 0.15) (layer "B.Cu") (net 166))
  (segment (start 86.49 115.4) (end 86.49 114.91) (width 0.15) (layer "B.Cu") (net 166))
  (segment (start 78.04 119.045) (end 77.545 119.045) (width 0.15) (layer "B.Cu") (net 166))
  (segment (start 78.04 118.045) (end 77.555 118.045) (width 0.15) (layer "B.Cu") (net 166))
  (segment (start 86.49 114.91) (end 85.99 114.41) (width 0.15) (layer "B.Cu") (net 166))
  (segment (start 86.49 125.495) (end 86.49 125.04) (width 0.15) (layer "B.Cu") (net 166))
  (segment (start 83.99 114.41) (end 84.5 114.92) (width 0.15) (layer "B.Cu") (net 166))
  (segment (start 85.99 124.89) (end 85.975 124.875) (width 0.15) (layer "B.Cu") (net 166))
  (segment (start 78.04 120.045) (end 77.555 120.045) (width 0.15) (layer "B.Cu") (net 166))
  (segment (start 83.99 115.4) (end 83.99 114.41) (width 0.15) (layer "B.Cu") (net 166))
  (segment (start 86.325 124.875) (end 85.975 124.875) (width 0.15) (layer "B.Cu") (net 166))
  (segment (start 77.05 121.54) (end 77.54 121.05) (width 0.15) (layer "B.Cu") (net 166))
  (segment (start 83.02 125.175) (end 83.63 124.565) (width 0.25) (layer "B.Cu") (net 166))
  (segment (start 92.8 144.7) (end 92.7 144.6) (width 0.1) (layer "F.Cu") (net 167))
  (segment (start 94.2 144.7) (end 92.8 144.7) (width 0.1) (layer "F.Cu") (net 167))
  (segment (start 106.4 109.75) (end 106.8 110.15) (width 0.15) (layer "F.Cu") (net 167))
  (segment (start 92.7 144.6) (end 92.1 144.6) (width 0.1) (layer "F.Cu") (net 167))
  (via (at 120.45 138.45) (size 0.5) (drill 0.2) (layers "F.Cu" "B.Cu") (net 167))
  (via (at 94.2 144.7) (size 0.5) (drill 0.2) (layers "F.Cu" "B.Cu") (net 167))
  (via (at 106.8 110.15) (size 0.5) (drill 0.2) (layers "F.Cu" "B.Cu") (net 167))
  (segment (start 108.411062 111.296614) (end 108.586503 111.472055) (width 0.1) (layer "In2.Cu") (net 167))
  (segment (start 120.000004 138.000004) (end 120.45 138.45) (width 0.1) (layer "In2.Cu") (net 167))
  (segment (start 107.8 110.55) (end 108.411062 111.161062) (width 0.1) (layer "In2.Cu") (net 167))
  (segment (start 120.000004 123.550004) (end 120.000004 138.000004) (width 0.1) (layer "In2.Cu") (net 167))
  (segment (start 107.2 110.55) (end 107.8 110.55) (width 0.1) (layer "In2.Cu") (net 167))
  (segment (start 106.8 110.15) (end 107.2 110.55) (width 0.1) (layer "In2.Cu") (net 167))
  (segment (start 108.411062 111.161062) (end 108.411062 111.296614) (width 0.1) (layer "In2.Cu") (net 167))
  (segment (start 108.586503 112.136503) (end 120.000004 123.550004) (width 0.1) (layer "In2.Cu") (net 167))
  (segment (start 108.586503 111.472055) (end 108.586503 112.136503) (width 0.1) (layer "In2.Cu") (net 167))
  (segment (start 94.808571 144.7) (end 95.358571 145.25) (width 0.1) (layer "In5.Cu") (net 167))
  (segment (start 95.358571 145.25) (end 115.56503 145.25) (width 0.1) (layer "In5.Cu") (net 167))
  (segment (start 120.096447 138.45) (end 120.45 138.45) (width 0.1) (layer "In5.Cu") (net 167))
  (segment (start 115.56503 145.25) (end 117.7 143.11503) (width 0.1) (layer "In5.Cu") (net 167))
  (segment (start 117.7 143.11503) (end 117.7 140.846445) (width 0.1) (layer "In5.Cu") (net 167))
  (segment (start 117.7 140.846445) (end 120.096447 138.45) (width 0.1) (layer "In5.Cu") (net 167))
  (segment (start 94.2 144.7) (end 94.808571 144.7) (width 0.1) (layer "In5.Cu") (net 167))
  (segment (start 94.2 144.7) (end 93.25 144.7) (width 0.1) (layer "B.Cu") (net 167))
  (segment (start 91.65 143.1) (end 91.15 143.1) (width 0.1) (layer "B.Cu") (net 167))
  (segment (start 93.25 144.7) (end 91.65 143.1) (width 0.1) (layer "B.Cu") (net 167))
  (segment (start 92.8 144.1) (end 92.1 144.1) (width 0.1) (layer "F.Cu") (net 168))
  (segment (start 107.5 108.15) (end 108 108.65) (width 0.15) (layer "F.Cu") (net 168))
  (segment (start 92.9 144.2) (end 92.8 144.1) (width 0.1) (layer "F.Cu") (net 168))
  (segment (start 107.2 108.15) (end 107.5 108.15) (width 0.15) (layer "F.Cu") (net 168))
  (segment (start 108 108.65) (end 108 108.85) (width 0.15) (layer "F.Cu") (net 168))
  (segment (start 93.65 144.2) (end 92.9 144.2) (width 0.1) (layer "F.Cu") (net 168))
  (via (at 108 108.85) (size 0.5) (drill 0.2) (layers "F.Cu" "B.Cu") (net 168))
  (via (at 120.7 137.45) (size 0.5) (drill 0.2) (layers "F.Cu" "B.Cu") (net 168))
  (via (at 93.65 144.2) (size 0.5) (drill 0.2) (layers "F.Cu" "B.Cu") (net 168))
  (segment (start 108 109.95) (end 108.811082 110.761082) (width 0.1) (layer "In2.Cu") (net 168))
  (segment (start 120.7 123.65) (end 120.7 137.45) (width 0.1) (layer "In2.Cu") (net 168))
  (segment (start 109.6 112.55) (end 120.7 123.65) (width 0.1) (layer "In2.Cu") (net 168))
  (segment (start 108.811082 110.761082) (end 108.811082 111.130918) (width 0.1) (layer "In2.Cu") (net 168))
  (segment (start 108 108.85) (end 108 109.95) (width 0.1) (layer "In2.Cu") (net 168))
  (segment (start 109.019082 111.338918) (end 109.388918 111.338918) (width 0.1) (layer "In2.Cu") (net 168))
  (segment (start 109.388918 111.338918) (end 109.6 111.55) (width 0.1) (layer "In2.Cu") (net 168))
  (segment (start 109.6 111.55) (end 109.6 112.55) (width 0.1) (layer "In2.Cu") (net 168))
  (segment (start 108.811082 111.130918) (end 109.019082 111.338918) (width 0.1) (layer "In2.Cu") (net 168))
  (segment (start 117.45 143.011474) (end 117.45 140.5) (width 0.1) (layer "In5.Cu") (net 168))
  (segment (start 117.45 140.5) (end 120.5 137.45) (width 0.1) (layer "In5.Cu") (net 168))
  (segment (start 120.5 137.45) (end 120.7 137.45) (width 0.1) (layer "In5.Cu") (net 168))
  (segment (start 95.625 145) (end 115.461474 145) (width 0.1) (layer "In5.Cu") (net 168))
  (segment (start 94.825 144.2) (end 95.625 145) (width 0.1) (layer "In5.Cu") (net 168))
  (segment (start 115.461474 145) (end 117.45 143.011474) (width 0.1) (layer "In5.Cu") (net 168))
  (segment (start 93.65 144.2) (end 94.825 144.2) (width 0.1) (layer "In5.Cu") (net 168))
  (segment (start 91.55 142.1) (end 91.15 142.1) (width 0.1) (layer "B.Cu") (net 168))
  (segment (start 93.65 144.2) (end 91.55 142.1) (width 0.1) (layer "B.Cu") (net 168))
  (segment (start 94.199976 145.649976) (end 94.2 145.65) (width 0.1) (layer "F.Cu") (net 169))
  (segment (start 106.4 110.55) (end 106.8 110.95) (width 0.15) (layer "F.Cu") (net 169))
  (segment (start 94.15 145.6) (end 92.15 145.6) (width 0.1) (layer "F.Cu") (net 169))
  (segment (start 94.2 145.65) (end 94.15 145.6) (width 0.1) (layer "F.Cu") (net 169))
  (via (at 119.8 140.35) (size 0.5) (drill 0.2) (layers "F.Cu" "B.Cu") (net 169))
  (via (at 94.2 145.65) (size 0.5) (drill 0.2) (layers "F.Cu" "B.Cu") (net 169))
  (via (at 106.8 110.95) (size 0.5) (drill 0.2) (layers "F.Cu" "B.Cu") (net 169))
  (segment (start 107.2 111.35) (end 107.2 111.984284) (width 0.1) (layer "In2.Cu") (net 169))
  (segment (start 106.8 110.95) (end 107.2 111.35) (width 0.1) (layer "In2.Cu") (net 169))
  (segment (start 108.167142 112.617142) (end 119.399971 123.849971) (width 0.1) (layer "In2.Cu") (net 169))
  (segment (start 119.399971 139.949971) (end 119.8 140.35) (width 0.1) (layer "In2.Cu") (net 169))
  (segment (start 107.832858 112.617142) (end 108.167142 112.617142) (width 0.1) (layer "In2.Cu") (net 169))
  (segment (start 107.2 111.984284) (end 107.832858 112.617142) (width 0.1) (layer "In2.Cu") (net 169))
  (segment (start 119.399971 123.849971) (end 119.399971 139.949971) (width 0.1) (layer "In2.Cu") (net 169))
  (segment (start 94.7 145.75) (end 115.772142 145.75) (width 0.1) (layer "In5.Cu") (net 169))
  (segment (start 94.2 145.65) (end 94.6 145.65) (width 0.1) (layer "In5.Cu") (net 169))
  (segment (start 118.2 141.25) (end 119.1 140.35) (width 0.1) (layer "In5.Cu") (net 169))
  (segment (start 115.772142 145.75) (end 118.2 143.322142) (width 0.1) (layer "In5.Cu") (net 169))
  (segment (start 119.1 140.35) (end 119.8 140.35) (width 0.1) (layer "In5.Cu") (net 169))
  (segment (start 94.6 145.65) (end 94.7 145.75) (width 0.1) (layer "In5.Cu") (net 169))
  (segment (start 118.2 143.322142) (end 118.2 141.25) (width 0.1) (layer "In5.Cu") (net 169))
  (segment (start 93.866025 145.65) (end 93.866001 145.649976) (width 0.1) (layer "B.Cu") (net 169))
  (segment (start 93.866001 145.649976) (end 92.199976 145.649976) (width 0.1) (layer "B.Cu") (net 169))
  (segment (start 91.65 145.1) (end 91.15 145.1) (width 0.1) (layer "B.Cu") (net 169))
  (segment (start 94.2 145.65) (end 93.866025 145.65) (width 0.1) (layer "B.Cu") (net 169))
  (segment (start 92.199976 145.649976) (end 91.65 145.1) (width 0.1) (layer "B.Cu") (net 169))
  (segment (start 107.2 112.15) (end 107.952197 112.15) (width 0.1) (layer "F.Cu") (net 170))
  (segment (start 93.6 145.1) (end 92.05 145.1) (width 0.1) (layer "F.Cu") (net 170))
  (segment (start 93.65 145.15) (end 93.6 145.1) (width 0.1) (layer "F.Cu") (net 170))
  (segment (start 107.952197 112.15) (end 107.98649 112.184293) (width 0.1) (layer "F.Cu") (net 170))
  (via (at 107.98649 112.184293) (size 0.5) (drill 0.2) (layers "F.Cu" "B.Cu") (net 170))
  (via (at 119.999957 139.75) (size 0.5) (drill 0.2) (layers "F.Cu" "B.Cu") (net 170))
  (via (at 93.65 145.15) (size 0.5) (drill 0.2) (layers "F.Cu" "B.Cu") (net 170))
  (segment (start 108.034293 112.184293) (end 119.599982 123.749982) (width 0.1) (layer "In2.Cu") (net 170))
  (segment (start 107.98649 112.184293) (end 108.034293 112.184293) (width 0.1) (layer "In2.Cu") (net 170))
  (segment (start 119.599982 139.350025) (end 119.999957 139.75) (width 0.1) (layer "In2.Cu") (net 170))
  (segment (start 119.599982 123.749982) (end 119.599982 139.350025) (width 0.1) (layer "In2.Cu") (net 170))
  (segment (start 117.95 143.218586) (end 117.95 141) (width 0.1) (layer "In5.Cu") (net 170))
  (segment (start 117.95 141) (end 119.2 139.75) (width 0.1) (layer "In5.Cu") (net 170))
  (segment (start 119.2 139.75) (end 119.999957 139.75) (width 0.1) (layer "In5.Cu") (net 170))
  (segment (start 93.65 145.15) (end 94.6 145.15) (width 0.1) (layer "In5.Cu") (net 170))
  (segment (start 94.95 145.5) (end 115.668586 145.5) (width 0.1) (layer "In5.Cu") (net 170))
  (segment (start 94.6 145.15) (end 94.95 145.5) (width 0.1) (layer "In5.Cu") (net 170))
  (segment (start 115.668586 145.5) (end 117.95 143.218586) (width 0.1) (layer "In5.Cu") (net 170))
  (segment (start 93.65 145.15) (end 92.75 145.15) (width 0.1) (layer "B.Cu") (net 170))
  (segment (start 92.75 145.15) (end 91.7 144.1) (width 0.1) (layer "B.Cu") (net 170))
  (segment (start 91.7 144.1) (end 91.15 144.1) (width 0.1) (layer "B.Cu") (net 170))
  (segment (start 94.149987 146.549987) (end 94.2 146.6) (width 0.1) (layer "F.Cu") (net 171))
  (segment (start 94.149987 146.549987) (end 92.150013 146.549987) (width 0.1) (layer "F.Cu") (net 171))
  (segment (start 106.8 112.55) (end 106.8 112.550008) (width 0.15) (layer "F.Cu") (net 171))
  (segment (start 106.4 112.15) (end 106.8 112.55) (width 0.15) (layer "F.Cu") (net 171))
  (via (at 119.2 141.55) (size 0.5) (drill 0.2) (layers "F.Cu" "B.Cu") (net 171))
  (via (at 94.2 146.6) (size 0.5) (drill 0.2) (layers "F.Cu" "B.Cu") (net 171))
  (via (at 106.8 112.550008) (size 0.5) (drill 0.2) (layers "F.Cu" "B.Cu") (net 171))
  (segment (start 106.8 112.550008) (end 106.800008 112.550008) (width 0.1) (layer "In2.Cu") (net 171))
  (segment (start 118.999949 141.349949) (end 119.2 141.55) (width 0.1) (layer "In2.Cu") (net 171))
  (segment (start 108 113.05) (end 118.999949 124.049949) (width 0.1) (layer "In2.Cu") (net 171))
  (segment (start 118.999949 124.049949) (end 118.999949 141.349949) (width 0.1) (layer "In2.Cu") (net 171))
  (segment (start 106.800008 112.550008) (end 107.3 113.05) (width 0.1) (layer "In2.Cu") (net 171))
  (segment (start 107.3 113.05) (end 108 113.05) (width 0.1) (layer "In2.Cu") (net 171))
  (segment (start 118.7 141.775) (end 118.925 141.55) (width 0.1) (layer "In5.Cu") (net 171))
  (segment (start 95.2 146.25) (end 115.979254 146.25) (width 0.1) (layer "In5.Cu") (net 171))
  (segment (start 94.2 146.6) (end 94.85 146.6) (width 0.1) (layer "In5.Cu") (net 171))
  (segment (start 94.85 146.6) (end 95.2 146.25) (width 0.1) (layer "In5.Cu") (net 171))
  (segment (start 118.7 143.529254) (end 118.7 141.775) (width 0.1) (layer "In5.Cu") (net 171))
  (segment (start 115.979254 146.25) (end 118.7 143.529254) (width 0.1) (layer "In5.Cu") (net 171))
  (segment (start 118.925 141.55) (end 119.2 141.55) (width 0.1) (layer "In5.Cu") (net 171))
  (segment (start 91.7 147.05) (end 91.2 147.05) (width 0.1) (layer "B.Cu") (net 171))
  (segment (start 94.2 146.6) (end 93.916014 146.6) (width 0.1) (layer "B.Cu") (net 171))
  (segment (start 93.916014 146.6) (end 93.866001 146.549987) (width 0.1) (layer "B.Cu") (net 171))
  (segment (start 93.866001 146.549987) (end 92.200013 146.549987) (width 0.1) (layer "B.Cu") (net 171))
  (segment (start 92.200013 146.549987) (end 91.7 147.05) (width 0.1) (layer "B.Cu") (net 171))
  (segment (start 106.4 111.35) (end 106.8 111.75) (width 0.15) (layer "F.Cu") (net 172))
  (segment (start 93.65 146.099977) (end 92.100023 146.099977) (width 0.1) (layer "F.Cu") (net 172))
  (via (at 106.8 111.75) (size 0.5) (drill 0.2) (layers "F.Cu" "B.Cu") (net 172))
  (via (at 119.5 140.95) (size 0.5) (drill 0.2) (layers "F.Cu" "B.Cu") (net 172))
  (via (at 93.65 146.099977) (size 0.5) (drill 0.2) (layers "F.Cu" "B.Cu") (net 172))
  (segment (start 108.099989 112.849989) (end 119.19996 123.94996) (width 0.1) (layer "In2.Cu") (net 172))
  (segment (start 119.19996 123.94996) (end 119.19996 140.64996) (width 0.1) (layer "In2.Cu") (net 172))
  (segment (start 119.19996 140.64996) (end 119.5 140.95) (width 0.1) (layer "In2.Cu") (net 172))
  (segment (start 106.8 111.867142) (end 107.782847 112.849989) (width 0.1) (layer "In2.Cu") (net 172))
  (segment (start 106.8 111.75) (end 106.8 111.867142) (width 0.1) (layer "In2.Cu") (net 172))
  (segment (start 107.782847 112.849989) (end 108.099989 112.849989) (width 0.1) (layer "In2.Cu") (net 172))
  (segment (start 94.7 146.099977) (end 94.799977 146) (width 0.1) (layer "In5.Cu") (net 172))
  (segment (start 115.875698 146) (end 118.45 143.425698) (width 0.1) (layer "In5.Cu") (net 172))
  (segment (start 118.45 141.448224) (end 118.948224 140.95) (width 0.1) (layer "In5.Cu") (net 172))
  (segment (start 94.799977 146) (end 115.875698 146) (width 0.1) (layer "In5.Cu") (net 172))
  (segment (start 118.948224 140.95) (end 119.5 140.95) (width 0.1) (layer "In5.Cu") (net 172))
  (segment (start 118.45 143.425698) (end 118.45 141.448224) (width 0.1) (layer "In5.Cu") (net 172))
  (segment (start 93.65 146.099977) (end 94.7 146.099977) (width 0.1) (layer "In5.Cu") (net 172))
  (segment (start 93.65 146.099977) (end 91.150023 146.099977) (width 0.1) (layer "B.Cu") (net 172))
  (segment (start 94.2 147.5) (end 94.15 147.45) (width 0.1) (layer "F.Cu") (net 173))
  (segment (start 91.25 147.45) (end 91.15 147.55) (width 0.1) (layer "F.Cu") (net 173))
  (segment (start 94.149998 147.449998) (end 94.2 147.5) (width 0.1) (layer "F.Cu") (net 173))
  (segment (start 94.15 147.45) (end 91.25 147.45) (width 0.1) (layer "F.Cu") (net 173))
  (segment (start 107.2 109.75) (end 107.6 110.15) (width 0.15) (layer "F.Cu") (net 173))
  (via (at 107.6 110.15) (size 0.5) (drill 0.2) (layers "F.Cu" "B.Cu") (net 173))
  (via (at 94.2 147.5) (size 0.5) (drill 0.2) (layers "F.Cu" "B.Cu") (net 173))
  (via (at 120.45 141) (size 0.5) (drill 0.2) (layers "F.Cu" "B.Cu") (net 173))
  (segment (start 108.611071 111.078213) (end 108.611072 111.213766) (width 0.1) (layer "In2.Cu") (net 173))
  (segment (start 108.8 112.05) (end 120.200015 123.450015) (width 0.1) (layer "In2.Cu") (net 173))
  (segment (start 120.200015 137.550015) (end 120.949999 138.299999) (width 0.1) (layer "In2.Cu") (net 173))
  (segment (start 120.200015 123.450015) (end 120.200015 137.550015) (width 0.1) (layer "In2.Cu") (net 173))
  (segment (start 107.6 110.15) (end 107.682858 110.15) (width 0.1) (layer "In2.Cu") (net 173))
  (segment (start 108.8 111.402694) (end 108.8 112.05) (width 0.1) (layer "In2.Cu") (net 173))
  (segment (start 120.949999 140.500001) (end 120.45 141) (width 0.1) (layer "In2.Cu") (net 173))
  (segment (start 107.682858 110.15) (end 108.611071 111.078213) (width 0.1) (layer "In2.Cu") (net 173))
  (segment (start 108.611072 111.213766) (end 108.8 111.402694) (width 0.1) (layer "In2.Cu") (net 173))
  (segment (start 120.949999 138.299999) (end 120.949999 140.500001) (width 0.1) (layer "In2.Cu") (net 173))
  (segment (start 120.45 142.486366) (end 120.45 141) (width 0.1) (layer "In5.Cu") (net 173))
  (segment (start 115.436366 147.5) (end 120.45 142.486366) (width 0.1) (layer "In5.Cu") (net 173))
  (segment (start 94.2 147.5) (end 115.436366 147.5) (width 0.1) (layer "In5.Cu") (net 173))
  (segment (start 91.7 149.05) (end 91.2 149.05) (width 0.1) (layer "B.Cu") (net 173))
  (segment (start 93.3 147.45) (end 91.7 149.05) (width 0.1) (layer "B.Cu") (net 173))
  (segment (start 94.15 147.45) (end 93.3 147.45) (width 0.1) (layer "B.Cu") (net 173))
  (segment (start 94.2 147.5) (end 94.15 147.45) (width 0.1) (layer "B.Cu") (net 173))
  (segment (start 93.65 146.999988) (end 93.549988 147.1) (width 0.1) (layer "F.Cu") (net 174))
  (segment (start 107.2 110.55) (end 107.6 110.95) (width 0.15) (layer "F.Cu") (net 174))
  (segment (start 93.549988 147.1) (end 92.1 147.1) (width 0.1) (layer "F.Cu") (net 174))
  (via (at 120.45 139.15) (size 0.5) (drill 0.2) (layers "F.Cu" "B.Cu") (net 174))
  (via (at 93.65 146.999988) (size 0.5) (drill 0.2) (layers "F.Cu" "B.Cu") (net 174))
  (via (at 107.6 110.95) (size 0.5) (drill 0.2) (layers "F.Cu" "B.Cu") (net 174))
  (segment (start 119.799993 138.499993) (end 120.45 139.15) (width 0.1) (layer "In2.Cu") (net 174))
  (segment (start 119.799993 123.649993) (end 119.799993 138.499993) (width 0.1) (layer "In2.Cu") (net 174))
  (segment (start 108.386492 112.236492) (end 119.799993 123.649993) (width 0.1) (layer "In2.Cu") (net 174))
  (segment (start 108.386492 111.736492) (end 108.386492 112.236492) (width 0.1) (layer "In2.Cu") (net 174))
  (segment (start 107.6 110.95) (end 108.386492 111.736492) (width 0.1) (layer "In2.Cu") (net 174))
  (segment (start 115.53281 147.05) (end 120.049998 142.532812) (width 0.1) (layer "In5.Cu") (net 174))
  (segment (start 93.700012 147.05) (end 115.53281 147.05) (width 0.1) (layer "In5.Cu") (net 174))
  (segment (start 120.45 140.407996) (end 120.45 139.15) (width 0.1) (layer "In5.Cu") (net 174))
  (segment (start 120.049998 142.532812) (end 120.049998 140.807998) (width 0.1) (layer "In5.Cu") (net 174))
  (segment (start 93.65 146.999988) (end 93.700012 147.05) (width 0.1) (layer "In5.Cu") (net 174))
  (segment (start 120.049998 140.807998) (end 120.45 140.407996) (width 0.1) (layer "In5.Cu") (net 174))
  (segment (start 93.65 146.999988) (end 92.700012 146.999988) (width 0.1) (layer "B.Cu") (net 174))
  (segment (start 91.65 148.05) (end 91.15 148.05) (width 0.1) (layer "B.Cu") (net 174))
  (segment (start 92.700012 146.999988) (end 91.65 148.05) (width 0.1) (layer "B.Cu") (net 174))
  (segment (start 81.9 127.75) (end 82.3 128.15) (width 0.1) (layer "F.Cu") (net 175))
  (segment (start 93.6 125.75) (end 93.2 126.15) (width 0.1) (layer "F.Cu") (net 175))
  (via (at 82.3 128.15) (size 0.5) (drill 0.2) (layers "F.Cu" "B.Cu") (net 175))
  (via (at 93.2 126.15) (size 0.5) (drill 0.2) (layers "F.Cu" "B.Cu") (net 175))
  (segment (start 82.1 127.8) (end 82.4 127.5) (width 0.1) (layer "In5.Cu") (net 175))
  (segment (start 83.259903 127.556611) (end 83.271816 127.537651) (width 0.1) (layer "In5.Cu") (net 175))
  (segment (start 82.847492 128.02007) (end 82.85 127.997818) (width 0.1) (layer "In5.Cu") (net 175))
  (segment (start 82.772252 128.09531) (end 82.793388 128.087914) (width 0.1) (layer "In5.Cu") (net 175))
  (segment (start 82.4 127.5) (end 82.55 127.5) (width 0.1) (layer "In5.Cu") (net 175))
  (segment (start 83.047492 127.577747) (end 83.05 127.6) (width 0.1) (layer "In5.Cu") (net 175))
  (segment (start 83.052507 128.02007) (end 83.059903 128.041206) (width 0.1) (layer "In5.Cu") (net 175))
  (segment (start 83.028183 127.537651) (end 83.040096 127.556611) (width 0.1) (layer "In5.Cu") (net 175))
  (segment (start 82.972252 127.502507) (end 82.993388 127.509903) (width 0.1) (layer "In5.Cu") (net 175))
  (segment (start 83.212348 128.076001) (end 83.228183 128.060166) (width 0.1) (layer "In5.Cu") (net 175))
  (segment (start 82.871816 127.537651) (end 82.887651 127.521816) (width 0.1) (layer "In5.Cu") (net 175))
  (segment (start 82.706611 128.087914) (end 82.727747 128.09531) (width 0.1) (layer "In5.Cu") (net 175))
  (segment (start 83.15 128.097818) (end 83.172252 128.09531) (width 0.1) (layer "In5.Cu") (net 175))
  (segment (start 83.059903 128.041206) (end 83.071816 128.060166) (width 0.1) (layer "In5.Cu") (net 175))
  (segment (start 82.659903 128.041206) (end 82.671816 128.060166) (width 0.1) (layer "In5.Cu") (net 175))
  (segment (start 82.95 127.5) (end 82.972252 127.502507) (width 0.1) (layer "In5.Cu") (net 175))
  (segment (start 82.852507 127.577747) (end 82.859903 127.556611) (width 0.1) (layer "In5.Cu") (net 175))
  (segment (start 82.1 127.95) (end 82.1 127.8) (width 0.1) (layer "In5.Cu") (net 175))
  (segment (start 83.271816 127.537651) (end 83.287651 127.521816) (width 0.1) (layer "In5.Cu") (net 175))
  (segment (start 83.327747 127.502507) (end 83.35 127.5) (width 0.1) (layer "In5.Cu") (net 175))
  (segment (start 83.35 127.5) (end 84.4 127.5) (width 0.1) (layer "In5.Cu") (net 175))
  (segment (start 83.05 127.997818) (end 83.052507 128.02007) (width 0.1) (layer "In5.Cu") (net 175))
  (segment (start 83.106611 128.087914) (end 83.127747 128.09531) (width 0.1) (layer "In5.Cu") (net 175))
  (segment (start 90.55 127.75) (end 92.15 126.15) (width 0.1) (layer "In5.Cu") (net 175))
  (segment (start 82.65 127.997818) (end 82.652507 128.02007) (width 0.1) (layer "In5.Cu") (net 175))
  (segment (start 82.859903 127.556611) (end 82.871816 127.537651) (width 0.1) (layer "In5.Cu") (net 175))
  (segment (start 82.85 127.997818) (end 82.85 127.6) (width 0.1) (layer "In5.Cu") (net 175))
  (segment (start 82.640096 127.556611) (end 82.647492 127.577747) (width 0.1) (layer "In5.Cu") (net 175))
  (segment (start 82.572252 127.502507) (end 82.593388 127.509903) (width 0.1) (layer "In5.Cu") (net 175))
  (segment (start 83.127747 128.09531) (end 83.15 128.097818) (width 0.1) (layer "In5.Cu") (net 175))
  (segment (start 82.906611 127.509903) (end 82.927747 127.502507) (width 0.1) (layer "In5.Cu") (net 175))
  (segment (start 82.628183 127.537651) (end 82.640096 127.556611) (width 0.1) (layer "In5.Cu") (net 175))
  (segment (start 83.193388 128.087914) (end 83.212348 128.076001) (width 0.1) (layer "In5.Cu") (net 175))
  (segment (start 82.85 127.6) (end 82.852507 127.577747) (width 0.1) (layer "In5.Cu") (net 175))
  (segment (start 82.828183 128.060166) (end 82.840096 128.041206) (width 0.1) (layer "In5.Cu") (net 175))
  (segment (start 82.812348 128.076001) (end 82.828183 128.060166) (width 0.1) (layer "In5.Cu") (net 175))
  (segment (start 83.306611 127.509903) (end 83.327747 127.502507) (width 0.1) (layer "In5.Cu") (net 175))
  (segment (start 83.25 127.997818) (end 83.25 127.6) (width 0.1) (layer "In5.Cu") (net 175))
  (segment (start 84.4 127.5) (end 84.65 127.75) (width 0.1) (layer "In5.Cu") (net 175))
  (segment (start 82.927747 127.502507) (end 82.95 127.5) (width 0.1) (layer "In5.Cu") (net 175))
  (segment (start 83.228183 128.060166) (end 83.240096 128.041206) (width 0.1) (layer "In5.Cu") (net 175))
  (segment (start 82.612348 127.521816) (end 82.628183 127.537651) (width 0.1) (layer "In5.Cu") (net 175))
  (segment (start 82.55 127.5) (end 82.572252 127.502507) (width 0.1) (layer "In5.Cu") (net 175))
  (segment (start 82.75 128.097818) (end 82.772252 128.09531) (width 0.1) (layer "In5.Cu") (net 175))
  (segment (start 83.172252 128.09531) (end 83.193388 128.087914) (width 0.1) (layer "In5.Cu") (net 175))
  (segment (start 83.252507 127.577747) (end 83.259903 127.556611) (width 0.1) (layer "In5.Cu") (net 175))
  (segment (start 84.65 127.75) (end 90.55 127.75) (width 0.1) (layer "In5.Cu") (net 175))
  (segment (start 83.05 127.6) (end 83.05 127.997818) (width 0.1) (layer "In5.Cu") (net 175))
  (segment (start 82.887651 127.521816) (end 82.906611 127.509903) (width 0.1) (layer "In5.Cu") (net 175))
  (segment (start 82.993388 127.509903) (end 83.012348 127.521816) (width 0.1) (layer "In5.Cu") (net 175))
  (segment (start 83.287651 127.521816) (end 83.306611 127.509903) (width 0.1) (layer "In5.Cu") (net 175))
  (segment (start 82.65 127.6) (end 82.65 127.997818) (width 0.1) (layer "In5.Cu") (net 175))
  (segment (start 83.012348 127.521816) (end 83.028183 127.537651) (width 0.1) (layer "In5.Cu") (net 175))
  (segment (start 92.15 126.15) (end 93.2 126.15) (width 0.1) (layer "In5.Cu") (net 175))
  (segment (start 82.727747 128.09531) (end 82.75 128.097818) (width 0.1) (layer "In5.Cu") (net 175))
  (segment (start 82.593388 127.509903) (end 82.612348 127.521816) (width 0.1) (layer "In5.Cu") (net 175))
  (segment (start 83.071816 128.060166) (end 83.087651 128.076001) (width 0.1) (layer "In5.Cu") (net 175))
  (segment (start 83.25 127.6) (end 83.252507 127.577747) (width 0.1) (layer "In5.Cu") (net 175))
  (segment (start 82.840096 128.041206) (end 82.847492 128.02007) (width 0.1) (layer "In5.Cu") (net 175))
  (segment (start 83.087651 128.076001) (end 83.106611 128.087914) (width 0.1) (layer "In5.Cu") (net 175))
  (segment (start 83.240096 128.041206) (end 83.247492 128.02007) (width 0.1) (layer "In5.Cu") (net 175))
  (segment (start 82.3 128.15) (end 82.1 127.95) (width 0.1) (layer "In5.Cu") (net 175))
  (segment (start 82.647492 127.577747) (end 82.65 127.6) (width 0.1) (layer "In5.Cu") (net 175))
  (segment (start 83.247492 128.02007) (end 83.25 127.997818) (width 0.1) (layer "In5.Cu") (net 175))
  (segment (start 82.671816 128.060166) (end 82.687651 128.076001) (width 0.1) (layer "In5.Cu") (net 175))
  (segment (start 82.687651 128.076001) (end 82.706611 128.087914) (width 0.1) (layer "In5.Cu") (net 175))
  (segment (start 82.793388 128.087914) (end 82.812348 128.076001) (width 0.1) (layer "In5.Cu") (net 175))
  (segment (start 82.652507 128.02007) (end 82.659903 128.041206) (width 0.1) (layer "In5.Cu") (net 175))
  (segment (start 83.040096 127.556611) (end 83.047492 127.577747) (width 0.1) (layer "In5.Cu") (net 175))
  (segment (start 81.9 128.55) (end 81.5 128.15) (width 0.1) (layer "F.Cu") (net 176))
  (segment (start 92.8 124.95) (end 92.4 125.35) (width 0.1) (layer "F.Cu") (net 176))
  (via (at 81.5 128.15) (size 0.5) (drill 0.2) (layers "F.Cu" "B.Cu") (net 176))
  (via (at 92.4 125.35) (size 0.5) (drill 0.2) (layers "F.Cu" "B.Cu") (net 176))
  (segment (start 82.947492 127.222253) (end 82.95 127.2) (width 0.1) (layer "In5.Cu") (net 176))
  (segment (start 92.4 125.575) (end 92.4 125.35) (width 0.1) (layer "In5.Cu") (net 176))
  (segment (start 82.827747 127.297493) (end 82.85 127.3) (width 0.1) (layer "In5.Cu") (net 176))
  (segment (start 83.072252 126.705839) (end 83.093388 126.713235) (width 0.1) (layer "In5.Cu") (net 176))
  (segment (start 82.806611 127.290097) (end 82.827747 127.297493) (width 0.1) (layer "In5.Cu") (net 176))
  (segment (start 82.65 126.703331) (end 82.672252 126.705839) (width 0.1) (layer "In5.Cu") (net 176))
  (segment (start 83.05 126.703331) (end 83.072252 126.705839) (width 0.1) (layer "In5.Cu") (net 176))
  (segment (start 82.493388 127.290097) (end 82.512348 127.278184) (width 0.1) (layer "In5.Cu") (net 176))
  (segment (start 82.971816 126.740983) (end 82.987651 126.725148) (width 0.1) (layer "In5.Cu") (net 176))
  (segment (start 82.627747 126.705839) (end 82.65 126.703331) (width 0.1) (layer "In5.Cu") (net 176))
  (segment (start 81.5 128.1) (end 82.3 127.3) (width 0.1) (layer "In5.Cu") (net 176))
  (segment (start 82.912348 127.278184) (end 82.928183 127.262349) (width 0.1) (layer "In5.Cu") (net 176))
  (segment (start 83.206611 127.290097) (end 83.227747 127.297493) (width 0.1) (layer "In5.Cu") (net 176))
  (segment (start 82.528183 127.262349) (end 82.540096 127.243389) (width 0.1) (layer "In5.Cu") (net 176))
  (segment (start 83.25 127.3) (end 84.5 127.3) (width 0.1) (layer "In5.Cu") (net 176))
  (segment (start 82.771816 127.262349) (end 82.787651 127.278184) (width 0.1) (layer "In5.Cu") (net 176))
  (segment (start 83.112348 126.725148) (end 83.128183 126.740983) (width 0.1) (layer "In5.Cu") (net 176))
  (segment (start 82.3 127.3) (end 82.45 127.3) (width 0.1) (layer "In5.Cu") (net 176))
  (segment (start 82.55 126.803331) (end 82.552507 126.781079) (width 0.1) (layer "In5.Cu") (net 176))
  (segment (start 82.759903 127.243389) (end 82.771816 127.262349) (width 0.1) (layer "In5.Cu") (net 176))
  (segment (start 82.940096 127.243389) (end 82.947492 127.222253) (width 0.1) (layer "In5.Cu") (net 176))
  (segment (start 82.587651 126.725148) (end 82.606611 126.713235) (width 0.1) (layer "In5.Cu") (net 176))
  (segment (start 82.712348 126.725148) (end 82.728183 126.740983) (width 0.1) (layer "In5.Cu") (net 176))
  (segment (start 82.95 127.2) (end 82.95 126.803331) (width 0.1) (layer "In5.Cu") (net 176))
  (segment (start 82.75 126.803331) (end 82.75 127.2) (width 0.1) (layer "In5.Cu") (net 176))
  (segment (start 84.75 127.55) (end 90.425 127.55) (width 0.1) (layer "In5.Cu") (net 176))
  (segment (start 90.425 127.55) (end 92.4 125.575) (width 0.1) (layer "In5.Cu") (net 176))
  (segment (start 82.547492 127.222253) (end 82.55 127.2) (width 0.1) (layer "In5.Cu") (net 176))
  (segment (start 83.159903 127.243389) (end 83.171816 127.262349) (width 0.1) (layer "In5.Cu") (net 176))
  (segment (start 82.987651 126.725148) (end 83.006611 126.713235) (width 0.1) (layer "In5.Cu") (net 176))
  (segment (start 82.571816 126.740983) (end 82.587651 126.725148) (width 0.1) (layer "In5.Cu") (net 176))
  (segment (start 82.787651 127.278184) (end 82.806611 127.290097) (width 0.1) (layer "In5.Cu") (net 176))
  (segment (start 83.140096 126.759943) (end 83.147492 126.781079) (width 0.1) (layer "In5.Cu") (net 176))
  (segment (start 82.55 127.2) (end 82.55 126.803331) (width 0.1) (layer "In5.Cu") (net 176))
  (segment (start 82.672252 126.705839) (end 82.693388 126.713235) (width 0.1) (layer "In5.Cu") (net 176))
  (segment (start 83.147492 126.781079) (end 83.15 126.803331) (width 0.1) (layer "In5.Cu") (net 176))
  (segment (start 83.187651 127.278184) (end 83.206611 127.290097) (width 0.1) (layer "In5.Cu") (net 176))
  (segment (start 82.952507 126.781079) (end 82.959903 126.759943) (width 0.1) (layer "In5.Cu") (net 176))
  (segment (start 82.959903 126.759943) (end 82.971816 126.740983) (width 0.1) (layer "In5.Cu") (net 176))
  (segment (start 82.540096 127.243389) (end 82.547492 127.222253) (width 0.1) (layer "In5.Cu") (net 176))
  (segment (start 82.747492 126.781079) (end 82.75 126.803331) (width 0.1) (layer "In5.Cu") (net 176))
  (segment (start 83.006611 126.713235) (end 83.027747 126.705839) (width 0.1) (layer "In5.Cu") (net 176))
  (segment (start 82.472252 127.297493) (end 82.493388 127.290097) (width 0.1) (layer "In5.Cu") (net 176))
  (segment (start 82.928183 127.262349) (end 82.940096 127.243389) (width 0.1) (layer "In5.Cu") (net 176))
  (segment (start 83.15 127.2) (end 83.152507 127.222253) (width 0.1) (layer "In5.Cu") (net 176))
  (segment (start 82.552507 126.781079) (end 82.559903 126.759943) (width 0.1) (layer "In5.Cu") (net 176))
  (segment (start 82.728183 126.740983) (end 82.740096 126.759943) (width 0.1) (layer "In5.Cu") (net 176))
  (segment (start 82.45 127.3) (end 82.472252 127.297493) (width 0.1) (layer "In5.Cu") (net 176))
  (segment (start 83.027747 126.705839) (end 83.05 126.703331) (width 0.1) (layer "In5.Cu") (net 176))
  (segment (start 82.606611 126.713235) (end 82.627747 126.705839) (width 0.1) (layer "In5.Cu") (net 176))
  (segment (start 83.227747 127.297493) (end 83.25 127.3) (width 0.1) (layer "In5.Cu") (net 176))
  (segment (start 81.5 128.15) (end 81.5 128.1) (width 0.1) (layer "In5.Cu") (net 176))
  (segment (start 82.872252 127.297493) (end 82.893388 127.290097) (width 0.1) (layer "In5.Cu") (net 176))
  (segment (start 83.15 126.803331) (end 83.15 127.2) (width 0.1) (layer "In5.Cu") (net 176))
  (segment (start 83.128183 126.740983) (end 83.140096 126.759943) (width 0.1) (layer "In5.Cu") (net 176))
  (segment (start 82.559903 126.759943) (end 82.571816 126.740983) (width 0.1) (layer "In5.Cu") (net 176))
  (segment (start 82.512348 127.278184) (end 82.528183 127.262349) (width 0.1) (layer "In5.Cu") (net 176))
  (segment (start 82.75 127.2) (end 82.752507 127.222253) (width 0.1) (layer "In5.Cu") (net 176))
  (segment (start 82.740096 126.759943) (end 82.747492 126.781079) (width 0.1) (layer "In5.Cu") (net 176))
  (segment (start 83.093388 126.713235) (end 83.112348 126.725148) (width 0.1) (layer "In5.Cu") (net 176))
  (segment (start 82.95 126.803331) (end 82.952507 126.781079) (width 0.1) (layer "In5.Cu") (net 176))
  (segment (start 83.171816 127.262349) (end 83.187651 127.278184) (width 0.1) (layer "In5.Cu") (net 176))
  (segment (start 84.5 127.3) (end 84.75 127.55) (width 0.1) (layer "In5.Cu") (net 176))
  (segment (start 82.85 127.3) (end 82.872252 127.297493) (width 0.1) (layer "In5.Cu") (net 176))
  (segment (start 82.693388 126.713235) (end 82.712348 126.725148) (width 0.1) (layer "In5.Cu") (net 176))
  (segment (start 83.152507 127.222253) (end 83.159903 127.243389) (width 0.1) (layer "In5.Cu") (net 176))
  (segment (start 82.752507 127.222253) (end 82.759903 127.243389) (width 0.1) (layer "In5.Cu") (net 176))
  (segment (start 82.893388 127.290097) (end 82.912348 127.278184) (width 0.1) (layer "In5.Cu") (net 176))
  (segment (start 85.1 124.55) (end 84.7 124.95) (width 0.1) (layer "F.Cu") (net 177))
  (segment (start 89.85 125.15) (end 89.85 124.45) (width 0.1) (layer "F.Cu") (net 177))
  (segment (start 89.75 125.25) (end 89.85 125.15) (width 0.1) (layer "F.Cu") (net 177))
  (segment (start 89.85 124.45) (end 90.35 123.95) (width 0.1) (layer "F.Cu") (net 177))
  (segment (start 89.4 125.05) (end 89.6 125.25) (width 0.1) (layer "F.Cu") (net 177))
  (segment (start 90.35 123.95) (end 94.925 123.95) (width 0.1) (layer "F.Cu") (net 177))
  (segment (start 89.6 125.25) (end 89.75 125.25) (width 0.1) (layer "F.Cu") (net 177))
  (segment (start 94.925 123.95) (end 95.925 124.95) (width 0.1) (layer "F.Cu") (net 177))
  (via blind (at 84.7 124.95) (size 0.5) (drill 0.2) (layers "F.Cu" "In5.Cu") (net 177))
  (via (at 89.4 125.05) (size 0.5) (drill 0.2) (layers "F.Cu" "B.Cu") (net 177))
  (segment (start 85.727747 124.947492) (end 85.706611 124.940096) (width 0.1) (layer "In5.Cu") (net 177))
  (segment (start 85.25 125.064426) (end 85.25 125.05) (width 0.1) (layer "In5.Cu") (net 177))
  (segment (start 85.506611 124.645477) (end 85.487651 124.65739) (width 0.1) (layer "In5.Cu") (net 177))
  (segment (start 85.75 124.95) (end 85.727747 124.947492) (width 0.1) (layer "In5.Cu") (net 177))
  (segment (start 85.25 125.05) (end 85.247492 125.027748) (width 0.1) (layer "In5.Cu") (net 177))
  (segment (start 85.55 124.635574) (end 85.527747 124.638081) (width 0.1) (layer "In5.Cu") (net 177))
  (segment (start 85.252507 125.086679) (end 85.25 125.064426) (width 0.1) (layer "In5.Cu") (net 177))
  (segment (start 85.65 124.735574) (end 85.647492 124.713321) (width 0.1) (layer "In5.Cu") (net 177))
  (segment (start 85.240096 125.006612) (end 85.228183 124.987652) (width 0.1) (layer "In5.Cu") (net 177))
  (segment (start 89.4 125.05) (end 89.25 125.2) (width 0.1) (layer "In5.Cu") (net 177))
  (segment (start 89.25 125.2) (end 89.15 125.2) (width 0.1) (layer "In5.Cu") (net 177))
  (segment (start 85.65 124.85) (end 85.65 124.735574) (width 0.1) (layer "In5.Cu") (net 177))
  (segment (start 85.612348 124.65739) (end 85.593388 124.645477) (width 0.1) (layer "In5.Cu") (net 177))
  (segment (start 88.35 123.75) (end 87.15 123.75) (width 0.1) (layer "In5.Cu") (net 177))
  (segment (start 85.45 125.064426) (end 85.447492 125.086679) (width 0.1) (layer "In5.Cu") (net 177))
  (segment (start 85.671816 124.912348) (end 85.659903 124.893388) (width 0.1) (layer "In5.Cu") (net 177))
  (segment (start 85.45 124.735574) (end 85.45 125.064426) (width 0.1) (layer "In5.Cu") (net 177))
  (segment (start 85.193388 124.959904) (end 85.172252 124.952508) (width 0.1) (layer "In5.Cu") (net 177))
  (segment (start 85.459903 124.692185) (end 85.452507 124.713321) (width 0.1) (layer "In5.Cu") (net 177))
  (segment (start 85.593388 124.645477) (end 85.572252 124.638081) (width 0.1) (layer "In5.Cu") (net 177))
  (segment (start 89.15 125.2) (end 88.85 124.9) (width 0.1) (layer "In5.Cu") (net 177))
  (segment (start 85.327747 125.161919) (end 85.306611 125.154523) (width 0.1) (layer "In5.Cu") (net 177))
  (segment (start 85.647492 124.713321) (end 85.640096 124.692185) (width 0.1) (layer "In5.Cu") (net 177))
  (segment (start 85.15 124.95) (end 84.81497 124.95) (width 0.1) (layer "In5.Cu") (net 177))
  (segment (start 85.652507 124.872252) (end 85.65 124.85) (width 0.1) (layer "In5.Cu") (net 177))
  (segment (start 87.15 123.75) (end 85.95 124.95) (width 0.1) (layer "In5.Cu") (net 177))
  (segment (start 85.428183 125.126775) (end 85.412348 125.14261) (width 0.1) (layer "In5.Cu") (net 177))
  (segment (start 88.85 124.9) (end 88.85 124.25) (width 0.1) (layer "In5.Cu") (net 177))
  (segment (start 85.487651 124.65739) (end 85.471816 124.673225) (width 0.1) (layer "In5.Cu") (net 177))
  (segment (start 85.572252 124.638081) (end 85.55 124.635574) (width 0.1) (layer "In5.Cu") (net 177))
  (segment (start 85.228183 124.987652) (end 85.212348 124.971817) (width 0.1) (layer "In5.Cu") (net 177))
  (segment (start 85.628183 124.673225) (end 85.612348 124.65739) (width 0.1) (layer "In5.Cu") (net 177))
  (segment (start 85.452507 124.713321) (end 85.45 124.735574) (width 0.1) (layer "In5.Cu") (net 177))
  (segment (start 85.447492 125.086679) (end 85.440096 125.107815) (width 0.1) (layer "In5.Cu") (net 177))
  (segment (start 85.247492 125.027748) (end 85.240096 125.006612) (width 0.1) (layer "In5.Cu") (net 177))
  (segment (start 85.471816 124.673225) (end 85.459903 124.692185) (width 0.1) (layer "In5.Cu") (net 177))
  (segment (start 85.706611 124.940096) (end 85.687651 124.928183) (width 0.1) (layer "In5.Cu") (net 177))
  (segment (start 85.372252 125.161919) (end 85.35 125.164426) (width 0.1) (layer "In5.Cu") (net 177))
  (segment (start 85.393388 125.154523) (end 85.372252 125.161919) (width 0.1) (layer "In5.Cu") (net 177))
  (segment (start 84.81497 124.95) (end 84.7 124.95) (width 0.1) (layer "In5.Cu") (net 177))
  (segment (start 85.306611 125.154523) (end 85.287651 125.14261) (width 0.1) (layer "In5.Cu") (net 177))
  (segment (start 85.687651 124.928183) (end 85.671816 124.912348) (width 0.1) (layer "In5.Cu") (net 177))
  (segment (start 85.212348 124.971817) (end 85.193388 124.959904) (width 0.1) (layer "In5.Cu") (net 177))
  (segment (start 85.95 124.95) (end 85.75 124.95) (width 0.1) (layer "In5.Cu") (net 177))
  (segment (start 85.259903 125.107815) (end 85.252507 125.086679) (width 0.1) (layer "In5.Cu") (net 177))
  (segment (start 88.85 124.25) (end 88.35 123.75) (width 0.1) (layer "In5.Cu") (net 177))
  (segment (start 85.35 125.164426) (end 85.327747 125.161919) (width 0.1) (layer "In5.Cu") (net 177))
  (segment (start 85.412348 125.14261) (end 85.393388 125.154523) (width 0.1) (layer "In5.Cu") (net 177))
  (segment (start 85.271816 125.126775) (end 85.259903 125.107815) (width 0.1) (layer "In5.Cu") (net 177))
  (segment (start 85.640096 124.692185) (end 85.628183 124.673225) (width 0.1) (layer "In5.Cu") (net 177))
  (segment (start 85.659903 124.893388) (end 85.652507 124.872252) (width 0.1) (layer "In5.Cu") (net 177))
  (segment (start 85.287651 125.14261) (end 85.271816 125.126775) (width 0.1) (layer "In5.Cu") (net 177))
  (segment (start 85.440096 125.107815) (end 85.428183 125.126775) (width 0.1) (layer "In5.Cu") (net 177))
  (segment (start 85.527747 124.638081) (end 85.506611 124.645477) (width 0.1) (layer "In5.Cu") (net 177))
  (segment (start 85.172252 124.952508) (end 85.15 124.95) (width 0.1) (layer "In5.Cu") (net 177))
  (segment (start 83.15 126.4) (end 82.15 126.4) (width 0.1) (layer "F.Cu") (net 178))
  (segment (start 96.8 126.55) (end 96.4 126.15) (width 0.1) (layer "F.Cu") (net 178))
  (segment (start 82.15 126.4) (end 81.9 126.15) (width 0.1) (layer "F.Cu") (net 178))
  (segment (start 83.25 126.3) (end 83.15 126.4) (width 0.1) (layer "F.Cu") (net 178))
  (via (at 83.25 126.3) (size 0.5) (drill 0.2) (layers "F.Cu" "B.Cu") (net 178))
  (via (at 96.4 126.15) (size 0.5) (drill 0.2) (layers "F.Cu" "B.Cu") (net 178))
  (segment (start 85.25 126.15) (end 90.25 126.15) (width 0.1) (layer "B.Cu") (net 178))
  (segment (start 90.25 126.15) (end 90.65 125.75) (width 0.1) (layer "B.Cu") (net 178))
  (segment (start 90.65 125.75) (end 96 125.75) (width 0.1) (layer "B.Cu") (net 178))
  (segment (start 96 125.75) (end 96.4 126.15) (width 0.1) (layer "B.Cu") (net 178))
  (segment (start 85.1 126.3) (end 85.25 126.15) (width 0.1) (layer "B.Cu") (net 178))
  (segment (start 83.25 126.3) (end 85.1 126.3) (width 0.1) (layer "B.Cu") (net 178))
  (segment (start 84.487651 129.121817) (end 84.506611 129.109904) (width 0.1) (layer "F.Cu") (net 179))
  (segment (start 84.452507 129.177748) (end 84.459903 129.156612) (width 0.1) (layer "F.Cu") (net 179))
  (segment (start 84.727747 129.597492) (end 84.75 129.6) (width 0.1) (layer "F.Cu") (net 179))
  (segment (start 84.447492 129.522252) (end 84.45 129.5) (width 0.1) (layer "F.Cu") (net 179))
  (segment (start 89.55 127.5) (end 90.5 126.55) (width 0.1) (layer "F.Cu") (net 179))
  (segment (start 84.372252 129.597492) (end 84.393388 129.590096) (width 0.1) (layer "F.Cu") (net 179))
  (segment (start 84.428183 129.562348) (end 84.440096 129.543388) (width 0.1) (layer "F.Cu") (net 179))
  (segment (start 84.640096 129.156612) (end 84.647492 129.177748) (width 0.1) (layer "F.Cu") (net 179))
  (segment (start 84.687651 129.578183) (end 84.706611 129.590096) (width 0.1) (layer "F.Cu") (net 179))
  (segment (start 84.706611 129.590096) (end 84.727747 129.597492) (width 0.1) (layer "F.Cu") (net 179))
  (segment (start 84.506611 129.109904) (end 84.527747 129.102508) (width 0.1) (layer "F.Cu") (net 179))
  (segment (start 84.252507 129.522252) (end 84.259903 129.543388) (width 0.1) (layer "F.Cu") (net 179))
  (segment (start 84.85 129.45) (end 84.852507 129.427747) (width 0.1) (layer "F.Cu") (net 179))
  (segment (start 84.412348 129.578183) (end 84.428183 129.562348) (width 0.1) (layer "F.Cu") (net 179))
  (segment (start 84.812348 129.578183) (end 84.828183 129.562348) (width 0.1) (layer "F.Cu") (net 179))
  (segment (start 84.859903 129.406611) (end 84.871816 129.387651) (width 0.1) (layer "F.Cu") (net 179))
  (segment (start 84.287651 129.578183) (end 84.306611 129.590096) (width 0.1) (layer "F.Cu") (net 179))
  (segment (start 84.45 129.5) (end 84.45 129.2) (width 0.1) (layer "F.Cu") (net 179))
  (segment (start 84.327747 129.597492) (end 84.35 129.6) (width 0.1) (layer "F.Cu") (net 179))
  (segment (start 84.35 129.6) (end 84.372252 129.597492) (width 0.1) (layer "F.Cu") (net 179))
  (segment (start 84.212348 129.371816) (end 84.228183 129.387651) (width 0.1) (layer "F.Cu") (net 179))
  (segment (start 84.193388 129.359903) (end 84.212348 129.371816) (width 0.1) (layer "F.Cu") (net 179))
  (segment (start 84.259903 129.543388) (end 84.271816 129.562348) (width 0.1) (layer "F.Cu") (net 179))
  (segment (start 84.871816 129.387651) (end 84.887651 129.371816) (width 0.1) (layer "F.Cu") (net 179))
  (segment (start 84.25 129.45) (end 84.25 129.5) (width 0.1) (layer "F.Cu") (net 179))
  (segment (start 84.659903 129.543388) (end 84.671816 129.562348) (width 0.1) (layer "F.Cu") (net 179))
  (segment (start 84.247492 129.427747) (end 84.25 129.45) (width 0.1) (layer "F.Cu") (net 179))
  (segment (start 84.527747 129.102508) (end 84.55 129.1) (width 0.1) (layer "F.Cu") (net 179))
  (segment (start 84.772252 129.597492) (end 84.793388 129.590096) (width 0.1) (layer "F.Cu") (net 179))
  (segment (start 84.628183 129.137652) (end 84.640096 129.156612) (width 0.1) (layer "F.Cu") (net 179))
  (segment (start 84.55 129.1) (end 84.572252 129.102508) (width 0.1) (layer "F.Cu") (net 179))
  (segment (start 84.306611 129.590096) (end 84.327747 129.597492) (width 0.1) (layer "F.Cu") (net 179))
  (segment (start 84.172252 129.352507) (end 84.193388 129.359903) (width 0.1) (layer "F.Cu") (net 179))
  (segment (start 84.228183 129.387651) (end 84.240096 129.406611) (width 0.1) (layer "F.Cu") (net 179))
  (segment (start 84.271816 129.562348) (end 84.287651 129.578183) (width 0.1) (layer "F.Cu") (net 179))
  (segment (start 84.593388 129.109904) (end 84.612348 129.121817) (width 0.1) (layer "F.Cu") (net 179))
  (segment (start 84.906611 129.359903) (end 84.927747 129.352507) (width 0.1) (layer "F.Cu") (net 179))
  (segment (start 84.15 129.35) (end 84.172252 129.352507) (width 0.1) (layer "F.Cu") (net 179))
  (segment (start 84.65 129.2) (end 84.65 129.5) (width 0.1) (layer "F.Cu") (net 179))
  (segment (start 84.572252 129.102508) (end 84.593388 129.109904) (width 0.1) (layer "F.Cu") (net 179))
  (segment (start 84.828183 129.562348) (end 84.840096 129.543388) (width 0.1) (layer "F.Cu") (net 179))
  (segment (start 84.840096 129.543388) (end 84.847492 129.522252) (width 0.1) (layer "F.Cu") (net 179))
  (segment (start 84.793388 129.590096) (end 84.812348 129.578183) (width 0.1) (layer "F.Cu") (net 179))
  (segment (start 84.85 129.5) (end 84.85 129.45) (width 0.1) (layer "F.Cu") (net 179))
  (segment (start 89.55 129) (end 89.55 127.5) (width 0.1) (layer "F.Cu") (net 179))
  (segment (start 90.5 126.55) (end 92 126.55) (width 0.1) (layer "F.Cu") (net 179))
  (segment (start 84.612348 129.121817) (end 84.628183 129.137652) (width 0.1) (layer "F.Cu") (net 179))
  (segment (start 84.75 129.6) (end 84.772252 129.597492) (width 0.1) (layer "F.Cu") (net 179))
  (segment (start 84.852507 129.427747) (end 84.859903 129.406611) (width 0.1) (layer "F.Cu") (net 179))
  (segment (start 84.647492 129.177748) (end 84.65 129.2) (width 0.1) (layer "F.Cu") (net 179))
  (segment (start 84.459903 129.156612) (end 84.471816 129.137652) (width 0.1) (layer "F.Cu") (net 179))
  (segment (start 84.393388 129.590096) (end 84.412348 129.578183) (width 0.1) (layer "F.Cu") (net 179))
  (segment (start 84.927747 129.352507) (end 84.95 129.35) (width 0.1) (layer "F.Cu") (net 179))
  (segment (start 84.471816 129.137652) (end 84.487651 129.121817) (width 0.1) (layer "F.Cu") (net 179))
  (segment (start 84.240096 129.406611) (end 84.247492 129.427747) (width 0.1) (layer "F.Cu") (net 179))
  (segment (start 83.75 129.4) (end 83.8 129.35) (width 0.1) (layer "F.Cu") (net 179))
  (segment (start 84.440096 129.543388) (end 84.447492 129.522252) (width 0.1) (layer "F.Cu") (net 179))
  (segment (start 84.45 129.2) (end 84.452507 129.177748) (width 0.1) (layer "F.Cu") (net 179))
  (segment (start 84.652507 129.522252) (end 84.659903 129.543388) (width 0.1) (layer "F.Cu") (net 179))
  (segment (start 83.8 129.35) (end 84.15 129.35) (width 0.1) (layer "F.Cu") (net 179))
  (segment (start 84.887651 129.371816) (end 84.906611 129.359903) (width 0.1) (layer "F.Cu") (net 179))
  (segment (start 84.65 129.5) (end 84.652507 129.522252) (width 0.1) (layer "F.Cu") (net 179))
  (segment (start 84.847492 129.522252) (end 84.85 129.5) (width 0.1) (layer "F.Cu") (net 179))
  (segment (start 84.671816 129.562348) (end 84.687651 129.578183) (width 0.1) (layer "F.Cu") (net 179))
  (segment (start 84.25 129.5) (end 84.252507 129.522252) (width 0.1) (layer "F.Cu") (net 179))
  (via (at 89.55 129) (size 0.5) (drill 0.2) (layers "F.Cu" "B.Cu") (net 179))
  (via (at 83.75 129.4) (size 0.5) (drill 0.2) (layers "F.Cu" "B.Cu") (net 179))
  (segment (start 84.152507 129.774603) (end 84.15 129.75235) (width 0.1) (layer "In2.Cu") (net 179))
  (segment (start 84.75 129.75235) (end 84.747492 129.774603) (width 0.1) (layer "In2.Cu") (net 179))
  (segment (start 84.806611 129.207553) (end 84.787651 129.219466) (width 0.1) (layer "In2.Cu") (net 179))
  (segment (start 84.65 129.85235) (end 84.627747 129.849843) (width 0.1) (layer "In2.Cu") (net 179))
  (segment (start 84.552507 129.774603) (end 84.55 129.75235) (width 0.1) (layer "In2.Cu") (net 179))
  (segment (start 84.587651 129.830534) (end 84.571816 129.814699) (width 0.1) (layer "In2.Cu") (net 179))
  (segment (start 84.95 129.3) (end 84.95 129.29765) (width 0.1) (layer "In2.Cu") (net 179))
  (segment (start 84.512348 129.219466) (end 84.493388 129.207553) (width 0.1) (layer "In2.Cu") (net 179))
  (segment (start 85.05 129.4) (end 85.027747 129.397492) (width 0.1) (layer "In2.Cu") (net 179))
  (segment (start 84.352507 129.275397) (end 84.35 129.29765) (width 0.1) (layer "In2.Cu") (net 179))
  (segment (start 84.147492 129.477748) (end 84.140096 129.456612) (width 0.1) (layer "In2.Cu") (net 179))
  (segment (start 84.728183 129.814699) (end 84.712348 129.830534) (width 0.1) (layer "In2.Cu") (net 179))
  (segment (start 84.952507 129.322252) (end 84.95 129.3) (width 0.1) (layer "In2.Cu") (net 179))
  (segment (start 84.272252 129.849843) (end 84.25 129.85235) (width 0.1) (layer "In2.Cu") (net 179))
  (segment (start 84.959903 129.343388) (end 84.952507 129.322252) (width 0.1) (layer "In2.Cu") (net 179))
  (segment (start 84.45 129.19765) (end 84.427747 129.200157) (width 0.1) (layer "In2.Cu") (net 179))
  (segment (start 84.227747 129.849843) (end 84.206611 129.842447) (width 0.1) (layer "In2.Cu") (net 179))
  (segment (start 84.559903 129.795739) (end 84.552507 129.774603) (width 0.1) (layer "In2.Cu") (net 179))
  (segment (start 84.25 129.85235) (end 84.227747 129.849843) (width 0.1) (layer "In2.Cu") (net 179))
  (segment (start 84.712348 129.830534) (end 84.693388 129.842447) (width 0.1) (layer "In2.Cu") (net 179))
  (segment (start 84.872252 129.200157) (end 84.85 129.19765) (width 0.1) (layer "In2.Cu") (net 179))
  (segment (start 84.987651 129.378183) (end 84.971816 129.362348) (width 0.1) (layer "In2.Cu") (net 179))
  (segment (start 84.340096 129.795739) (end 84.328183 129.814699) (width 0.1) (layer "In2.Cu") (net 179))
  (segment (start 84.893388 129.207553) (end 84.872252 129.200157) (width 0.1) (layer "In2.Cu") (net 179))
  (segment (start 84.95 129.29765) (end 84.947492 129.275397) (width 0.1) (layer "In2.Cu") (net 179))
  (segment (start 84.05 129.4) (end 83.75 129.4) (width 0.1) (layer "In2.Cu") (net 179))
  (segment (start 84.771816 129.235301) (end 84.759903 129.254261) (width 0.1) (layer "In2.Cu") (net 179))
  (segment (start 85.875 130.1) (end 85.175 129.4) (width 0.1) (layer "In2.Cu") (net 179))
  (segment (start 84.85 129.19765) (end 84.827747 129.200157) (width 0.1) (layer "In2.Cu") (net 179))
  (segment (start 84.171816 129.814699) (end 84.159903 129.795739) (width 0.1) (layer "In2.Cu") (net 179))
  (segment (start 89.55 129) (end 88.45 130.1) (width 0.1) (layer "In2.Cu") (net 179))
  (segment (start 84.740096 129.795739) (end 84.728183 129.814699) (width 0.1) (layer "In2.Cu") (net 179))
  (segment (start 84.672252 129.849843) (end 84.65 129.85235) (width 0.1) (layer "In2.Cu") (net 179))
  (segment (start 88.45 130.1) (end 85.875 130.1) (width 0.1) (layer "In2.Cu") (net 179))
  (segment (start 84.747492 129.774603) (end 84.740096 129.795739) (width 0.1) (layer "In2.Cu") (net 179))
  (segment (start 84.387651 129.219466) (end 84.371816 129.235301) (width 0.1) (layer "In2.Cu") (net 179))
  (segment (start 84.752507 129.275397) (end 84.75 129.29765) (width 0.1) (layer "In2.Cu") (net 179))
  (segment (start 84.912348 129.219466) (end 84.893388 129.207553) (width 0.1) (layer "In2.Cu") (net 179))
  (segment (start 84.406611 129.207553) (end 84.387651 129.219466) (width 0.1) (layer "In2.Cu") (net 179))
  (segment (start 84.540096 129.254261) (end 84.528183 129.235301) (width 0.1) (layer "In2.Cu") (net 179))
  (segment (start 84.140096 129.456612) (end 84.128183 129.437652) (width 0.1) (layer "In2.Cu") (net 179))
  (segment (start 84.093388 129.409904) (end 84.072252 129.402508) (width 0.1) (layer "In2.Cu") (net 179))
  (segment (start 84.55 129.75235) (end 84.55 129.29765) (width 0.1) (layer "In2.Cu") (net 179))
  (segment (start 85.175 129.4) (end 85.05 129.4) (width 0.1) (layer "In2.Cu") (net 179))
  (segment (start 84.15 129.5) (end 84.147492 129.477748) (width 0.1) (layer "In2.Cu") (net 179))
  (segment (start 84.35 129.75235) (end 84.347492 129.774603) (width 0.1) (layer "In2.Cu") (net 179))
  (segment (start 84.547492 129.275397) (end 84.540096 129.254261) (width 0.1) (layer "In2.Cu") (net 179))
  (segment (start 84.627747 129.849843) (end 84.606611 129.842447) (width 0.1) (layer "In2.Cu") (net 179))
  (segment (start 84.359903 129.254261) (end 84.352507 129.275397) (width 0.1) (layer "In2.Cu") (net 179))
  (segment (start 84.493388 129.207553) (end 84.472252 129.200157) (width 0.1) (layer "In2.Cu") (net 179))
  (segment (start 84.371816 129.235301) (end 84.359903 129.254261) (width 0.1) (layer "In2.Cu") (net 179))
  (segment (start 84.187651 129.830534) (end 84.171816 129.814699) (width 0.1) (layer "In2.Cu") (net 179))
  (segment (start 84.971816 129.362348) (end 84.959903 129.343388) (width 0.1) (layer "In2.Cu") (net 179))
  (segment (start 84.928183 129.235301) (end 84.912348 129.219466) (width 0.1) (layer "In2.Cu") (net 179))
  (segment (start 84.128183 129.437652) (end 84.112348 129.421817) (width 0.1) (layer "In2.Cu") (net 179))
  (segment (start 85.006611 129.390096) (end 84.987651 129.378183) (width 0.1) (layer "In2.Cu") (net 179))
  (segment (start 84.328183 129.814699) (end 84.312348 129.830534) (width 0.1) (layer "In2.Cu") (net 179))
  (segment (start 84.947492 129.275397) (end 84.940096 129.254261) (width 0.1) (layer "In2.Cu") (net 179))
  (segment (start 84.571816 129.814699) (end 84.559903 129.795739) (width 0.1) (layer "In2.Cu") (net 179))
  (segment (start 84.293388 129.842447) (end 84.272252 129.849843) (width 0.1) (layer "In2.Cu") (net 179))
  (segment (start 84.072252 129.402508) (end 84.05 129.4) (width 0.1) (layer "In2.Cu") (net 179))
  (segment (start 85.027747 129.397492) (end 85.006611 129.390096) (width 0.1) (layer "In2.Cu") (net 179))
  (segment (start 84.606611 129.842447) (end 84.587651 129.830534) (width 0.1) (layer "In2.Cu") (net 179))
  (segment (start 84.940096 129.254261) (end 84.928183 129.235301) (width 0.1) (layer "In2.Cu") (net 179))
  (segment (start 84.75 129.29765) (end 84.75 129.75235) (width 0.1) (layer "In2.Cu") (net 179))
  (segment (start 84.827747 129.200157) (end 84.806611 129.207553) (width 0.1) (layer "In2.Cu") (net 179))
  (segment (start 84.55 129.29765) (end 84.547492 129.275397) (width 0.1) (layer "In2.Cu") (net 179))
  (segment (start 84.528183 129.235301) (end 84.512348 129.219466) (width 0.1) (layer "In2.Cu") (net 179))
  (segment (start 84.35 129.29765) (end 84.35 129.75235) (width 0.1) (layer "In2.Cu") (net 179))
  (segment (start 84.347492 129.774603) (end 84.340096 129.795739) (width 0.1) (layer "In2.Cu") (net 179))
  (segment (start 84.787651 129.219466) (end 84.771816 129.235301) (width 0.1) (layer "In2.Cu") (net 179))
  (segment (start 84.427747 129.200157) (end 84.406611 129.207553) (width 0.1) (layer "In2.Cu") (net 179))
  (segment (start 84.693388 129.842447) (end 84.672252 129.849843) (width 0.1) (layer "In2.Cu") (net 179))
  (segment (start 84.759903 129.254261) (end 84.752507 129.275397) (width 0.1) (layer "In2.Cu") (net 179))
  (segment (start 84.112348 129.421817) (end 84.093388 129.409904) (width 0.1) (layer "In2.Cu") (net 179))
  (segment (start 84.206611 129.842447) (end 84.187651 129.830534) (width 0.1) (layer "In2.Cu") (net 179))
  (segment (start 84.312348 129.830534) (end 84.293388 129.842447) (width 0.1) (layer "In2.Cu") (net 179))
  (segment (start 84.472252 129.200157) (end 84.45 129.19765) (width 0.1) (layer "In2.Cu") (net 179))
  (segment (start 84.15 129.75235) (end 84.15 129.5) (width 0.1) (layer "In2.Cu") (net 179))
  (segment (start 84.159903 129.795739) (end 84.152507 129.774603) (width 0.1) (layer "In2.Cu") (net 179))
  (segment (start 85.9 129.35) (end 85.5 128.95) (width 0.15) (layer "F.Cu") (net 180))
  (segment (start 89.25 127.35) (end 89.25 128.4) (width 0.1) (layer "F.Cu") (net 180))
  (segment (start 89.25 128.4) (end 88.65 129) (width 0.1) (layer "F.Cu") (net 180))
  (segment (start 92 125.75) (end 90.85 125.75) (width 0.1) (layer "F.Cu") (net 180))
  (segment (start 90.85 125.75) (end 89.25 127.35) (width 0.1) (layer "F.Cu") (net 180))
  (via (at 85.5 128.95) (size 0.5) (drill 0.2) (layers "F.Cu" "B.Cu") (net 180))
  (via (at 88.65 129) (size 0.5) (drill 0.2) (layers "F.Cu" "B.Cu") (net 180))
  (segment (start 87.699402 129.898805) (end 87.800598 129.898805) (width 0.1) (layer "In2.Cu") (net 180))
  (segment (start 87.087651 129.373012) (end 87.106611 129.361099) (width 0.1) (layer "In2.Cu") (net 180))
  (segment (start 86.030801 129.810777) (end 86.038624 129.8186) (width 0.1) (layer "In2.Cu") (net 180))
  (segment (start 86.75 129.251195) (end 86.772252 129.253703) (width 0.1) (layer "In2.Cu") (net 180))
  (segment (start 86.45 129.849403) (end 86.451238 129.860395) (width 0.1) (layer "In2.Cu") (net 180))
  (segment (start 87.254892 129.870837) (end 87.260777 129.880204) (width 0.1) (layer "In2.Cu") (net 180))
  (segment (start 86.249402 129.8) (end 86.25 129.8) (width 0.1) (layer "In2.Cu") (net 180))
  (segment (start 87.031399 129.888027) (end 87.039222 129.880204) (width 0.1) (layer "In2.Cu") (net 180))
  (segment (start 86.687651 129.273012) (end 86.706611 129.261099) (width 0.1) (layer "In2.Cu") (net 180))
  (segment (start 87.845107 129.870837) (end 87.848761 129.860395) (width 0.1) (layer "In2.Cu") (net 180))
  (segment (start 87.448761 129.860395) (end 87.45 129.849403) (width 0.1) (layer "In2.Cu") (net 180))
  (segment (start 87.288409 129.897566) (end 87.299402 129.898805) (width 0.1) (layer "In2.Cu") (net 180))
  (segment (start 86.393388 129.361099) (end 86.412348 129.373012) (width 0.1) (layer "In2.Cu") (net 180))
  (segment (start 86.45 129.451195) (end 86.45 129.849403) (width 0.1) (layer "In2.Cu") (net 180))
  (segment (start 87.059903 129.407807) (end 87.071816 129.388847) (width 0.1) (layer "In2.Cu") (net 180))
  (segment (start 87.839222 129.880204) (end 87.845107 129.870837) (width 0.1) (layer "In2.Cu") (net 180))
  (segment (start 87.527747 129.253703) (end 87.55 129.251195) (width 0.1) (layer "In2.Cu") (net 180))
  (segment (start 87.887651 129.273012) (end 87.906611 129.261099) (width 0.1) (layer "In2.Cu") (net 180))
  (segment (start 86.65 129.849403) (end 86.65 129.351195) (width 0.1) (layer "In2.Cu") (net 180))
  (segment (start 87.640096 129.307807) (end 87.647492 129.328943) (width 0.1) (layer "In2.Cu") (net 180))
  (segment (start 87.01159 129.897566) (end 87.022032 129.893912) (width 0.1) (layer "In2.Cu") (net 180))
  (segment (start 87.654892 129.870837) (end 87.660777 129.880204) (width 0.1) (layer "In2.Cu") (net 180))
  (segment (start 88.3 129.8) (end 88.65 129.45) (width 0.1) (layer "In2.Cu") (net 180))
  (segment (start 87.651238 129.860395) (end 87.654892 129.870837) (width 0.1) (layer "In2.Cu") (net 180))
  (segment (start 86.454892 129.870837) (end 86.460777 129.880204) (width 0.1) (layer "In2.Cu") (net 180))
  (segment (start 86.477967 129.893912) (end 86.488409 129.897566) (width 0.1) (layer "In2.Cu") (net 180))
  (segment (start 86.412348 129.373012) (end 86.428183 129.388847) (width 0.1) (layer "In2.Cu") (net 180))
  (segment (start 87.000598 129.898805) (end 87.01159 129.897566) (width 0.1) (layer "In2.Cu") (net 180))
  (segment (start 87.15 129.351195) (end 87.172252 129.353703) (width 0.1) (layer "In2.Cu") (net 180))
  (segment (start 87.647492 129.328943) (end 87.65 129.351195) (width 0.1) (layer "In2.Cu") (net 180))
  (segment (start 86.210992 129.897566) (end 86.221434 129.893912) (width 0.1) (layer "In2.Cu") (net 180))
  (segment (start 86.600598 129.898805) (end 86.61159 129.897566) (width 0.1) (layer "In2.Cu") (net 180))
  (segment (start 86.851238 129.860395) (end 86.854892 129.870837) (width 0.1) (layer "In2.Cu") (net 180))
  (segment (start 87.85 129.849403) (end 87.85 129.351195) (width 0.1) (layer "In2.Cu") (net 180))
  (segment (start 88.087651 129.778184) (end 88.106611 129.790097) (width 0.1) (layer "In2.Cu") (net 180))
  (segment (start 88.040096 129.307807) (end 88.047492 129.328943) (width 0.1) (layer "In2.Cu") (net 180))
  (segment (start 87.045107 129.870837) (end 87.048761 129.860395) (width 0.1) (layer "In2.Cu") (net 180))
  (segment (start 87.251238 129.860395) (end 87.254892 129.870837) (width 0.1) (layer "In2.Cu") (net 180))
  (segment (start 88.05 129.7) (end 88.052507 129.722253) (width 0.1) (layer "In2.Cu") (net 180))
  (segment (start 87.260777 129.880204) (end 87.2686 129.888027) (width 0.1) (layer "In2.Cu") (net 180))
  (segment (start 87.506611 129.261099) (end 87.527747 129.253703) (width 0.1) (layer "In2.Cu") (net 180))
  (segment (start 86.044509 129.827967) (end 86.048163 129.838409) (width 0.1) (layer "In2.Cu") (net 180))
  (segment (start 87.85 129.351195) (end 87.852507 129.328943) (width 0.1) (layer "In2.Cu") (net 180))
  (segment (start 86.087811 129.897566) (end 86.098804 129.898805) (width 0.1) (layer "In2.Cu") (net 180))
  (segment (start 87.45 129.351195) (end 87.452507 129.328943) (width 0.1) (layer "In2.Cu") (net 180))
  (segment (start 87.660777 129.880204) (end 87.6686 129.888027) (width 0.1) (layer "In2.Cu") (net 180))
  (segment (start 87.852507 129.328943) (end 87.859903 129.307807) (width 0.1) (layer "In2.Cu") (net 180))
  (segment (start 87.459903 129.307807) (end 87.471816 129.288847) (width 0.1) (layer "In2.Cu") (net 180))
  (segment (start 87.95 129.251195) (end 87.972252 129.253703) (width 0.1) (layer "In2.Cu") (net 180))
  (segment (start 87.127747 129.353703) (end 87.15 129.351195) (width 0.1) (layer "In2.Cu") (net 180))
  (segment (start 85.9 129.8) (end 86 129.8) (width 0.1) (layer "In2.Cu") (net 180))
  (segment (start 86.372252 129.353703) (end 86.393388 129.361099) (width 0.1) (layer "In2.Cu") (net 180))
  (segment (start 88.127747 129.797493) (end 88.15 129.8) (width 0.1) (layer "In2.Cu") (net 180))
  (segment (start 87.677967 129.893912) (end 87.688409 129.897566) (width 0.1) (layer "In2.Cu") (net 180))
  (segment (start 86.306611 129.361099) (end 86.327747 129.353703) (width 0.1) (layer "In2.Cu") (net 180))
  (segment (start 85.5 129.4) (end 85.9 129.8) (width 0.1) (layer "In2.Cu") (net 180))
  (segment (start 87.048761 129.860395) (end 87.05 129.849403) (width 0.1) (layer "In2.Cu") (net 180))
  (segment (start 86.652507 129.328943) (end 86.659903 129.307807) (width 0.1) (layer "In2.Cu") (net 180))
  (segment (start 86 129.8) (end 86.010992 129.801238) (width 0.1) (layer "In2.Cu") (net 180))
  (segment (start 86.35 129.351195) (end 86.372252 129.353703) (width 0.1) (layer "In2.Cu") (net 180))
  (segment (start 86.860777 129.880204) (end 86.8686 129.888027) (width 0.1) (layer "In2.Cu") (net 180))
  (segment (start 87.022032 129.893912) (end 87.031399 129.888027) (width 0.1) (layer "In2.Cu") (net 180))
  (segment (start 87.471816 129.288847) (end 87.487651 129.273012) (width 0.1) (layer "In2.Cu") (net 180))
  (segment (start 86.61159 129.897566) (end 86.622032 129.893912) (width 0.1) (layer "In2.Cu") (net 180))
  (segment (start 87.65 129.351195) (end 87.65 129.849403) (width 0.1) (layer "In2.Cu") (net 180))
  (segment (start 87.972252 129.253703) (end 87.993388 129.261099) (width 0.1) (layer "In2.Cu") (net 180))
  (segment (start 86.854892 129.870837) (end 86.860777 129.880204) (width 0.1) (layer "In2.Cu") (net 180))
  (segment (start 86.271816 129.388847) (end 86.287651 129.373012) (width 0.1) (layer "In2.Cu") (net 180))
  (segment (start 86.244509 129.870837) (end 86.248163 129.860395) (width 0.1) (layer "In2.Cu") (net 180))
  (segment (start 87.071816 129.388847) (end 87.087651 129.373012) (width 0.1) (layer "In2.Cu") (net 180))
  (segment (start 87.927747 129.253703) (end 87.95 129.251195) (width 0.1) (layer "In2.Cu") (net 180))
  (segment (start 87.572252 129.253703) (end 87.593388 129.261099) (width 0.1) (layer "In2.Cu") (net 180))
  (segment (start 87.6686 129.888027) (end 87.677967 129.893912) (width 0.1) (layer "In2.Cu") (net 180))
  (segment (start 87.039222 129.880204) (end 87.045107 129.870837) (width 0.1) (layer "In2.Cu") (net 180))
  (segment (start 87.05 129.849403) (end 87.05 129.451195) (width 0.1) (layer "In2.Cu") (net 180))
  (segment (start 87.871816 129.288847) (end 87.887651 129.273012) (width 0.1) (layer "In2.Cu") (net 180))
  (segment (start 87.487651 129.273012) (end 87.506611 129.261099) (width 0.1) (layer "In2.Cu") (net 180))
  (segment (start 87.612348 129.273012) (end 87.628183 129.288847) (width 0.1) (layer "In2.Cu") (net 180))
  (segment (start 86.727747 129.253703) (end 86.75 129.251195) (width 0.1) (layer "In2.Cu") (net 180))
  (segment (start 86.098804 129.898805) (end 86.2 129.898805) (width 0.1) (layer "In2.Cu") (net 180))
  (segment (start 88.15 129.8) (end 88.3 129.8) (width 0.1) (layer "In2.Cu") (net 180))
  (segment (start 87.106611 129.361099) (end 87.127747 129.353703) (width 0.1) (layer "In2.Cu") (net 180))
  (segment (start 87.400598 129.898805) (end 87.41159 129.897566) (width 0.1) (layer "In2.Cu") (net 180))
  (segment (start 88.059903 129.743389) (end 88.071816 129.762349) (width 0.1) (layer "In2.Cu") (net 180))
  (segment (start 86.659903 129.307807) (end 86.671816 129.288847) (width 0.1) (layer "In2.Cu") (net 180))
  (segment (start 86.8686 129.888027) (end 86.877967 129.893912) (width 0.1) (layer "In2.Cu") (net 180))
  (segment (start 87.452507 129.328943) (end 87.459903 129.307807) (width 0.1) (layer "In2.Cu") (net 180))
  (segment (start 86.054294 129.870837) (end 86.060179 129.880204) (width 0.1) (layer "In2.Cu") (net 180))
  (segment (start 86.238624 129.880204) (end 86.244509 129.870837) (width 0.1) (layer "In2.Cu") (net 180))
  (segment (start 87.05 129.451195) (end 87.052507 129.428943) (width 0.1) (layer "In2.Cu") (net 180))
  (segment (start 86.447492 129.428943) (end 86.45 129.451195) (width 0.1) (layer "In2.Cu") (net 180))
  (segment (start 86.645107 129.870837) (end 86.648761 129.860395) (width 0.1) (layer "In2.Cu") (net 180))
  (segment (start 86.840096 129.307807) (end 86.847492 129.328943) (width 0.1) (layer "In2.Cu") (net 180))
  (segment (start 86.05064 129.860395) (end 86.054294 129.870837) (width 0.1) (layer "In2.Cu") (net 180))
  (segment (start 87.859903 129.307807) (end 87.871816 129.288847) (width 0.1) (layer "In2.Cu") (net 180))
  (segment (start 86.65 129.351195) (end 86.652507 129.328943) (width 0.1) (layer "In2.Cu") (net 180))
  (segment (start 86.230801 129.888027) (end 86.238624 129.880204) (width 0.1) (layer "In2.Cu") (net 180))
  (segment (start 86.639222 129.880204) (end 86.645107 129.870837) (width 0.1) (layer "In2.Cu") (net 180))
  (segment (start 86.4686 129.888027) (end 86.477967 129.893912) (width 0.1) (layer "In2.Cu") (net 180))
  (segment (start 86.451238 129.860395) (end 86.454892 129.870837) (width 0.1) (layer "In2.Cu") (net 180))
  (segment (start 86.793388 129.261099) (end 86.812348 129.273012) (width 0.1) (layer "In2.Cu") (net 180))
  (segment (start 86.077369 129.893912) (end 86.087811 129.897566) (width 0.1) (layer "In2.Cu") (net 180))
  (segment (start 87.299402 129.898805) (end 87.400598 129.898805) (width 0.1) (layer "In2.Cu") (net 180))
  (segment (start 86.460777 129.880204) (end 86.4686 129.888027) (width 0.1) (layer "In2.Cu") (net 180))
  (segment (start 88.071816 129.762349) (end 88.087651 129.778184) (width 0.1) (layer "In2.Cu") (net 180))
  (segment (start 87.688409 129.897566) (end 87.699402 129.898805) (width 0.1) (layer "In2.Cu") (net 180))
  (segment (start 86.038624 129.8186) (end 86.044509 129.827967) (width 0.1) (layer "In2.Cu") (net 180))
  (segment (start 87.848761 129.860395) (end 87.85 129.849403) (width 0.1) (layer "In2.Cu") (net 180))
  (segment (start 87.831399 129.888027) (end 87.839222 129.880204) (width 0.1) (layer "In2.Cu") (net 180))
  (segment (start 86.068002 129.888027) (end 86.077369 129.893912) (width 0.1) (layer "In2.Cu") (net 180))
  (segment (start 86.85 129.351195) (end 86.85 129.849403) (width 0.1) (layer "In2.Cu") (net 180))
  (segment (start 86.048163 129.838409) (end 86.05064 129.860395) (width 0.1) (layer "In2.Cu") (net 180))
  (segment (start 87.431399 129.888027) (end 87.439222 129.880204) (width 0.1) (layer "In2.Cu") (net 180))
  (segment (start 87.445107 129.870837) (end 87.448761 129.860395) (width 0.1) (layer "In2.Cu") (net 180))
  (segment (start 86.706611 129.261099) (end 86.727747 129.253703) (width 0.1) (layer "In2.Cu") (net 180))
  (segment (start 86.622032 129.893912) (end 86.631399 129.888027) (width 0.1) (layer "In2.Cu") (net 180))
  (segment (start 86.499402 129.898805) (end 86.600598 129.898805) (width 0.1) (layer "In2.Cu") (net 180))
  (segment (start 87.277967 129.893912) (end 87.288409 129.897566) (width 0.1) (layer "In2.Cu") (net 180))
  (segment (start 86.812348 129.273012) (end 86.828183 129.288847) (width 0.1) (layer "In2.Cu") (net 180))
  (segment (start 86.25 129.8) (end 86.25 129.451195) (width 0.1) (layer "In2.Cu") (net 180))
  (segment (start 86.010992 129.801238) (end 86.021434 129.804892) (width 0.1) (layer "In2.Cu") (net 180))
  (segment (start 87.422032 129.893912) (end 87.431399 129.888027) (width 0.1) (layer "In2.Cu") (net 180))
  (segment (start 87.593388 129.261099) (end 87.612348 129.273012) (width 0.1) (layer "In2.Cu") (net 180))
  (segment (start 86.631399 129.888027) (end 86.639222 129.880204) (width 0.1) (layer "In2.Cu") (net 180))
  (segment (start 87.172252 129.353703) (end 87.193388 129.361099) (width 0.1) (layer "In2.Cu") (net 180))
  (segment (start 87.822032 129.893912) (end 87.831399 129.888027) (width 0.1) (layer "In2.Cu") (net 180))
  (segment (start 86.671816 129.288847) (end 86.687651 129.273012) (width 0.1) (layer "In2.Cu") (net 180))
  (segment (start 86.877967 129.893912) (end 86.888409 129.897566) (width 0.1) (layer "In2.Cu") (net 180))
  (segment (start 86.440096 129.407807) (end 86.447492 129.428943) (width 0.1) (layer "In2.Cu") (net 180))
  (segment (start 86.021434 129.804892) (end 86.030801 129.810777) (width 0.1) (layer "In2.Cu") (net 180))
  (segment (start 86.2 129.898805) (end 86.210992 129.897566) (width 0.1) (layer "In2.Cu") (net 180))
  (segment (start 87.906611 129.261099) (end 87.927747 129.253703) (width 0.1) (layer "In2.Cu") (net 180))
  (segment (start 86.327747 129.353703) (end 86.35 129.351195) (width 0.1) (layer "In2.Cu") (net 180))
  (segment (start 87.228183 129.388847) (end 87.240096 129.407807) (width 0.1) (layer "In2.Cu") (net 180))
  (segment (start 87.81159 129.897566) (end 87.822032 129.893912) (width 0.1) (layer "In2.Cu") (net 180))
  (segment (start 86.249402 129.849402) (end 86.249402 129.8) (width 0.1) (layer "In2.Cu") (net 180))
  (segment (start 86.85 129.849403) (end 86.851238 129.860395) (width 0.1) (layer "In2.Cu") (net 180))
  (segment (start 88.047492 129.328943) (end 88.05 129.351195) (width 0.1) (layer "In2.Cu") (net 180))
  (segment (start 86.287651 129.373012) (end 86.306611 129.361099) (width 0.1) (layer "In2.Cu") (net 180))
  (segment (start 86.828183 129.288847) (end 86.840096 129.307807) (width 0.1) (layer "In2.Cu") (net 180))
  (segment (start 87.240096 129.407807) (end 87.247492 129.428943) (width 0.1) (layer "In2.Cu") (net 180))
  (segment (start 87.65 129.849403) (end 87.651238 129.860395) (width 0.1) (layer "In2.Cu") (net 180))
  (segment (start 88.052507 129.722253) (end 88.059903 129.743389) (width 0.1) (layer "In2.Cu") (net 180))
  (segment (start 86.060179 129.880204) (end 86.068002 129.888027) (width 0.1) (layer "In2.Cu") (net 180))
  (segment (start 86.428183 129.388847) (end 86.440096 129.407807) (width 0.1) (layer "In2.Cu") (net 180))
  (segment (start 87.993388 129.261099) (end 88.012348 129.273012) (width 0.1) (layer "In2.Cu") (net 180))
  (segment (start 87.800598 129.898805) (end 87.81159 129.897566) (width 0.1) (layer "In2.Cu") (net 180))
  (segment (start 86.772252 129.253703) (end 86.793388 129.261099) (width 0.1) (layer "In2.Cu") (net 180))
  (segment (start 88.012348 129.273012) (end 88.028183 129.288847) (width 0.1) (layer "In2.Cu") (net 180))
  (segment (start 87.25 129.451195) (end 87.25 129.849403) (width 0.1) (layer "In2.Cu") (net 180))
  (segment (start 86.899402 129.898805) (end 87.000598 129.898805) (width 0.1) (layer "In2.Cu") (net 180))
  (segment (start 87.41159 129.897566) (end 87.422032 129.893912) (width 0.1) (layer "In2.Cu") (net 180))
  (segment (start 87.2686 129.888027) (end 87.277967 129.893912) (width 0.1) (layer "In2.Cu") (net 180))
  (segment (start 87.193388 129.361099) (end 87.212348 129.373012) (width 0.1) (layer "In2.Cu") (net 180))
  (segment (start 88.05 129.351195) (end 88.05 129.7) (width 0.1) (layer "In2.Cu") (net 180))
  (segment (start 87.212348 129.373012) (end 87.228183 129.388847) (width 0.1) (layer "In2.Cu") (net 180))
  (segment (start 87.052507 129.428943) (end 87.059903 129.407807) (width 0.1) (layer "In2.Cu") (net 180))
  (segment (start 86.25 129.451195) (end 86.252507 129.428943) (width 0.1) (layer "In2.Cu") (net 180))
  (segment (start 86.259903 129.407807) (end 86.271816 129.388847) (width 0.1) (layer "In2.Cu") (net 180))
  (segment (start 86.221434 129.893912) (end 86.230801 129.888027) (width 0.1) (layer "In2.Cu") (net 180))
  (segment (start 86.488409 129.897566) (end 86.499402 129.898805) (width 0.1) (layer "In2.Cu") (net 180))
  (segment (start 87.55 129.251195) (end 87.572252 129.253703) (width 0.1) (layer "In2.Cu") (net 180))
  (segment (start 86.248163 129.860395) (end 86.249402 129.849402) (width 0.1) (layer "In2.Cu") (net 180))
  (segment (start 87.247492 129.428943) (end 87.25 129.451195) (width 0.1) (layer "In2.Cu") (net 180))
  (segment (start 87.25 129.849403) (end 87.251238 129.860395) (width 0.1) (layer "In2.Cu") (net 180))
  (segment (start 88.028183 129.288847) (end 88.040096 129.307807) (width 0.1) (layer "In2.Cu") (net 180))
  (segment (start 88.106611 129.790097) (end 88.127747 129.797493) (width 0.1) (layer "In2.Cu") (net 180))
  (segment (start 87.439222 129.880204) (end 87.445107 129.870837) (width 0.1) (layer "In2.Cu") (net 180))
  (segment (start 86.648761 129.860395) (end 86.65 129.849403) (width 0.1) (layer "In2.Cu") (net 180))
  (segment (start 87.45 129.849403) (end 87.45 129.351195) (width 0.1) (layer "In2.Cu") (net 180))
  (segment (start 85.5 128.95) (end 85.5 129.4) (width 0.1) (layer "In2.Cu") (net 180))
  (segment (start 86.252507 129.428943) (end 86.259903 129.407807) (width 0.1) (layer "In2.Cu") (net 180))
  (segment (start 86.888409 129.897566) (end 86.899402 129.898805) (width 0.1) (layer "In2.Cu") (net 180))
  (segment (start 86.847492 129.328943) (end 86.85 129.351195) (width 0.1) (layer "In2.Cu") (net 180))
  (segment (start 87.628183 129.288847) (end 87.640096 129.307807) (width 0.1) (layer "In2.Cu") (net 180))
  (segment (start 88.65 129.45) (end 88.65 129) (width 0.1) (layer "In2.Cu") (net 180))
  (segment (start 92.8 127.35) (end 93.2 127.75) (width 0.1) (layer "F.Cu") (net 181))
  (segment (start 81.1 128.55) (end 81.5 128.95) (width 0.1) (layer "F.Cu") (net 181))
  (via blind (at 93.2 127.75) (size 0.5) (drill 0.2) (layers "F.Cu" "In2.Cu") (net 181))
  (via (at 81.5 128.95) (size 0.5) (drill 0.2) (layers "F.Cu" "B.Cu") (net 181))
  (segment (start 82.659903 128.794921) (end 82.671816 128.775961) (width 0.1) (layer "In2.Cu") (net 181))
  (segment (start 83.012348 129.139874) (end 83.028183 129.124039) (width 0.1) (layer "In2.Cu") (net 181))
  (segment (start 82.487651 129.139874) (end 82.506611 129.151787) (width 0.1) (layer "In2.Cu") (net 181))
  (segment (start 82.793388 128.748213) (end 82.812348 128.760126) (width 0.1) (layer "In2.Cu") (net 181))
  (segment (start 83.45 129.05) (end 83.452507 129.027747) (width 0.1) (layer "In2.Cu") (net 181))
  (segment (start 83.45 129.061691) (end 83.45 129.05) (width 0.1) (layer "In2.Cu") (net 181))
  (segment (start 83.15 128.738309) (end 83.172252 128.740817) (width 0.1) (layer "In2.Cu") (net 181))
  (segment (start 81.993388 128.959903) (end 82.012348 128.971816) (width 0.1) (layer "In2.Cu") (net 181))
  (segment (start 82.652507 128.816057) (end 82.659903 128.794921) (width 0.1) (layer "In2.Cu") (net 181))
  (segment (start 82.247492 129.083943) (end 82.25 129.061691) (width 0.1) (layer "In2.Cu") (net 181))
  (segment (start 82.55 129.161691) (end 82.572252 129.159183) (width 0.1) (layer "In2.Cu") (net 181))
  (segment (start 82.25 128.838309) (end 82.252507 128.816057) (width 0.1) (layer "In2.Cu") (net 181))
  (segment (start 82.847492 128.816057) (end 82.85 128.838309) (width 0.1) (layer "In2.Cu") (net 181))
  (segment (start 83.05 129.061691) (end 83.05 128.838309) (width 0.1) (layer "In2.Cu") (net 181))
  (segment (start 82.106611 129.151787) (end 82.127747 129.159183) (width 0.1) (layer "In2.Cu") (net 181))
  (segment (start 82.906611 129.151787) (end 82.927747 129.159183) (width 0.1) (layer "In2.Cu") (net 181))
  (segment (start 83.052507 128.816057) (end 83.059903 128.794921) (width 0.1) (layer "In2.Cu") (net 181))
  (segment (start 82.040096 129.006611) (end 82.047492 129.027747) (width 0.1) (layer "In2.Cu") (net 181))
  (segment (start 82.993388 129.151787) (end 83.012348 129.139874) (width 0.1) (layer "In2.Cu") (net 181))
  (segment (start 83.106611 128.748213) (end 83.127747 128.740817) (width 0.1) (layer "In2.Cu") (net 181))
  (segment (start 82.727747 128.740817) (end 82.75 128.738309) (width 0.1) (layer "In2.Cu") (net 181))
  (segment (start 82.059903 129.105079) (end 82.071816 129.124039) (width 0.1) (layer "In2.Cu") (net 181))
  (segment (start 82.687651 128.760126) (end 82.706611 128.748213) (width 0.1) (layer "In2.Cu") (net 181))
  (segment (start 82.228183 129.124039) (end 82.240096 129.105079) (width 0.1) (layer "In2.Cu") (net 181))
  (segment (start 83.087651 128.760126) (end 83.106611 128.748213) (width 0.1) (layer "In2.Cu") (net 181))
  (segment (start 82.240096 129.105079) (end 82.247492 129.083943) (width 0.1) (layer "In2.Cu") (net 181))
  (segment (start 82.871816 129.124039) (end 82.887651 129.139874) (width 0.1) (layer "In2.Cu") (net 181))
  (segment (start 83.240096 128.794921) (end 83.247492 128.816057) (width 0.1) (layer "In2.Cu") (net 181))
  (segment (start 82.972252 129.159183) (end 82.993388 129.151787) (width 0.1) (layer "In2.Cu") (net 181))
  (segment (start 83.35 129.161691) (end 83.372252 129.159183) (width 0.1) (layer "In2.Cu") (net 181))
  (segment (start 83.327747 129.159183) (end 83.35 129.161691) (width 0.1) (layer "In2.Cu") (net 181))
  (segment (start 82.05 129.05) (end 82.05 129.061691) (width 0.1) (layer "In2.Cu") (net 181))
  (segment (start 82.012348 128.971816) (end 82.028183 128.987651) (width 0.1) (layer "In2.Cu") (net 181))
  (segment (start 82.628183 129.124039) (end 82.640096 129.105079) (width 0.1) (layer "In2.Cu") (net 181))
  (segment (start 83.212348 128.760126) (end 83.228183 128.775961) (width 0.1) (layer "In2.Cu") (net 181))
  (segment (start 82.927747 129.159183) (end 82.95 129.161691) (width 0.1) (layer "In2.Cu") (net 181))
  (segment (start 83.028183 129.124039) (end 83.040096 129.105079) (width 0.1) (layer "In2.Cu") (net 181))
  (segment (start 82.372252 128.740817) (end 82.393388 128.748213) (width 0.1) (layer "In2.Cu") (net 181))
  (segment (start 83.172252 128.740817) (end 83.193388 128.748213) (width 0.1) (layer "In2.Cu") (net 181))
  (segment (start 81.95 128.95) (end 81.972252 128.952507) (width 0.1) (layer "In2.Cu") (net 181))
  (segment (start 82.047492 129.027747) (end 82.05 129.05) (width 0.1) (layer "In2.Cu") (net 181))
  (segment (start 82.15 129.161691) (end 82.172252 129.159183) (width 0.1) (layer "In2.Cu") (net 181))
  (segment (start 82.85 128.838309) (end 82.85 129.061691) (width 0.1) (layer "In2.Cu") (net 181))
  (segment (start 83.506611 128.959903) (end 83.527747 128.952507) (width 0.1) (layer "In2.Cu") (net 181))
  (segment (start 83.193388 128.748213) (end 83.212348 128.760126) (width 0.1) (layer "In2.Cu") (net 181))
  (segment (start 83.127747 128.740817) (end 83.15 128.738309) (width 0.1) (layer "In2.Cu") (net 181))
  (segment (start 83.447492 129.083943) (end 83.45 129.061691) (width 0.1) (layer "In2.Cu") (net 181))
  (segment (start 83.047492 129.083943) (end 83.05 129.061691) (width 0.1) (layer "In2.Cu") (net 181))
  (segment (start 82.647492 129.083943) (end 82.65 129.061691) (width 0.1) (layer "In2.Cu") (net 181))
  (segment (start 83.440096 129.105079) (end 83.447492 129.083943) (width 0.1) (layer "In2.Cu") (net 181))
  (segment (start 83.271816 129.124039) (end 83.287651 129.139874) (width 0.1) (layer "In2.Cu") (net 181))
  (segment (start 83.259903 129.105079) (end 83.271816 129.124039) (width 0.1) (layer "In2.Cu") (net 181))
  (segment (start 82.506611 129.151787) (end 82.527747 129.159183) (width 0.1) (layer "In2.Cu") (net 181))
  (segment (start 83.059903 128.794921) (end 83.071816 128.775961) (width 0.1) (layer "In2.Cu") (net 181))
  (segment (start 82.459903 129.105079) (end 82.471816 129.124039) (width 0.1) (layer "In2.Cu") (net 181))
  (segment (start 82.887651 129.139874) (end 82.906611 129.151787) (width 0.1) (layer "In2.Cu") (net 181))
  (segment (start 82.45 128.838309) (end 82.45 129.061691) (width 0.1) (layer "In2.Cu") (net 181))
  (segment (start 82.447492 128.816057) (end 82.45 128.838309) (width 0.1) (layer "In2.Cu") (net 181))
  (segment (start 83.071816 128.775961) (end 83.087651 128.760126) (width 0.1) (layer "In2.Cu") (net 181))
  (segment (start 82.593388 129.151787) (end 82.612348 129.139874) (width 0.1) (layer "In2.Cu") (net 181))
  (segment (start 82.440096 128.794921) (end 82.447492 128.816057) (width 0.1) (layer "In2.Cu") (net 181))
  (segment (start 82.65 129.061691) (end 82.65 128.838309) (width 0.1) (layer "In2.Cu") (net 181))
  (segment (start 82.706611 128.748213) (end 82.727747 128.740817) (width 0.1) (layer "In2.Cu") (net 181))
  (segment (start 82.859903 129.105079) (end 82.871816 129.124039) (width 0.1) (layer "In2.Cu") (net 181))
  (segment (start 83.228183 128.775961) (end 83.240096 128.794921) (width 0.1) (layer "In2.Cu") (net 181))
  (segment (start 82.640096 129.105079) (end 82.647492 129.083943) (width 0.1) (layer "In2.Cu") (net 181))
  (segment (start 82.212348 129.139874) (end 82.228183 129.124039) (width 0.1) (layer "In2.Cu") (net 181))
  (segment (start 82.471816 129.124039) (end 82.487651 129.139874) (width 0.1) (layer "In2.Cu") (net 181))
  (segment (start 82.087651 129.139874) (end 82.106611 129.151787) (width 0.1) (layer "In2.Cu") (net 181))
  (segment (start 82.840096 128.794921) (end 82.847492 128.816057) (width 0.1) (layer "In2.Cu") (net 181))
  (segment (start 81.972252 128.952507) (end 81.993388 128.959903) (width 0.1) (layer "In2.Cu") (net 181))
  (segment (start 83.55 128.95) (end 84.8 128.95) (width 0.1) (layer "In2.Cu") (net 181))
  (segment (start 83.247492 128.816057) (end 83.25 128.838309) (width 0.1) (layer "In2.Cu") (net 181))
  (segment (start 82.306611 128.748213) (end 82.327747 128.740817) (width 0.1) (layer "In2.Cu") (net 181))
  (segment (start 92.75 128.2) (end 93.2 127.75) (width 0.1) (layer "In2.Cu") (net 181))
  (segment (start 82.052507 129.083943) (end 82.059903 129.105079) (width 0.1) (layer "In2.Cu") (net 181))
  (segment (start 82.287651 128.760126) (end 82.306611 128.748213) (width 0.1) (layer "In2.Cu") (net 181))
  (segment (start 82.671816 128.775961) (end 82.687651 128.760126) (width 0.1) (layer "In2.Cu") (net 181))
  (segment (start 83.05 128.838309) (end 83.052507 128.816057) (width 0.1) (layer "In2.Cu") (net 181))
  (segment (start 83.393388 129.151787) (end 83.412348 129.139874) (width 0.1) (layer "In2.Cu") (net 181))
  (segment (start 83.252507 129.083943) (end 83.259903 129.105079) (width 0.1) (layer "In2.Cu") (net 181))
  (segment (start 83.287651 129.139874) (end 83.306611 129.151787) (width 0.1) (layer "In2.Cu") (net 181))
  (segment (start 84.8 128.95) (end 85.2 128.55) (width 0.1) (layer "In2.Cu") (net 181))
  (segment (start 82.85 129.061691) (end 82.852507 129.083943) (width 0.1) (layer "In2.Cu") (net 181))
  (segment (start 82.452507 129.083943) (end 82.459903 129.105079) (width 0.1) (layer "In2.Cu") (net 181))
  (segment (start 83.527747 128.952507) (end 83.55 128.95) (width 0.1) (layer "In2.Cu") (net 181))
  (segment (start 83.040096 129.105079) (end 83.047492 129.083943) (width 0.1) (layer "In2.Cu") (net 181))
  (segment (start 82.772252 128.740817) (end 82.793388 128.748213) (width 0.1) (layer "In2.Cu") (net 181))
  (segment (start 83.459903 129.006611) (end 83.471816 128.987651) (width 0.1) (layer "In2.Cu") (net 181))
  (segment (start 82.25 129.061691) (end 82.25 128.838309) (width 0.1) (layer "In2.Cu") (net 181))
  (segment (start 82.05 129.061691) (end 82.052507 129.083943) (width 0.1) (layer "In2.Cu") (net 181))
  (segment (start 82.071816 129.124039) (end 82.087651 129.139874) (width 0.1) (layer "In2.Cu") (net 181))
  (segment (start 83.428183 129.124039) (end 83.440096 129.105079) (width 0.1) (layer "In2.Cu") (net 181))
  (segment (start 82.393388 128.748213) (end 82.412348 128.760126) (width 0.1) (layer "In2.Cu") (net 181))
  (segment (start 83.412348 129.139874) (end 83.428183 129.124039) (width 0.1) (layer "In2.Cu") (net 181))
  (segment (start 82.65 128.838309) (end 82.652507 128.816057) (width 0.1) (layer "In2.Cu") (net 181))
  (segment (start 82.45 129.061691) (end 82.452507 129.083943) (width 0.1) (layer "In2.Cu") (net 181))
  (segment (start 83.25 128.838309) (end 83.25 129.061691) (width 0.1) (layer "In2.Cu") (net 181))
  (segment (start 85.2 128.55) (end 89.1 128.55) (width 0.1) (layer "In2.Cu") (net 181))
  (segment (start 82.271816 128.775961) (end 82.287651 128.760126) (width 0.1) (layer "In2.Cu") (net 181))
  (segment (start 89.45 128.2) (end 92.75 128.2) (width 0.1) (layer "In2.Cu") (net 181))
  (segment (start 83.306611 129.151787) (end 83.327747 129.159183) (width 0.1) (layer "In2.Cu") (net 181))
  (segment (start 82.612348 129.139874) (end 82.628183 129.124039) (width 0.1) (layer "In2.Cu") (net 181))
  (segment (start 82.527747 129.159183) (end 82.55 129.161691) (width 0.1) (layer "In2.Cu") (net 181))
  (segment (start 82.75 128.738309) (end 82.772252 128.740817) (width 0.1) (layer "In2.Cu") (net 181))
  (segment (start 82.259903 128.794921) (end 82.271816 128.775961) (width 0.1) (layer "In2.Cu") (net 181))
  (segment (start 82.327747 128.740817) (end 82.35 128.738309) (width 0.1) (layer "In2.Cu") (net 181))
  (segment (start 82.95 129.161691) (end 82.972252 129.159183) (width 0.1) (layer "In2.Cu") (net 181))
  (segment (start 82.852507 129.083943) (end 82.859903 129.105079) (width 0.1) (layer "In2.Cu") (net 181))
  (segment (start 82.193388 129.151787) (end 82.212348 129.139874) (width 0.1) (layer "In2.Cu") (net 181))
  (segment (start 83.25 129.061691) (end 83.252507 129.083943) (width 0.1) (layer "In2.Cu") (net 181))
  (segment (start 89.1 128.55) (end 89.45 128.2) (width 0.1) (layer "In2.Cu") (net 181))
  (segment (start 83.372252 129.159183) (end 83.393388 129.151787) (width 0.1) (layer "In2.Cu") (net 181))
  (segment (start 82.828183 128.775961) (end 82.840096 128.794921) (width 0.1) (layer "In2.Cu") (net 181))
  (segment (start 82.428183 128.775961) (end 82.440096 128.794921) (width 0.1) (layer "In2.Cu") (net 181))
  (segment (start 83.452507 129.027747) (end 83.459903 129.006611) (width 0.1) (layer "In2.Cu") (net 181))
  (segment (start 82.172252 129.159183) (end 82.193388 129.151787) (width 0.1) (layer "In2.Cu") (net 181))
  (segment (start 82.028183 128.987651) (end 82.040096 129.006611) (width 0.1) (layer "In2.Cu") (net 181))
  (segment (start 83.487651 128.971816) (end 83.506611 128.959903) (width 0.1) (layer "In2.Cu") (net 181))
  (segment (start 82.127747 129.159183) (end 82.15 129.161691) (width 0.1) (layer "In2.Cu") (net 181))
  (segment (start 82.812348 128.760126) (end 82.828183 128.775961) (width 0.1) (layer "In2.Cu") (net 181))
  (segment (start 83.471816 128.987651) (end 83.487651 128.971816) (width 0.1) (layer "In2.Cu") (net 181))
  (segment (start 82.412348 128.760126) (end 82.428183 128.775961) (width 0.1) (layer "In2.Cu") (net 181))
  (segment (start 81.5 128.95) (end 81.95 128.95) (width 0.1) (layer "In2.Cu") (net 181))
  (segment (start 82.252507 128.816057) (end 82.259903 128.794921) (width 0.1) (layer "In2.Cu") (net 181))
  (segment (start 82.572252 129.159183) (end 82.593388 129.151787) (width 0.1) (layer "In2.Cu") (net 181))
  (segment (start 82.35 128.738309) (end 82.372252 128.740817) (width 0.1) (layer "In2.Cu") (net 181))
  (segment (start 83.7 127.85) (end 83.85 127.85) (width 0.1) (layer "F.Cu") (net 182))
  (segment (start 84.25 127.85) (end 84.65 127.85) (width 0.1) (layer "F.Cu") (net 182))
  (segment (start 84.171816 127.887651) (end 84.187651 127.871816) (width 0.1) (layer "F.Cu") (net 182))
  (segment (start 83.947492 127.927747) (end 83.95 127.95) (width 0.1) (layer "F.Cu") (net 182))
  (segment (start 92 127.35) (end 91.6 127.75) (width 0.1) (layer "F.Cu") (net 182))
  (segment (start 84.15 128.3) (end 84.15 127.95) (width 0.1) (layer "F.Cu") (net 182))
  (segment (start 84.187651 127.871816) (end 84.206611 127.859903) (width 0.1) (layer "F.Cu") (net 182))
  (segment (start 84.227747 127.852507) (end 84.25 127.85) (width 0.1) (layer "F.Cu") (net 182))
  (segment (start 84.75 127.75) (end 84.975739 127.75) (width 0.1) (layer "F.Cu") (net 182))
  (segment (start 83.952507 128.322252) (end 83.959903 128.343388) (width 0.1) (layer "F.Cu") (net 182))
  (segment (start 83.912348 127.871816) (end 83.928183 127.887651) (width 0.1) (layer "F.Cu") (net 182))
  (segment (start 83.928183 127.887651) (end 83.940096 127.906611) (width 0.1) (layer "F.Cu") (net 182))
  (segment (start 84.65 127.85) (end 84.75 127.75) (width 0.1) (layer "F.Cu") (net 182))
  (segment (start 84.006611 128.390096) (end 84.027747 128.397492) (width 0.1) (layer "F.Cu") (net 182))
  (segment (start 83.971816 128.362348) (end 83.987651 128.378183) (width 0.1) (layer "F.Cu") (net 182))
  (segment (start 83.987651 128.378183) (end 84.006611 128.390096) (width 0.1) (layer "F.Cu") (net 182))
  (segment (start 83.95 128.3) (end 83.952507 128.322252) (width 0.1) (layer "F.Cu") (net 182))
  (segment (start 84.128183 128.362348) (end 84.140096 128.343388) (width 0.1) (layer "F.Cu") (net 182))
  (segment (start 84.072252 128.397492) (end 84.093388 128.390096) (width 0.1) (layer "F.Cu") (net 182))
  (segment (start 83.959903 128.343388) (end 83.971816 128.362348) (width 0.1) (layer "F.Cu") (net 182))
  (segment (start 83.85 127.85) (end 83.872252 127.852507) (width 0.1) (layer "F.Cu") (net 182))
  (segment (start 83.95 127.95) (end 83.95 128.3) (width 0.1) (layer "F.Cu") (net 182))
  (segment (start 84.206611 127.859903) (end 84.227747 127.852507) (width 0.1) (layer "F.Cu") (net 182))
  (segment (start 84.112348 128.378183) (end 84.128183 128.362348) (width 0.1) (layer "F.Cu") (net 182))
  (segment (start 83.5 128.05) (end 83.7 127.85) (width 0.1) (layer "F.Cu") (net 182))
  (segment (start 84.15 127.95) (end 84.152507 127.927747) (width 0.1) (layer "F.Cu") (net 182))
  (segment (start 83.872252 127.852507) (end 83.893388 127.859903) (width 0.1) (layer "F.Cu") (net 182))
  (segment (start 83.5 128.4) (end 83.5 128.05) (width 0.1) (layer "F.Cu") (net 182))
  (segment (start 83.940096 127.906611) (end 83.947492 127.927747) (width 0.1) (layer "F.Cu") (net 182))
  (segment (start 83.893388 127.859903) (end 83.912348 127.871816) (width 0.1) (layer "F.Cu") (net 182))
  (segment (start 84.140096 128.343388) (end 84.147492 128.322252) (width 0.1) (layer "F.Cu") (net 182))
  (segment (start 84.152507 127.927747) (end 84.159903 127.906611) (width 0.1) (layer "F.Cu") (net 182))
  (segment (start 84.05 128.4) (end 84.072252 128.397492) (width 0.1) (layer "F.Cu") (net 182))
  (segment (start 84.093388 128.390096) (end 84.112348 128.378183) (width 0.1) (layer "F.Cu") (net 182))
  (segment (start 84.147492 128.322252) (end 84.15 128.3) (width 0.1) (layer "F.Cu") (net 182))
  (segment (start 84.159903 127.906611) (end 84.171816 127.887651) (width 0.1) (layer "F.Cu") (net 182))
  (segment (start 84.027747 128.397492) (end 84.05 128.4) (width 0.1) (layer "F.Cu") (net 182))
  (via (at 83.5 128.4) (size 0.5) (drill 0.2) (layers "F.Cu" "B.Cu") (net 182))
  (via blind (at 91.6 127.75) (size 0.5) (drill 0.2) (layers "F.Cu" "In2.Cu") (net 182))
  (segment (start 85.290096 127.806611) (end 85.297492 127.827747) (width 0.1) (layer "In2.Cu") (net 182))
  (segment (start 84.092058 128.340685) (end 84.109565 128.326723) (width 0.1) (layer "In2.Cu") (net 182))
  (segment (start 83.7 128.2) (end 83.717507 128.186038) (width 0.1) (layer "In2.Cu") (net 182))
  (segment (start 85.843388 128.21931) (end 85.862348 128.207397) (width 0.1) (layer "In2.Cu") (net 182))
  (segment (start 85.622252 127.752507) (end 85.643388 127.759903) (width 0.1) (layer "In2.Cu") (net 182))
  (segment (start 85.302507 128.151466) (end 85.309903 128.172602) (width 0.1) (layer "In2.Cu") (net 182))
  (segment (start 84.502507 128.051466) (end 84.509903 128.072602) (width 0.1) (layer "In2.Cu") (net 182))
  (segment (start 83.759514 128.171339) (end 83.781907 128.171339) (width 0.1) (layer "In2.Cu") (net 182))
  (segment (start 85.8 128.229214) (end 85.822252 128.226706) (width 0.1) (layer "In2.Cu") (net 182))
  (segment (start 85.7 128.129214) (end 85.702507 128.151466) (width 0.1) (layer "In2.Cu") (net 182))
  (segment (start 85.309903 128.172602) (end 85.321816 128.191562) (width 0.1) (layer "In2.Cu") (net 182))
  (segment (start 85.2 127.75) (end 85.222252 127.752507) (width 0.1) (layer "In2.Cu") (net 182))
  (segment (start 85.497492 128.151466) (end 85.5 128.129214) (width 0.1) (layer "In2.Cu") (net 182))
  (segment (start 84.133242 128.222984) (end 84.123526 128.202809) (width 0.1) (layer "In2.Cu") (net 182))
  (segment (start 85.377747 128.226706) (end 85.4 128.229214) (width 0.1) (layer "In2.Cu") (net 182))
  (segment (start 84.443388 127.759903) (end 84.462348 127.771816) (width 0.1) (layer "In2.Cu") (net 182))
  (segment (start 84.6 128.129214) (end 84.622252 128.126706) (width 0.1) (layer "In2.Cu") (net 182))
  (segment (start 84.4 127.75) (end 84.422252 127.752507) (width 0.1) (layer "In2.Cu") (net 182))
  (segment (start 85.537651 127.771816) (end 85.556611 127.759903) (width 0.1) (layer "In2.Cu") (net 182))
  (segment (start 85.5 127.85) (end 85.502507 127.827747) (width 0.1) (layer "In2.Cu") (net 182))
  (segment (start 84.497492 127.827747) (end 84.5 127.85) (width 0.1) (layer "In2.Cu") (net 182))
  (segment (start 84.721816 127.787651) (end 84.737651 127.771816) (width 0.1) (layer "In2.Cu") (net 182))
  (segment (start 83.878596 127.952928) (end 83.874747 127.944938) (width 0.1) (layer "In2.Cu") (net 182))
  (segment (start 84.490096 127.806611) (end 84.497492 127.827747) (width 0.1) (layer "In2.Cu") (net 182))
  (segment (start 84.690096 128.072602) (end 84.697492 128.051466) (width 0.1) (layer "In2.Cu") (net 182))
  (segment (start 85.862348 128.207397) (end 85.878183 128.191562) (width 0.1) (layer "In2.Cu") (net 182))
  (segment (start 85.690096 127.806611) (end 85.697492 127.827747) (width 0.1) (layer "In2.Cu") (net 182))
  (segment (start 84.5 128.029214) (end 84.502507 128.051466) (width 0.1) (layer "In2.Cu") (net 182))
  (segment (start 84.678183 128.091562) (end 84.690096 128.072602) (width 0.1) (layer "In2.Cu") (net 182))
  (segment (start 85.822252 128.226706) (end 85.843388 128.21931) (width 0.1) (layer "In2.Cu") (net 182))
  (segment (start 84.057989 127.829793) (end 84.066636 127.82782) (width 0.1) (layer "In2.Cu") (net 182))
  (segment (start 84.509903 128.072602) (end 84.521816 128.091562) (width 0.1) (layer "In2.Cu") (net 182))
  (segment (start 85.022252 128.226706) (end 85.043388 128.21931) (width 0.1) (layer "In2.Cu") (net 182))
  (segment (start 85.090096 128.172602) (end 85.097492 128.151466) (width 0.1) (layer "In2.Cu") (net 182))
  (segment (start 83.803738 128.176322) (end 83.823913 128.186038) (width 0.1) (layer "In2.Cu") (net 182))
  (segment (start 83.5 128.4) (end 83.7 128.2) (width 0.1) (layer "In2.Cu") (net 182))
  (segment (start 83.884126 127.959862) (end 83.878596 127.952928) (width 0.1) (layer "In2.Cu") (net 182))
  (segment (start 85.062348 128.207397) (end 85.078183 128.191562) (width 0.1) (layer "In2.Cu") (net 182))
  (segment (start 84.878183 127.787651) (end 84.890096 127.806611) (width 0.1) (layer "In2.Cu") (net 182))
  (segment (start 85.977747 127.752507) (end 86 127.75) (width 0.1) (layer "In2.Cu") (net 182))
  (segment (start 84.577747 128.126706) (end 84.6 128.129214) (width 0.1) (layer "In2.Cu") (net 182))
  (segment (start 84.040474 127.82782) (end 84.049119 127.829794) (width 0.1) (layer "In2.Cu") (net 182))
  (segment (start 85.177747 127.752507) (end 85.2 127.75) (width 0.1) (layer "In2.Cu") (net 182))
  (segment (start 84.909903 128.172602) (end 84.921816 128.191562) (width 0.1) (layer "In2.Cu") (net 182))
  (segment (start 84.956611 128.21931) (end 84.977747 128.226706) (width 0.1) (layer "In2.Cu") (net 182))
  (segment (start 85.643388 127.759903) (end 85.662348 127.771816) (width 0.1) (layer "In2.Cu") (net 182))
  (segment (start 85.3 128.129214) (end 85.302507 128.151466) (width 0.1) (layer "In2.Cu") (net 182))
  (segment (start 84.643388 128.11931) (end 84.662348 128.107397) (width 0.1) (layer "In2.Cu") (net 182))
  (segment (start 85.356611 128.21931) (end 85.377747 128.226706) (width 0.1) (layer "In2.Cu") (net 182))
  (segment (start 84.109565 128.326723) (end 84.123526 128.309215) (width 0.1) (layer "In2.Cu") (net 182))
  (segment (start 85.6 127.75) (end 85.622252 127.752507) (width 0.1) (layer "In2.Cu") (net 182))
  (segment (start 85.137651 127.771816) (end 85.156611 127.759903) (width 0.1) (layer "In2.Cu") (net 182))
  (segment (start 85.7 127.85) (end 85.7 128.129214) (width 0.1) (layer "In2.Cu") (net 182))
  (segment (start 83.841421 128.2) (end 83.968144 128.326723) (width 0.1) (layer "In2.Cu") (net 182))
  (segment (start 85.678183 127.787651) (end 85.690096 127.806611) (width 0.1) (layer "In2.Cu") (net 182))
  (segment (start 83.872775 127.927421) (end 83.874748 127.918774) (width 0.1) (layer "In2.Cu") (net 182))
  (segment (start 83.985651 128.340685) (end 84.005827 128.350401) (width 0.1) (layer "In2.Cu") (net 182))
  (segment (start 85.4 128.229214) (end 85.422252 128.226706) (width 0.1) (layer "In2.Cu") (net 182))
  (segment (start 85.109903 127.806611) (end 85.121816 127.787651) (width 0.1) (layer "In2.Cu") (net 182))
  (segment (start 85.502507 127.827747) (end 85.509903 127.806611) (width 0.1) (layer "In2.Cu") (net 182))
  (segment (start 85.556611 127.759903) (end 85.577747 127.752507) (width 0.1) (layer "In2.Cu") (net 182))
  (segment (start 84.5 127.85) (end 84.5 128.029214) (width 0.1) (layer "In2.Cu") (net 182))
  (segment (start 84.702507 127.827747) (end 84.709903 127.806611) (width 0.1) (layer "In2.Cu") (net 182))
  (segment (start 84.697492 128.051466) (end 84.7 128.029214) (width 0.1) (layer "In2.Cu") (net 182))
  (segment (start 83.781907 128.171339) (end 83.803738 128.176322) (width 0.1) (layer "In2.Cu") (net 182))
  (segment (start 85.222252 127.752507) (end 85.243388 127.759903) (width 0.1) (layer "In2.Cu") (net 182))
  (segment (start 84.032483 127.823971) (end 84.040474 127.82782) (width 0.1) (layer "In2.Cu") (net 182))
  (segment (start 83.874748 127.918774) (end 83.878596 127.910784) (width 0.1) (layer "In2.Cu") (net 182))
  (segment (start 85.756611 128.21931) (end 85.777747 128.226706) (width 0.1) (layer "In2.Cu") (net 182))
  (segment (start 84.622252 128.126706) (end 84.643388 128.11931) (width 0.1) (layer "In2.Cu") (net 182))
  (segment (start 84.709903 127.806611) (end 84.721816 127.787651) (width 0.1) (layer "In2.Cu") (net 182))
  (segment (start 84.9 127.85) (end 84.9 128.129214) (width 0.1) (layer "In2.Cu") (net 182))
  (segment (start 84.862348 127.771816) (end 84.878183 127.787651) (width 0.1) (layer "In2.Cu") (net 182))
  (segment (start 84.7 127.85) (end 84.702507 127.827747) (width 0.1) (layer "In2.Cu") (net 182))
  (segment (start 84.050051 128.355383) (end 84.071883 128.350401) (width 0.1) (layer "In2.Cu") (net 182))
  (segment (start 84.521816 128.091562) (end 84.537651 128.107397) (width 0.1) (layer "In2.Cu") (net 182))
  (segment (start 84.662348 128.107397) (end 84.678183 128.091562) (width 0.1) (layer "In2.Cu") (net 182))
  (segment (start 84.937651 128.207397) (end 84.956611 128.21931) (width 0.1) (layer "In2.Cu") (net 182))
  (segment (start 84.15 127.75) (end 84.4 127.75) (width 0.1) (layer "In2.Cu") (net 182))
  (segment (start 85.737651 128.207397) (end 85.756611 128.21931) (width 0.1) (layer "In2.Cu") (net 182))
  (segment (start 83.969535 127.818441) (end 83.976469 127.812911) (width 0.1) (layer "In2.Cu") (net 182))
  (segment (start 83.874747 127.944938) (end 83.872774 127.936291) (width 0.1) (layer "In2.Cu") (net 182))
  (segment (start 84.556611 128.11931) (end 84.577747 128.126706) (width 0.1) (layer "In2.Cu") (net 182))
  (segment (start 85.243388 127.759903) (end 85.262348 127.771816) (width 0.1) (layer "In2.Cu") (net 182))
  (segment (start 84.071883 128.350401) (end 84.092058 128.340685) (width 0.1) (layer "In2.Cu") (net 182))
  (segment (start 86 127.75) (end 91.6 127.75) (width 0.1) (layer "In2.Cu") (net 182))
  (segment (start 85.721816 128.191562) (end 85.737651 128.207397) (width 0.1) (layer "In2.Cu") (net 182))
  (segment (start 85.490096 128.172602) (end 85.497492 128.151466) (width 0.1) (layer "In2.Cu") (net 182))
  (segment (start 83.968144 128.326723) (end 83.985651 128.340685) (width 0.1) (layer "In2.Cu") (net 182))
  (segment (start 85.937651 127.771816) (end 85.956611 127.759903) (width 0.1) (layer "In2.Cu") (net 182))
  (segment (start 84.843388 127.759903) (end 84.862348 127.771816) (width 0.1) (layer "In2.Cu") (net 182))
  (segment (start 84.123526 128.309215) (end 84.133242 128.28904) (width 0.1) (layer "In2.Cu") (net 182))
  (segment (start 85.9 127.85) (end 85.902507 127.827747) (width 0.1) (layer "In2.Cu") (net 182))
  (segment (start 85.043388 128.21931) (end 85.062348 128.207397) (width 0.1) (layer "In2.Cu") (net 182))
  (segment (start 83.717507 128.186038) (end 83.737682 128.176322) (width 0.1) (layer "In2.Cu") (net 182))
  (segment (start 84.422252 127.752507) (end 84.443388 127.759903) (width 0.1) (layer "In2.Cu") (net 182))
  (segment (start 85.909903 127.806611) (end 85.921816 127.787651) (width 0.1) (layer "In2.Cu") (net 182))
  (segment (start 85.262348 127.771816) (end 85.278183 127.787651) (width 0.1) (layer "In2.Cu") (net 182))
  (segment (start 85.443388 128.21931) (end 85.462348 128.207397) (width 0.1) (layer "In2.Cu") (net 182))
  (segment (start 85.878183 128.191562) (end 85.890096 128.172602) (width 0.1) (layer "In2.Cu") (net 182))
  (segment (start 83.976469 127.812911) (end 83.984459 127.809064) (width 0.1) (layer "In2.Cu") (net 182))
  (segment (start 85.1 127.85) (end 85.102507 127.827747) (width 0.1) (layer "In2.Cu") (net 182))
  (segment (start 85.902507 127.827747) (end 85.909903 127.806611) (width 0.1) (layer "In2.Cu") (net 182))
  (segment (start 85.702507 128.151466) (end 85.709903 128.172602) (width 0.1) (layer "In2.Cu") (net 182))
  (segment (start 84.9 128.129214) (end 84.902507 128.151466) (width 0.1) (layer "In2.Cu") (net 182))
  (segment (start 84.018613 127.812912) (end 84.025547 127.818442) (width 0.1) (layer "In2.Cu") (net 182))
  (segment (start 85.097492 128.151466) (end 85.1 128.129214) (width 0.1) (layer "In2.Cu") (net 182))
  (segment (start 84.756611 127.759903) (end 84.777747 127.752507) (width 0.1) (layer "In2.Cu") (net 182))
  (segment (start 84.109565 128.185301) (end 83.884126 127.959862) (width 0.1) (layer "In2.Cu") (net 182))
  (segment (start 85 128.229214) (end 85.022252 128.226706) (width 0.1) (layer "In2.Cu") (net 182))
  (segment (start 84.001975 127.80709) (end 84.010623 127.809063) (width 0.1) (layer "In2.Cu") (net 182))
  (segment (start 84.074627 127.823971) (end 84.081561 127.818441) (width 0.1) (layer "In2.Cu") (net 182))
  (segment (start 84.462348 127.771816) (end 84.478183 127.787651) (width 0.1) (layer "In2.Cu") (net 182))
  (segment (start 84.138225 128.267208) (end 84.138225 128.244815) (width 0.1) (layer "In2.Cu") (net 182))
  (segment (start 85.921816 127.787651) (end 85.937651 127.771816) (width 0.1) (layer "In2.Cu") (net 182))
  (segment (start 85.1 128.129214) (end 85.1 127.85) (width 0.1) (layer "In2.Cu") (net 182))
  (segment (start 85.709903 128.172602) (end 85.721816 128.191562) (width 0.1) (layer "In2.Cu") (net 182))
  (segment (start 85.3 127.85) (end 85.3 128.129214) (width 0.1) (layer "In2.Cu") (net 182))
  (segment (start 85.897492 128.151466) (end 85.9 128.129214) (width 0.1) (layer "In2.Cu") (net 182))
  (segment (start 85.577747 127.752507) (end 85.6 127.75) (width 0.1) (layer "In2.Cu") (net 182))
  (segment (start 84.897492 127.827747) (end 84.9 127.85) (width 0.1) (layer "In2.Cu") (net 182))
  (segment (start 84.066636 127.82782) (end 84.074627 127.823971) (width 0.1) (layer "In2.Cu") (net 182))
  (segment (start 83.884125 127.90385) (end 83.969535 127.818441) (width 0.1) (layer "In2.Cu") (net 182))
  (segment (start 85.321816 128.191562) (end 85.337651 128.207397) (width 0.1) (layer "In2.Cu") (net 182))
  (segment (start 83.984459 127.809064) (end 83.993107 127.807089) (width 0.1) (layer "In2.Cu") (net 182))
  (segment (start 84.027658 128.355383) (end 84.050051 128.355383) (width 0.1) (layer "In2.Cu") (net 182))
  (segment (start 85.890096 128.172602) (end 85.897492 128.151466) (width 0.1) (layer "In2.Cu") (net 182))
  (segment (start 84.478183 127.787651) (end 84.490096 127.806611) (width 0.1) (layer "In2.Cu") (net 182))
  (segment (start 83.993107 127.807089) (end 84.001975 127.80709) (width 0.1) (layer "In2.Cu") (net 182))
  (segment (start 85.422252 128.226706) (end 85.443388 128.21931) (width 0.1) (layer "In2.Cu") (net 182))
  (segment (start 84.010623 127.809063) (end 84.018613 127.812912) (width 0.1) (layer "In2.Cu") (net 182))
  (segment (start 84.049119 127.829794) (end 84.057989 127.829793) (width 0.1) (layer "In2.Cu") (net 182))
  (segment (start 85.278183 127.787651) (end 85.290096 127.806611) (width 0.1) (layer "In2.Cu") (net 182))
  (segment (start 85.956611 127.759903) (end 85.977747 127.752507) (width 0.1) (layer "In2.Cu") (net 182))
  (segment (start 84.977747 128.226706) (end 85 128.229214) (width 0.1) (layer "In2.Cu") (net 182))
  (segment (start 83.823913 128.186038) (end 83.841421 128.2) (width 0.1) (layer "In2.Cu") (net 182))
  (segment (start 84.7 128.029214) (end 84.7 127.85) (width 0.1) (layer "In2.Cu") (net 182))
  (segment (start 83.872774 127.936291) (end 83.872775 127.927421) (width 0.1) (layer "In2.Cu") (net 182))
  (segment (start 83.737682 128.176322) (end 83.759514 128.171339) (width 0.1) (layer "In2.Cu") (net 182))
  (segment (start 85.156611 127.759903) (end 85.177747 127.752507) (width 0.1) (layer "In2.Cu") (net 182))
  (segment (start 84.890096 127.806611) (end 84.897492 127.827747) (width 0.1) (layer "In2.Cu") (net 182))
  (segment (start 85.462348 128.207397) (end 85.478183 128.191562) (width 0.1) (layer "In2.Cu") (net 182))
  (segment (start 85.777747 128.226706) (end 85.8 128.229214) (width 0.1) (layer "In2.Cu") (net 182))
  (segment (start 85.478183 128.191562) (end 85.490096 128.172602) (width 0.1) (layer "In2.Cu") (net 182))
  (segment (start 85.697492 127.827747) (end 85.7 127.85) (width 0.1) (layer "In2.Cu") (net 182))
  (segment (start 84.005827 128.350401) (end 84.027658 128.355383) (width 0.1) (layer "In2.Cu") (net 182))
  (segment (start 85.662348 127.771816) (end 85.678183 127.787651) (width 0.1) (layer "In2.Cu") (net 182))
  (segment (start 85.121816 127.787651) (end 85.137651 127.771816) (width 0.1) (layer "In2.Cu") (net 182))
  (segment (start 85.509903 127.806611) (end 85.521816 127.787651) (width 0.1) (layer "In2.Cu") (net 182))
  (segment (start 84.081561 127.818441) (end 84.15 127.75) (width 0.1) (layer "In2.Cu") (net 182))
  (segment (start 84.777747 127.752507) (end 84.8 127.75) (width 0.1) (layer "In2.Cu") (net 182))
  (segment (start 83.878596 127.910784) (end 83.884125 127.90385) (width 0.1) (layer "In2.Cu") (net 182))
  (segment (start 84.133242 128.28904) (end 84.138225 128.267208) (width 0.1) (layer "In2.Cu") (net 182))
  (segment (start 85.297492 127.827747) (end 85.3 127.85) (width 0.1) (layer "In2.Cu") (net 182))
  (segment (start 85.521816 127.787651) (end 85.537651 127.771816) (width 0.1) (layer "In2.Cu") (net 182))
  (segment (start 84.902507 128.151466) (end 84.909903 128.172602) (width 0.1) (layer "In2.Cu") (net 182))
  (segment (start 85.102507 127.827747) (end 85.109903 127.806611) (width 0.1) (layer "In2.Cu") (net 182))
  (segment (start 84.123526 128.202809) (end 84.109565 128.185301) (width 0.1) (layer "In2.Cu") (net 182))
  (segment (start 84.921816 128.191562) (end 84.937651 128.207397) (width 0.1) (layer "In2.Cu") (net 182))
  (segment (start 85.9 128.129214) (end 85.9 127.85) (width 0.1) (layer "In2.Cu") (net 182))
  (segment (start 85.337651 128.207397) (end 85.356611 128.21931) (width 0.1) (layer "In2.Cu") (net 182))
  (segment (start 84.537651 128.107397) (end 84.556611 128.11931) (width 0.1) (layer "In2.Cu") (net 182))
  (segment (start 84.822252 127.752507) (end 84.843388 127.759903) (width 0.1) (layer "In2.Cu") (net 182))
  (segment (start 84.737651 127.771816) (end 84.756611 127.759903) (width 0.1) (layer "In2.Cu") (net 182))
  (segment (start 84.8 127.75) (end 84.822252 127.752507) (width 0.1) (layer "In2.Cu") (net 182))
  (segment (start 85.078183 128.191562) (end 85.090096 128.172602) (width 0.1) (layer "In2.Cu") (net 182))
  (segment (start 84.138225 128.244815) (end 84.133242 128.222984) (width 0.1) (layer "In2.Cu") (net 182))
  (segment (start 84.025547 127.818442) (end 84.032483 127.823971) (width 0.1) (layer "In2.Cu") (net 182))
  (segment (start 85.5 128.129214) (end 85.5 127.85) (width 0.1) (layer "In2.Cu") (net 182))
  (segment (start 85.1 125.35) (end 84.7 125.75) (width 0.1) (layer "F.Cu") (net 183))
  (segment (start 90.05 125.25) (end 90.05 124.55) (width 0.1) (layer "F.Cu") (net 183))
  (segment (start 89.4 125.65) (end 89.6 125.45) (width 0.1) (layer "F.Cu") (net 183))
  (segment (start 90.05 124.55) (end 90.45 124.15) (width 0.1) (layer "F.Cu") (net 183))
  (segment (start 89.6 125.45) (end 89.85 125.45) (width 0.1) (layer "F.Cu") (net 183))
  (segment (start 95.35 124.8) (end 95.2 124.95) (width 0.1) (layer "F.Cu") (net 183))
  (segment (start 94.8 124.15) (end 95.35 124.7) (width 0.1) (layer "F.Cu") (net 183))
  (segment (start 89.85 125.45) (end 90.05 125.25) (width 0.1) (layer "F.Cu") (net 183))
  (segment (start 95.35 124.7) (end 95.35 124.8) (width 0.1) (layer "F.Cu") (net 183))
  (segment (start 90.45 124.15) (end 94.8 124.15) (width 0.1) (layer "F.Cu") (net 183))
  (via blind (at 84.7 125.75) (size 0.5) (drill 0.2) (layers "F.Cu" "In5.Cu") (net 183))
  (via (at 89.4 125.65) (size 0.5) (drill 0.2) (layers "F.Cu" "B.Cu") (net 183))
  (segment (start 85.2 125.55) (end 85.2 125.927755) (width 0.1) (layer "In5.Cu") (net 183))
  (segment (start 85.2 125.927755) (end 85.202507 125.950007) (width 0.1) (layer "In5.Cu") (net 183))
  (segment (start 85.362348 126.005938) (end 85.378183 125.990103) (width 0.1) (layer "In5.Cu") (net 183))
  (segment (start 85.75 125.45) (end 87.25 123.95) (width 0.1) (layer "In5.Cu") (net 183))
  (segment (start 85 125.45) (end 85.1 125.45) (width 0.1) (layer "In5.Cu") (net 183))
  (segment (start 85.402507 125.527747) (end 85.409903 125.506611) (width 0.1) (layer "In5.Cu") (net 183))
  (segment (start 85.390096 125.971143) (end 85.397492 125.950007) (width 0.1) (layer "In5.Cu") (net 183))
  (segment (start 88.65 125) (end 89.1 125.45) (width 0.1) (layer "In5.Cu") (net 183))
  (segment (start 85.4 125.55) (end 85.402507 125.527747) (width 0.1) (layer "In5.Cu") (net 183))
  (segment (start 85.143388 125.459903) (end 85.162348 125.471816) (width 0.1) (layer "In5.Cu") (net 183))
  (segment (start 85.221816 125.990103) (end 85.237651 126.005938) (width 0.1) (layer "In5.Cu") (net 183))
  (segment (start 85.397492 125.950007) (end 85.4 125.927755) (width 0.1) (layer "In5.Cu") (net 183))
  (segment (start 88.25 123.95) (end 88.65 124.35) (width 0.1) (layer "In5.Cu") (net 183))
  (segment (start 85.256611 126.017851) (end 85.277747 126.025247) (width 0.1) (layer "In5.Cu") (net 183))
  (segment (start 85.237651 126.005938) (end 85.256611 126.017851) (width 0.1) (layer "In5.Cu") (net 183))
  (segment (start 85.378183 125.990103) (end 85.390096 125.971143) (width 0.1) (layer "In5.Cu") (net 183))
  (segment (start 85.5 125.45) (end 85.75 125.45) (width 0.1) (layer "In5.Cu") (net 183))
  (segment (start 85.421816 125.487651) (end 85.437651 125.471816) (width 0.1) (layer "In5.Cu") (net 183))
  (segment (start 85.343388 126.017851) (end 85.362348 126.005938) (width 0.1) (layer "In5.Cu") (net 183))
  (segment (start 89.1 125.45) (end 89.2 125.45) (width 0.1) (layer "In5.Cu") (net 183))
  (segment (start 85.322252 126.025247) (end 85.343388 126.017851) (width 0.1) (layer "In5.Cu") (net 183))
  (segment (start 85.197492 125.527747) (end 85.2 125.55) (width 0.1) (layer "In5.Cu") (net 183))
  (segment (start 85.437651 125.471816) (end 85.456611 125.459903) (width 0.1) (layer "In5.Cu") (net 183))
  (segment (start 85.4 125.927755) (end 85.4 125.55) (width 0.1) (layer "In5.Cu") (net 183))
  (segment (start 88.65 124.35) (end 88.65 125) (width 0.1) (layer "In5.Cu") (net 183))
  (segment (start 85.277747 126.025247) (end 85.3 126.027755) (width 0.1) (layer "In5.Cu") (net 183))
  (segment (start 85.190096 125.506611) (end 85.197492 125.527747) (width 0.1) (layer "In5.Cu") (net 183))
  (segment (start 85.202507 125.950007) (end 85.209903 125.971143) (width 0.1) (layer "In5.Cu") (net 183))
  (segment (start 85.3 126.027755) (end 85.322252 126.025247) (width 0.1) (layer "In5.Cu") (net 183))
  (segment (start 85.477747 125.452507) (end 85.5 125.45) (width 0.1) (layer "In5.Cu") (net 183))
  (segment (start 85.409903 125.506611) (end 85.421816 125.487651) (width 0.1) (layer "In5.Cu") (net 183))
  (segment (start 87.25 123.95) (end 88.25 123.95) (width 0.1) (layer "In5.Cu") (net 183))
  (segment (start 85.178183 125.487651) (end 85.190096 125.506611) (width 0.1) (layer "In5.Cu") (net 183))
  (segment (start 84.7 125.75) (end 85 125.45) (width 0.1) (layer "In5.Cu") (net 183))
  (segment (start 85.162348 125.471816) (end 85.178183 125.487651) (width 0.1) (layer "In5.Cu") (net 183))
  (segment (start 89.2 125.45) (end 89.4 125.65) (width 0.1) (layer "In5.Cu") (net 183))
  (segment (start 85.456611 125.459903) (end 85.477747 125.452507) (width 0.1) (layer "In5.Cu") (net 183))
  (segment (start 85.1 125.45) (end 85.122252 125.452507) (width 0.1) (layer "In5.Cu") (net 183))
  (segment (start 85.122252 125.452507) (end 85.143388 125.459903) (width 0.1) (layer "In5.Cu") (net 183))
  (segment (start 85.209903 125.971143) (end 85.221816 125.990103) (width 0.1) (layer "In5.Cu") (net 183))
  (segment (start 92.8 125.75) (end 92.4 126.15) (width 0.1) (layer "F.Cu") (net 184))
  (segment (start 84.471816 127.586151) (end 84.487651 127.601986) (width 0.1) (layer "F.Cu") (net 184))
  (segment (start 84.047492 127.027747) (end 84.05 127.05) (width 0.1) (layer "F.Cu") (net 184))
  (segment (start 84.059903 127.567191) (end 84.071816 127.586151) (width 0.1) (layer "F.Cu") (net 184))
  (segment (start 84.259903 126.482809) (end 84.271816 126.463849) (width 0.1) (layer "F.Cu") (net 184))
  (segment (start 84.572252 127.621295) (end 84.593388 127.613899) (width 0.1) (layer "F.Cu") (net 184))
  (segment (start 84.527747 127.621295) (end 84.55 127.623803) (width 0.1) (layer "F.Cu") (net 184))
  (segment (start 84.228183 127.586151) (end 84.240096 127.567191) (width 0.1) (layer "F.Cu") (net 184))
  (segment (start 84.012348 126.971816) (end 84.028183 126.987651) (width 0.1) (layer "F.Cu") (net 184))
  (segment (start 84.593388 127.613899) (end 84.612348 127.601986) (width 0.1) (layer "F.Cu") (net 184))
  (segment (start 84.671816 126.987651) (end 84.687651 126.971816) (width 0.1) (layer "F.Cu") (net 184))
  (segment (start 84.659903 127.006611) (end 84.671816 126.987651) (width 0.1) (layer "F.Cu") (net 184))
  (segment (start 84.45 127.523803) (end 84.452507 127.546055) (width 0.1) (layer "F.Cu") (net 184))
  (segment (start 84.687651 126.971816) (end 84.706611 126.959903) (width 0.1) (layer "F.Cu") (net 184))
  (segment (start 84.452507 127.546055) (end 84.459903 127.567191) (width 0.1) (layer "F.Cu") (net 184))
  (segment (start 83.972252 126.952507) (end 83.993388 126.959903) (width 0.1) (layer "F.Cu") (net 184))
  (segment (start 84.65 127.05) (end 84.652507 127.027747) (width 0.1) (layer "F.Cu") (net 184))
  (segment (start 84.45 126.526197) (end 84.45 127.523803) (width 0.1) (layer "F.Cu") (net 184))
  (segment (start 84.487651 127.601986) (end 84.506611 127.613899) (width 0.1) (layer "F.Cu") (net 184))
  (segment (start 83.85 126.95) (end 83.95 126.95) (width 0.1) (layer "F.Cu") (net 184))
  (segment (start 84.247492 127.546055) (end 84.25 127.523803) (width 0.1) (layer "F.Cu") (net 184))
  (segment (start 84.127747 127.621295) (end 84.15 127.623803) (width 0.1) (layer "F.Cu") (net 184))
  (segment (start 84.647492 127.546055) (end 84.65 127.523803) (width 0.1) (layer "F.Cu") (net 184))
  (segment (start 84.393388 126.436101) (end 84.412348 126.448014) (width 0.1) (layer "F.Cu") (net 184))
  (segment (start 84.75 126.95) (end 84.95 126.95) (width 0.1) (layer "F.Cu") (net 184))
  (segment (start 84.212348 127.601986) (end 84.228183 127.586151) (width 0.1) (layer "F.Cu") (net 184))
  (segment (start 84.652507 127.027747) (end 84.659903 127.006611) (width 0.1) (layer "F.Cu") (net 184))
  (segment (start 84.071816 127.586151) (end 84.087651 127.601986) (width 0.1) (layer "F.Cu") (net 184))
  (segment (start 84.412348 126.448014) (end 84.428183 126.463849) (width 0.1) (layer "F.Cu") (net 184))
  (segment (start 84.271816 126.463849) (end 84.287651 126.448014) (width 0.1) (layer "F.Cu") (net 184))
  (segment (start 84.193388 127.613899) (end 84.212348 127.601986) (width 0.1) (layer "F.Cu") (net 184))
  (segment (start 84.55 127.623803) (end 84.572252 127.621295) (width 0.1) (layer "F.Cu") (net 184))
  (segment (start 84.35 126.426197) (end 84.372252 126.428705) (width 0.1) (layer "F.Cu") (net 184))
  (segment (start 84.65 127.523803) (end 84.65 127.05) (width 0.1) (layer "F.Cu") (net 184))
  (segment (start 84.25 126.526197) (end 84.252507 126.503945) (width 0.1) (layer "F.Cu") (net 184))
  (segment (start 84.028183 126.987651) (end 84.040096 127.006611) (width 0.1) (layer "F.Cu") (net 184))
  (segment (start 84.252507 126.503945) (end 84.259903 126.482809) (width 0.1) (layer "F.Cu") (net 184))
  (segment (start 84.727747 126.952507) (end 84.75 126.95) (width 0.1) (layer "F.Cu") (net 184))
  (segment (start 84.306611 126.436101) (end 84.327747 126.428705) (width 0.1) (layer "F.Cu") (net 184))
  (segment (start 84.15 127.623803) (end 84.172252 127.621295) (width 0.1) (layer "F.Cu") (net 184))
  (segment (start 84.640096 127.567191) (end 84.647492 127.546055) (width 0.1) (layer "F.Cu") (net 184))
  (segment (start 84.372252 126.428705) (end 84.393388 126.436101) (width 0.1) (layer "F.Cu") (net 184))
  (segment (start 84.240096 127.567191) (end 84.247492 127.546055) (width 0.1) (layer "F.Cu") (net 184))
  (segment (start 84.447492 126.503945) (end 84.45 126.526197) (width 0.1) (layer "F.Cu") (net 184))
  (segment (start 84.106611 127.613899) (end 84.127747 127.621295) (width 0.1) (layer "F.Cu") (net 184))
  (segment (start 83.993388 126.959903) (end 84.012348 126.971816) (width 0.1) (layer "F.Cu") (net 184))
  (segment (start 83.65 126.75) (end 83.85 126.95) (width 0.1) (layer "F.Cu") (net 184))
  (segment (start 84.506611 127.613899) (end 84.527747 127.621295) (width 0.1) (layer "F.Cu") (net 184))
  (segment (start 84.05 127.523803) (end 84.052507 127.546055) (width 0.1) (layer "F.Cu") (net 184))
  (segment (start 84.087651 127.601986) (end 84.106611 127.613899) (width 0.1) (layer "F.Cu") (net 184))
  (segment (start 84.628183 127.586151) (end 84.640096 127.567191) (width 0.1) (layer "F.Cu") (net 184))
  (segment (start 84.172252 127.621295) (end 84.193388 127.613899) (width 0.1) (layer "F.Cu") (net 184))
  (segment (start 84.706611 126.959903) (end 84.727747 126.952507) (width 0.1) (layer "F.Cu") (net 184))
  (segment (start 84.287651 126.448014) (end 84.306611 126.436101) (width 0.1) (layer "F.Cu") (net 184))
  (segment (start 84.428183 126.463849) (end 84.440096 126.482809) (width 0.1) (layer "F.Cu") (net 184))
  (segment (start 84.05 127.05) (end 84.05 127.523803) (width 0.1) (layer "F.Cu") (net 184))
  (segment (start 83.95 126.95) (end 83.972252 126.952507) (width 0.1) (layer "F.Cu") (net 184))
  (segment (start 84.052507 127.546055) (end 84.059903 127.567191) (width 0.1) (layer "F.Cu") (net 184))
  (segment (start 84.459903 127.567191) (end 84.471816 127.586151) (width 0.1) (layer "F.Cu") (net 184))
  (segment (start 84.440096 126.482809) (end 84.447492 126.503945) (width 0.1) (layer "F.Cu") (net 184))
  (segment (start 84.040096 127.006611) (end 84.047492 127.027747) (width 0.1) (layer "F.Cu") (net 184))
  (segment (start 84.25 127.523803) (end 84.25 126.526197) (width 0.1) (layer "F.Cu") (net 184))
  (segment (start 84.612348 127.601986) (end 84.628183 127.586151) (width 0.1) (layer "F.Cu") (net 184))
  (segment (start 84.327747 126.428705) (end 84.35 126.426197) (width 0.1) (layer "F.Cu") (net 184))
  (via blind (at 92.4 126.15) (size 0.5) (drill 0.2) (layers "F.Cu" "In2.Cu") (net 184))
  (via blind (at 83.65 126.75) (size 0.5) (drill 0.2) (layers "F.Cu" "In2.Cu") (net 184))
  (segment (start 83.838953 126.140327) (end 83.821445 126.154289) (width 0.1) (layer "In2.Cu") (net 184))
  (segment (start 84.137317 126.248677) (end 84.115485 126.25366) (width 0.1) (layer "In2.Cu") (net 184))
  (segment (start 84.104291 126.719974) (end 84.086783 126.733937) (width 0.1) (layer "In2.Cu") (net 184))
  (segment (start 83.810252 126.620604) (end 83.788421 126.625586) (width 0.1) (layer "In2.Cu") (net 184))
  (segment (start 88.55 126.35) (end 88.35 126.15) (width 0.1) (layer "In2.Cu") (net 184))
  (segment (start 83.67432 126.72568) (end 83.65 126.75) (width 0.1) (layer "In2.Cu") (net 184))
  (segment (start 84.071261 126.248677) (end 84.051086 126.238961) (width 0.1) (layer "In2.Cu") (net 184))
  (segment (start 83.903353 126.125628) (end 83.88096 126.125628) (width 0.1) (layer "In2.Cu") (net 184))
  (segment (start 83.88096 126.125628) (end 83.859128 126.130611) (width 0.1) (layer "In2.Cu") (net 184))
  (segment (start 83.797767 126.191971) (end 83.792784 126.213803) (width 0.1) (layer "In2.Cu") (net 184))
  (segment (start 91.6 126.35) (end 88.55 126.35) (width 0.1) (layer "In2.Cu") (net 184))
  (segment (start 83.980377 126.733937) (end 83.962869 126.719975) (width 0.1) (layer "In2.Cu") (net 184))
  (segment (start 83.945359 126.140327) (end 83.925184 126.130611) (width 0.1) (layer "In2.Cu") (net 184))
  (segment (start 84.115485 126.25366) (end 84.093092 126.25366) (width 0.1) (layer "In2.Cu") (net 184))
  (segment (start 84.051086 126.238961) (end 84.033578 126.225) (width 0.1) (layer "In2.Cu") (net 184))
  (segment (start 84.086783 126.733937) (end 84.066609 126.743652) (width 0.1) (layer "In2.Cu") (net 184))
  (segment (start 84.066609 126.743652) (end 84.044776 126.748636) (width 0.1) (layer "In2.Cu") (net 184))
  (segment (start 83.892159 126.649265) (end 83.874651 126.635303) (width 0.1) (layer "In2.Cu") (net 184))
  (segment (start 83.859128 126.130611) (end 83.838953 126.140327) (width 0.1) (layer "In2.Cu") (net 184))
  (segment (start 83.832646 126.620603) (end 83.810252 126.620604) (width 0.1) (layer "In2.Cu") (net 184))
  (segment (start 84.13295 126.638068) (end 84.132951 126.66046) (width 0.1) (layer "In2.Cu") (net 184))
  (segment (start 88.35 126.15) (end 84.25 126.15) (width 0.1) (layer "In2.Cu") (net 184))
  (segment (start 92.4 126.15) (end 91.8 126.15) (width 0.1) (layer "In2.Cu") (net 184))
  (segment (start 83.962869 126.719975) (end 83.892159 126.649265) (width 0.1) (layer "In2.Cu") (net 184))
  (segment (start 84.157492 126.238961) (end 84.137317 126.248677) (width 0.1) (layer "In2.Cu") (net 184))
  (segment (start 84.175 126.225) (end 84.157492 126.238961) (width 0.1) (layer "In2.Cu") (net 184))
  (segment (start 83.854477 126.625586) (end 83.832646 126.620603) (width 0.1) (layer "In2.Cu") (net 184))
  (segment (start 84.25 126.15) (end 84.175 126.225) (width 0.1) (layer "In2.Cu") (net 184))
  (segment (start 83.821445 126.29571) (end 84.10429 126.578554) (width 0.1) (layer "In2.Cu") (net 184))
  (segment (start 83.807483 126.171796) (end 83.797767 126.191971) (width 0.1) (layer "In2.Cu") (net 184))
  (segment (start 84.000553 126.743652) (end 83.980377 126.733937) (width 0.1) (layer "In2.Cu") (net 184))
  (segment (start 83.874651 126.635303) (end 83.854477 126.625586) (width 0.1) (layer "In2.Cu") (net 184))
  (segment (start 84.033578 126.225) (end 83.962867 126.154289) (width 0.1) (layer "In2.Cu") (net 184))
  (segment (start 84.118253 126.59606) (end 84.127969 126.616236) (width 0.1) (layer "In2.Cu") (net 184))
  (segment (start 91.8 126.15) (end 91.6 126.35) (width 0.1) (layer "In2.Cu") (net 184))
  (segment (start 84.132951 126.66046) (end 84.127968 126.682292) (width 0.1) (layer "In2.Cu") (net 184))
  (segment (start 84.044776 126.748636) (end 84.022384 126.748635) (width 0.1) (layer "In2.Cu") (net 184))
  (segment (start 83.768245 126.635303) (end 83.750737 126.649265) (width 0.1) (layer "In2.Cu") (net 184))
  (segment (start 84.118252 126.702468) (end 84.104291 126.719974) (width 0.1) (layer "In2.Cu") (net 184))
  (segment (start 84.093092 126.25366) (end 84.071261 126.248677) (width 0.1) (layer "In2.Cu") (net 184))
  (segment (start 83.797767 126.258027) (end 83.807483 126.278202) (width 0.1) (layer "In2.Cu") (net 184))
  (segment (start 83.962867 126.154289) (end 83.945359 126.140327) (width 0.1) (layer "In2.Cu") (net 184))
  (segment (start 83.925184 126.130611) (end 83.903353 126.125628) (width 0.1) (layer "In2.Cu") (net 184))
  (segment (start 84.127968 126.682292) (end 84.118252 126.702468) (width 0.1) (layer "In2.Cu") (net 184))
  (segment (start 83.750737 126.649265) (end 83.67432 126.72568) (width 0.1) (layer "In2.Cu") (net 184))
  (segment (start 84.127969 126.616236) (end 84.13295 126.638068) (width 0.1) (layer "In2.Cu") (net 184))
  (segment (start 83.788421 126.625586) (end 83.768245 126.635303) (width 0.1) (layer "In2.Cu") (net 184))
  (segment (start 83.792784 126.236196) (end 83.797767 126.258027) (width 0.1) (layer "In2.Cu") (net 184))
  (segment (start 83.792784 126.213803) (end 83.792784 126.236196) (width 0.1) (layer "In2.Cu") (net 184))
  (segment (start 84.022384 126.748635) (end 84.000553 126.743652) (width 0.1) (layer "In2.Cu") (net 184))
  (segment (start 83.807483 126.278202) (end 83.821445 126.29571) (width 0.1) (layer "In2.Cu") (net 184))
  (segment (start 84.10429 126.578554) (end 84.118253 126.59606) (width 0.1) (layer "In2.Cu") (net 184))
  (segment (start 83.821445 126.154289) (end 83.807483 126.171796) (width 0.1) (layer "In2.Cu") (net 184))
  (segment (start 94.4 124.95) (end 94 125.35) (width 0.1) (layer "F.Cu") (net 185))
  (segment (start 89.35 129.8) (end 83.05 129.8) (width 0.1) (layer "F.Cu") (net 185))
  (segment (start 82.752507 129.619174) (end 82.75 129.641427) (width 0.1) (layer "F.Cu") (net 185))
  (segment (start 82.771816 129.579078) (end 82.759903 129.598038) (width 0.1) (layer "F.Cu") (net 185))
  (segment (start 83.006611 129.790096) (end 82.987651 129.778183) (width 0.1) (layer "F.Cu") (net 185))
  (segment (start 82.872252 129.543934) (end 82.85 129.541427) (width 0.1) (layer "F.Cu") (net 185))
  (segment (start 82.95 129.7) (end 82.95 129.641427) (width 0.1) (layer "F.Cu") (net 185))
  (segment (start 82.940096 129.598038) (end 82.928183 129.579078) (width 0.1) (layer "F.Cu") (net 185))
  (segment (start 82.928183 129.579078) (end 82.912348 129.563243) (width 0.1) (layer "F.Cu") (net 185))
  (segment (start 82.893388 129.55133) (end 82.872252 129.543934) (width 0.1) (layer "F.Cu") (net 185))
  (segment (start 82.728183 129.762348) (end 82.712348 129.778183) (width 0.1) (layer "F.Cu") (net 185))
  (segment (start 82.947492 129.619174) (end 82.940096 129.598038) (width 0.1) (layer "F.Cu") (net 185))
  (segment (start 82.85 129.541427) (end 82.827747 129.543934) (width 0.1) (layer "F.Cu") (net 185))
  (segment (start 82.75 129.641427) (end 82.75 129.7) (width 0.1) (layer "F.Cu") (net 185))
  (segment (start 82.787651 129.563243) (end 82.771816 129.579078) (width 0.1) (layer "F.Cu") (net 185))
  (segment (start 82.693388 129.790096) (end 82.672252 129.797492) (width 0.1) (layer "F.Cu") (net 185))
  (segment (start 82.806611 129.55133) (end 82.787651 129.563243) (width 0.1) (layer "F.Cu") (net 185))
  (segment (start 82.740096 129.743388) (end 82.728183 129.762348) (width 0.1) (layer "F.Cu") (net 185))
  (segment (start 83.027747 129.797492) (end 83.006611 129.790096) (width 0.1) (layer "F.Cu") (net 185))
  (segment (start 92.4 127.8) (end 91.95 128.25) (width 0.1) (layer "F.Cu") (net 185))
  (segment (start 82.827747 129.543934) (end 82.806611 129.55133) (width 0.1) (layer "F.Cu") (net 185))
  (segment (start 82.95 129.641427) (end 82.947492 129.619174) (width 0.1) (layer "F.Cu") (net 185))
  (segment (start 82.65 129.8) (end 82.35 129.8) (width 0.1) (layer "F.Cu") (net 185))
  (segment (start 82.959903 129.743388) (end 82.952507 129.722252) (width 0.1) (layer "F.Cu") (net 185))
  (segment (start 82.912348 129.563243) (end 82.893388 129.55133) (width 0.1) (layer "F.Cu") (net 185))
  (segment (start 91.95 128.25) (end 90.9 128.25) (width 0.1) (layer "F.Cu") (net 185))
  (segment (start 82.971816 129.762348) (end 82.959903 129.743388) (width 0.1) (layer "F.Cu") (net 185))
  (segment (start 82.759903 129.598038) (end 82.752507 129.619174) (width 0.1) (layer "F.Cu") (net 185))
  (segment (start 82.987651 129.778183) (end 82.971816 129.762348) (width 0.1) (layer "F.Cu") (net 185))
  (segment (start 82.672252 129.797492) (end 82.65 129.8) (width 0.1) (layer "F.Cu") (net 185))
  (segment (start 83.05 129.8) (end 83.027747 129.797492) (width 0.1) (layer "F.Cu") (net 185))
  (segment (start 82.712348 129.778183) (end 82.693388 129.790096) (width 0.1) (layer "F.Cu") (net 185))
  (segment (start 82.952507 129.722252) (end 82.95 129.7) (width 0.1) (layer "F.Cu") (net 185))
  (segment (start 82.75 129.7) (end 82.747492 129.722252) (width 0.1) (layer "F.Cu") (net 185))
  (segment (start 90.9 128.25) (end 89.35 129.8) (width 0.1) (layer "F.Cu") (net 185))
  (segment (start 82.747492 129.722252) (end 82.740096 129.743388) (width 0.1) (layer "F.Cu") (net 185))
  (segment (start 82.35 129.8) (end 81.8898 129.3398) (width 0.1) (layer "F.Cu") (net 185))
  (via (at 94 125.35) (size 0.5) (drill 0.2) (layers "F.Cu" "B.Cu") (net 185))
  (via (at 92.4 127.8) (size 0.5) (drill 0.2) (layers "F.Cu" "B.Cu") (net 185))
  (segment (start 94 126.2) (end 92.4 127.8) (width 0.1) (layer "In5.Cu") (net 185))
  (segment (start 94 125.35) (end 94 126.2) (width 0.1) (layer "In5.Cu") (net 185))
  (segment (start 93.6 126.55) (end 94 126.95) (width 0.1) (layer "F.Cu") (net 186))
  (segment (start 81.1 127.75) (end 80.7 128.15) (width 0.1) (layer "F.Cu") (net 186))
  (via blind (at 94 126.95) (size 0.5) (drill 0.2) (layers "F.Cu" "In2.Cu") (net 186))
  (via (at 80.7 128.15) (size 0.5) (drill 0.2) (layers "F.Cu" "B.Cu") (net 186))
  (segment (start 81.440096 127.384314) (end 81.447492 127.40545) (width 0.1) (layer "In2.Cu") (net 186))
  (segment (start 83.9 127.55) (end 89.25 127.55) (width 0.1) (layer "In2.Cu") (net 186))
  (segment (start 80.7 128.15) (end 81.1 127.75) (width 0.1) (layer "In2.Cu") (net 186))
  (segment (start 81.228183 127.712349) (end 81.240096 127.693389) (width 0.1) (layer "In2.Cu") (net 186))
  (segment (start 81.487651 127.728184) (end 81.506611 127.740097) (width 0.1) (layer "In2.Cu") (net 186))
  (segment (start 81.452507 127.672253) (end 81.459903 127.693389) (width 0.1) (layer "In2.Cu") (net 186))
  (segment (start 81.459903 127.693389) (end 81.471816 127.712349) (width 0.1) (layer "In2.Cu") (net 186))
  (segment (start 81.471816 127.712349) (end 81.487651 127.728184) (width 0.1) (layer "In2.Cu") (net 186))
  (segment (start 81.172252 127.747493) (end 81.193388 127.740097) (width 0.1) (layer "In2.Cu") (net 186))
  (segment (start 81.212348 127.728184) (end 81.228183 127.712349) (width 0.1) (layer "In2.Cu") (net 186))
  (segment (start 81.240096 127.693389) (end 81.247492 127.672253) (width 0.1) (layer "In2.Cu") (net 186))
  (segment (start 81.327747 127.33021) (end 81.35 127.327702) (width 0.1) (layer "In2.Cu") (net 186))
  (segment (start 81.55 127.75) (end 83.7 127.75) (width 0.1) (layer "In2.Cu") (net 186))
  (segment (start 81.45 127.427702) (end 81.45 127.65) (width 0.1) (layer "In2.Cu") (net 186))
  (segment (start 81.35 127.327702) (end 81.372252 127.33021) (width 0.1) (layer "In2.Cu") (net 186))
  (segment (start 81.271816 127.365354) (end 81.287651 127.349519) (width 0.1) (layer "In2.Cu") (net 186))
  (segment (start 81.506611 127.740097) (end 81.527747 127.747493) (width 0.1) (layer "In2.Cu") (net 186))
  (segment (start 81.247492 127.672253) (end 81.25 127.65) (width 0.1) (layer "In2.Cu") (net 186))
  (segment (start 81.393388 127.337606) (end 81.412348 127.349519) (width 0.1) (layer "In2.Cu") (net 186))
  (segment (start 81.25 127.427702) (end 81.252507 127.40545) (width 0.1) (layer "In2.Cu") (net 186))
  (segment (start 81.447492 127.40545) (end 81.45 127.427702) (width 0.1) (layer "In2.Cu") (net 186))
  (segment (start 83.7 127.75) (end 83.9 127.55) (width 0.1) (layer "In2.Cu") (net 186))
  (segment (start 81.287651 127.349519) (end 81.306611 127.337606) (width 0.1) (layer "In2.Cu") (net 186))
  (segment (start 81.428183 127.365354) (end 81.440096 127.384314) (width 0.1) (layer "In2.Cu") (net 186))
  (segment (start 81.25 127.65) (end 81.25 127.427702) (width 0.1) (layer "In2.Cu") (net 186))
  (segment (start 81.372252 127.33021) (end 81.393388 127.337606) (width 0.1) (layer "In2.Cu") (net 186))
  (segment (start 81.252507 127.40545) (end 81.259903 127.384314) (width 0.1) (layer "In2.Cu") (net 186))
  (segment (start 81.527747 127.747493) (end 81.55 127.75) (width 0.1) (layer "In2.Cu") (net 186))
  (segment (start 81.259903 127.384314) (end 81.271816 127.365354) (width 0.1) (layer "In2.Cu") (net 186))
  (segment (start 89.25 127.55) (end 89.45 127.35) (width 0.1) (layer "In2.Cu") (net 186))
  (segment (start 89.45 127.35) (end 93.6 127.35) (width 0.1) (layer "In2.Cu") (net 186))
  (segment (start 81.1 127.75) (end 81.15 127.75) (width 0.1) (layer "In2.Cu") (net 186))
  (segment (start 81.15 127.75) (end 81.172252 127.747493) (width 0.1) (layer "In2.Cu") (net 186))
  (segment (start 93.6 127.35) (end 94 126.95) (width 0.1) (layer "In2.Cu") (net 186))
  (segment (start 81.412348 127.349519) (end 81.428183 127.365354) (width 0.1) (layer "In2.Cu") (net 186))
  (segment (start 81.45 127.65) (end 81.452507 127.672253) (width 0.1) (layer "In2.Cu") (net 186))
  (segment (start 81.306611 127.337606) (end 81.327747 127.33021) (width 0.1) (layer "In2.Cu") (net 186))
  (segment (start 81.193388 127.740097) (end 81.212348 127.728184) (width 0.1) (layer "In2.Cu") (net 186))
  (segment (start 85.9 127.75) (end 86.3 128.15) (width 0.1) (layer "F.Cu") (net 187))
  (segment (start 92 124.95) (end 91.2 124.95) (width 0.1) (layer "F.Cu") (net 187))
  (segment (start 88.8 127.35) (end 88.8 128.15) (width 0.1) (layer "F.Cu") (net 187))
  (segment (start 91.2 124.95) (end 88.8 127.35) (width 0.1) (layer "F.Cu") (net 187))
  (via blind (at 86.3 128.15) (size 0.5) (drill 0.2) (layers "F.Cu" "In5.Cu") (net 187))
  (via (at 88.8 128.15) (size 0.5) (drill 0.2) (layers "F.Cu" "B.Cu") (net 187))
  (segment (start 86.662087 129.274484) (end 86.680764 129.262748) (width 0.1) (layer "In5.Cu") (net 187))
  (segment (start 87.378134 129.849822) (end 87.387378 129.876242) (width 0.1) (layer "In5.Cu") (net 187))
  (segment (start 88.195764 129.462378) (end 88.222184 129.453134) (width 0.1) (layer "In5.Cu") (net 187))
  (segment (start 87.125 129.822007) (end 87.125 129.401496) (width 0.1) (layer "In5.Cu") (net 187))
  (segment (start 86.472184 129.943872) (end 86.5 129.947007) (width 0.1) (layer "In5.Cu") (net 187))
  (segment (start 87.945764 129.934628) (end 87.972184 129.943872) (width 0.1) (layer "In5.Cu") (net 187))
  (segment (start 86.837912 129.274484) (end 86.853509 129.290081) (width 0.1) (layer "In5.Cu") (net 187))
  (segment (start 87.695764 128.965372) (end 87.722184 128.956128) (width 0.1) (layer "In5.Cu") (net 187))
  (segment (start 86.87253 129.329578) (end 86.875 129.351496) (width 0.1) (layer "In5.Cu") (net 187))
  (segment (start 87.625 129.822007) (end 87.625 129.077993) (width 0.1) (layer "In5.Cu") (net 187))
  (segment (start 87.777815 128.956128) (end 87.804235 128.965372) (width 0.1) (layer "In5.Cu") (net 187))
  (segment (start 87.597728 129.899943) (end 87.612621 129.876242) (width 0.1) (layer "In5.Cu") (net 187))
  (segment (start 87.16271 129.35421) (end 87.173503 129.352993) (width 0.1) (layer "In5.Cu") (net 187))
  (segment (start 86.378134 129.849822) (end 86.387378 129.876242) (width 0.1) (layer "In5.Cu") (net 187))
  (segment (start 86.875 129.351496) (end 86.875 129.822007) (width 0.1) (layer "In5.Cu") (net 187))
  (segment (start 88.125 129.575) (end 88.128134 129.547184) (width 0.1) (layer "In5.Cu") (net 187))
  (segment (start 87.326497 129.352993) (end 87.337289 129.35421) (width 0.1) (layer "In5.Cu") (net 187))
  (segment (start 87.827936 128.980265) (end 87.847728 129.000057) (width 0.1) (layer "In5.Cu") (net 187))
  (segment (start 87.862621 129.023758) (end 87.871865 129.050178) (width 0.1) (layer "In5.Cu") (net 187))
  (segment (start 87.373783 129.390704) (end 87.375 129.401496) (width 0.1) (layer "In5.Cu") (net 187))
  (segment (start 86.362621 129.520764) (end 86.371865 129.547184) (width 0.1) (layer "In5.Cu") (net 187))
  (segment (start 86.634754 129.308758) (end 86.64649 129.290081) (width 0.1) (layer "In5.Cu") (net 187))
  (segment (start 87.135581 129.371255) (end 87.143261 129.363575) (width 0.1) (layer "In5.Cu") (net 187))
  (segment (start 89.1 129.2) (end 89.1 128.45) (width 0.1) (layer "In5.Cu") (net 187))
  (segment (start 87.370196 129.380452) (end 87.373783 129.390704) (width 0.1) (layer "In5.Cu") (net 187))
  (segment (start 87.125 129.401496) (end 87.126216 129.390704) (width 0.1) (layer "In5.Cu") (net 187))
  (segment (start 86.527815 129.943872) (end 86.554235 129.934628) (width 0.1) (layer "In5.Cu") (net 187))
  (segment (start 87.847728 129.000057) (end 87.862621 129.023758) (width 0.1) (layer "In5.Cu") (net 187))
  (segment (start 86.347728 129.497063) (end 86.362621 129.520764) (width 0.1) (layer "In5.Cu") (net 187))
  (segment (start 87.347541 129.357797) (end 87.356738 129.363575) (width 0.1) (layer "In5.Cu") (net 187))
  (segment (start 87.337289 129.35421) (end 87.347541 129.357797) (width 0.1) (layer "In5.Cu") (net 187))
  (segment (start 86.597728 129.899943) (end 86.612621 129.876242) (width 0.1) (layer "In5.Cu") (net 187))
  (segment (start 86.554235 129.934628) (end 86.577936 129.919735) (width 0.1) (layer "In5.Cu") (net 187))
  (segment (start 87.672063 128.980265) (end 87.695764 128.965372) (width 0.1) (layer "In5.Cu") (net 187))
  (segment (start 86.64649 129.290081) (end 86.662087 129.274484) (width 0.1) (layer "In5.Cu") (net 187))
  (segment (start 87.621865 129.849822) (end 87.625 129.822007) (width 0.1) (layer "In5.Cu") (net 187))
  (segment (start 87.422063 129.919735) (end 87.445764 129.934628) (width 0.1) (layer "In5.Cu") (net 187))
  (segment (start 86.3 128.15) (end 85.9 128.55) (width 0.1) (layer "In5.Cu") (net 187))
  (segment (start 88.222184 129.453134) (end 88.25 129.45) (width 0.1) (layer "In5.Cu") (net 187))
  (segment (start 87.628134 129.050178) (end 87.637378 129.023758) (width 0.1) (layer "In5.Cu") (net 187))
  (segment (start 86.5 129.947007) (end 86.527815 129.943872) (width 0.1) (layer "In5.Cu") (net 187))
  (segment (start 86.387378 129.876242) (end 86.402271 129.899943) (width 0.1) (layer "In5.Cu") (net 187))
  (segment (start 86.627469 129.329578) (end 86.634754 129.308758) (width 0.1) (layer "In5.Cu") (net 187))
  (segment (start 86.612621 129.876242) (end 86.621865 129.849822) (width 0.1) (layer "In5.Cu") (net 187))
  (segment (start 88.054235 129.934628) (end 88.077936 129.919735) (width 0.1) (layer "In5.Cu") (net 187))
  (segment (start 88.152271 129.497063) (end 88.172063 129.477271) (width 0.1) (layer "In5.Cu") (net 187))
  (segment (start 87.121865 129.849822) (end 87.125 129.822007) (width 0.1) (layer "In5.Cu") (net 187))
  (segment (start 87.625 129.077993) (end 87.628134 129.050178) (width 0.1) (layer "In5.Cu") (net 187))
  (segment (start 86.680764 129.262748) (end 86.701584 129.255463) (width 0.1) (layer "In5.Cu") (net 187))
  (segment (start 87.097728 129.899943) (end 87.112621 129.876242) (width 0.1) (layer "In5.Cu") (net 187))
  (segment (start 86.701584 129.255463) (end 86.723503 129.252993) (width 0.1) (layer "In5.Cu") (net 187))
  (segment (start 88.125 129.822007) (end 88.125 129.575) (width 0.1) (layer "In5.Cu") (net 187))
  (segment (start 87.152458 129.357797) (end 87.16271 129.35421) (width 0.1) (layer "In5.Cu") (net 187))
  (segment (start 88.112621 129.876242) (end 88.121865 129.849822) (width 0.1) (layer "In5.Cu") (net 187))
  (segment (start 87.364418 129.371255) (end 87.370196 129.380452) (width 0.1) (layer "In5.Cu") (net 187))
  (segment (start 86.375 129.575) (end 86.375 129.822007) (width 0.1) (layer "In5.Cu") (net 187))
  (segment (start 86.1 129.45) (end 86.25 129.45) (width 0.1) (layer "In5.Cu") (net 187))
  (segment (start 86.402271 129.899943) (end 86.422063 129.919735) (width 0.1) (layer "In5.Cu") (net 187))
  (segment (start 86.853509 129.290081) (end 86.865245 129.308758) (width 0.1) (layer "In5.Cu") (net 187))
  (segment (start 87.375 129.401496) (end 87.375 129.822007) (width 0.1) (layer "In5.Cu") (net 187))
  (segment (start 88.85 129.45) (end 89.1 129.2) (width 0.1) (layer "In5.Cu") (net 187))
  (segment (start 86.887378 129.876242) (end 86.902271 129.899943) (width 0.1) (layer "In5.Cu") (net 187))
  (segment (start 86.878134 129.849822) (end 86.887378 129.876242) (width 0.1) (layer "In5.Cu") (net 187))
  (segment (start 87.375 129.822007) (end 87.378134 129.849822) (width 0.1) (layer "In5.Cu") (net 187))
  (segment (start 86.375 129.822007) (end 86.378134 129.849822) (width 0.1) (layer "In5.Cu") (net 187))
  (segment (start 86.304235 129.462378) (end 86.327936 129.477271) (width 0.1) (layer "In5.Cu") (net 187))
  (segment (start 86.327936 129.477271) (end 86.347728 129.497063) (width 0.1) (layer "In5.Cu") (net 187))
  (segment (start 87.875 129.822007) (end 87.878134 129.849822) (width 0.1) (layer "In5.Cu") (net 187))
  (segment (start 86.371865 129.547184) (end 86.375 129.575) (width 0.1) (layer "In5.Cu") (net 187))
  (segment (start 87.554235 129.934628) (end 87.577936 129.919735) (width 0.1) (layer "In5.Cu") (net 187))
  (segment (start 88.027815 129.943872) (end 88.054235 129.934628) (width 0.1) (layer "In5.Cu") (net 187))
  (segment (start 87.972184 129.943872) (end 88 129.947007) (width 0.1) (layer "In5.Cu") (net 187))
  (segment (start 87.922063 129.919735) (end 87.945764 129.934628) (width 0.1) (layer "In5.Cu") (net 187))
  (segment (start 86.25 129.45) (end 86.277815 129.453134) (width 0.1) (layer "In5.Cu") (net 187))
  (segment (start 88 129.947007) (end 88.027815 129.943872) (width 0.1) (layer "In5.Cu") (net 187))
  (segment (start 87.652271 129.000057) (end 87.672063 128.980265) (width 0.1) (layer "In5.Cu") (net 187))
  (segment (start 86.577936 129.919735) (end 86.597728 129.899943) (width 0.1) (layer "In5.Cu") (net 187))
  (segment (start 87.387378 129.876242) (end 87.402271 129.899943) (width 0.1) (layer "In5.Cu") (net 187))
  (segment (start 87.143261 129.363575) (end 87.152458 129.357797) (width 0.1) (layer "In5.Cu") (net 187))
  (segment (start 86.945764 129.934628) (end 86.972184 129.943872) (width 0.1) (layer "In5.Cu") (net 187))
  (segment (start 87 129.947007) (end 87.027815 129.943872) (width 0.1) (layer "In5.Cu") (net 187))
  (segment (start 87.637378 129.023758) (end 87.652271 129.000057) (width 0.1) (layer "In5.Cu") (net 187))
  (segment (start 87.875 129.077993) (end 87.875 129.822007) (width 0.1) (layer "In5.Cu") (net 187))
  (segment (start 85.9 129.25) (end 86.1 129.45) (width 0.1) (layer "In5.Cu") (net 187))
  (segment (start 86.621865 129.849822) (end 86.625 129.822007) (width 0.1) (layer "In5.Cu") (net 187))
  (segment (start 87.75 128.952993) (end 87.777815 128.956128) (width 0.1) (layer "In5.Cu") (net 187))
  (segment (start 87.112621 129.876242) (end 87.121865 129.849822) (width 0.1) (layer "In5.Cu") (net 187))
  (segment (start 86.865245 129.308758) (end 86.87253 129.329578) (width 0.1) (layer "In5.Cu") (net 187))
  (segment (start 87.027815 129.943872) (end 87.054235 129.934628) (width 0.1) (layer "In5.Cu") (net 187))
  (segment (start 86.625 129.822007) (end 86.625 129.351496) (width 0.1) (layer "In5.Cu") (net 187))
  (segment (start 87.402271 129.899943) (end 87.422063 129.919735) (width 0.1) (layer "In5.Cu") (net 187))
  (segment (start 87.129803 129.380452) (end 87.135581 129.371255) (width 0.1) (layer "In5.Cu") (net 187))
  (segment (start 87.054235 129.934628) (end 87.077936 129.919735) (width 0.1) (layer "In5.Cu") (net 187))
  (segment (start 87.527815 129.943872) (end 87.554235 129.934628) (width 0.1) (layer "In5.Cu") (net 187))
  (segment (start 86.625 129.351496) (end 86.627469 129.329578) (width 0.1) (layer "In5.Cu") (net 187))
  (segment (start 86.902271 129.899943) (end 86.922063 129.919735) (width 0.1) (layer "In5.Cu") (net 187))
  (segment (start 88.172063 129.477271) (end 88.195764 129.462378) (width 0.1) (layer "In5.Cu") (net 187))
  (segment (start 86.922063 129.919735) (end 86.945764 129.934628) (width 0.1) (layer "In5.Cu") (net 187))
  (segment (start 88.128134 129.547184) (end 88.137378 129.520764) (width 0.1) (layer "In5.Cu") (net 187))
  (segment (start 86.776497 129.252993) (end 86.798415 129.255463) (width 0.1) (layer "In5.Cu") (net 187))
  (segment (start 86.445764 129.934628) (end 86.472184 129.943872) (width 0.1) (layer "In5.Cu") (net 187))
  (segment (start 87.126216 129.390704) (end 87.129803 129.380452) (width 0.1) (layer "In5.Cu") (net 187))
  (segment (start 86.723503 129.252993) (end 86.776497 129.252993) (width 0.1) (layer "In5.Cu") (net 187))
  (segment (start 87.887378 129.876242) (end 87.902271 129.899943) (width 0.1) (layer "In5.Cu") (net 187))
  (segment (start 89.1 128.45) (end 88.8 128.15) (width 0.1) (layer "In5.Cu") (net 187))
  (segment (start 86.972184 129.943872) (end 87 129.947007) (width 0.1) (layer "In5.Cu") (net 187))
  (segment (start 86.798415 129.255463) (end 86.819235 129.262748) (width 0.1) (layer "In5.Cu") (net 187))
  (segment (start 87.356738 129.363575) (end 87.364418 129.371255) (width 0.1) (layer "In5.Cu") (net 187))
  (segment (start 88.097728 129.899943) (end 88.112621 129.876242) (width 0.1) (layer "In5.Cu") (net 187))
  (segment (start 88.25 129.45) (end 88.85 129.45) (width 0.1) (layer "In5.Cu") (net 187))
  (segment (start 86.422063 129.919735) (end 86.445764 129.934628) (width 0.1) (layer "In5.Cu") (net 187))
  (segment (start 87.472184 129.943872) (end 87.5 129.947007) (width 0.1) (layer "In5.Cu") (net 187))
  (segment (start 86.277815 129.453134) (end 86.304235 129.462378) (width 0.1) (layer "In5.Cu") (net 187))
  (segment (start 87.445764 129.934628) (end 87.472184 129.943872) (width 0.1) (layer "In5.Cu") (net 187))
  (segment (start 87.577936 129.919735) (end 87.597728 129.899943) (width 0.1) (layer "In5.Cu") (net 187))
  (segment (start 87.722184 128.956128) (end 87.75 128.952993) (width 0.1) (layer "In5.Cu") (net 187))
  (segment (start 86.819235 129.262748) (end 86.837912 129.274484) (width 0.1) (layer "In5.Cu") (net 187))
  (segment (start 88.077936 129.919735) (end 88.097728 129.899943) (width 0.1) (layer "In5.Cu") (net 187))
  (segment (start 87.902271 129.899943) (end 87.922063 129.919735) (width 0.1) (layer "In5.Cu") (net 187))
  (segment (start 87.878134 129.849822) (end 87.887378 129.876242) (width 0.1) (layer "In5.Cu") (net 187))
  (segment (start 87.5 129.947007) (end 87.527815 129.943872) (width 0.1) (layer "In5.Cu") (net 187))
  (segment (start 87.804235 128.965372) (end 87.827936 128.980265) (width 0.1) (layer "In5.Cu") (net 187))
  (segment (start 85.9 128.55) (end 85.9 129.25) (width 0.1) (layer "In5.Cu") (net 187))
  (segment (start 87.612621 129.876242) (end 87.621865 129.849822) (width 0.1) (layer "In5.Cu") (net 187))
  (segment (start 88.121865 129.849822) (end 88.125 129.822007) (width 0.1) (layer "In5.Cu") (net 187))
  (segment (start 88.137378 129.520764) (end 88.152271 129.497063) (width 0.1) (layer "In5.Cu") (net 187))
  (segment (start 87.871865 129.050178) (end 87.875 129.077993) (width 0.1) (layer "In5.Cu") (net 187))
  (segment (start 86.875 129.822007) (end 86.878134 129.849822) (width 0.1) (layer "In5.Cu") (net 187))
  (segment (start 87.173503 129.352993) (end 87.326497 129.352993) (width 0.1) (layer "In5.Cu") (net 187))
  (segment (start 87.077936 129.919735) (end 87.097728 129.899943) (width 0.1) (layer "In5.Cu") (net 187))
  (segment (start 96.8 123.35) (end 96.4 122.95) (width 0.15) (layer "F.Cu") (net 188))
  (segment (start 81.9 123.75) (end 82.3 123.75) (width 0.1) (layer "F.Cu") (net 188))
  (segment (start 82.5 123.95) (end 82.3 123.75) (width 0.1) (layer "F.Cu") (net 188))
  (via blind (at 96.4 122.95) (size 0.5) (drill 0.2) (layers "F.Cu" "In2.Cu") (net 188))
  (via blind (at 82.5 123.95) (size 0.5) (drill 0.2) (layers "F.Cu" "In2.Cu") (net 188))
  (segment (start 94.35 123.6) (end 94.5 123.45) (width 0.1) (layer "In2.Cu") (net 188))
  (segment (start 95.9 123.45) (end 96.4 122.95) (width 0.1) (layer "In2.Cu") (net 188))
  (segment (start 94.5 123.45) (end 95.9 123.45) (width 0.1) (layer "In2.Cu") (net 188))
  (segment (start 91.05 123.55) (end 91.1 123.6) (width 0.1) (layer "In2.Cu") (net 188))
  (segment (start 82.89999 123.55) (end 82.89999 123.55001) (width 0.1) (layer "In2.Cu") (net 188))
  (segment (start 91.1 123.6) (end 94.35 123.6) (width 0.1) (layer "In2.Cu") (net 188))
  (segment (start 82.89999 123.55001) (end 82.5 123.95) (width 0.1) (layer "In2.Cu") (net 188))
  (segment (start 82.89999 123.55) (end 91.05 123.55) (width 0.1) (layer "In2.Cu") (net 188))
  (segment (start 81.1 123.75) (end 80.7 123.35) (width 0.15) (layer "F.Cu") (net 189))
  (segment (start 95.2 123.35) (end 94.8 122.95) (width 0.15) (layer "F.Cu") (net 189))
  (via blind (at 80.7 123.35) (size 0.5) (drill 0.2) (layers "F.Cu" "In2.Cu") (net 189))
  (via (at 94.8 122.95) (size 0.5) (drill 0.2) (layers "F.Cu" "B.Cu") (net 189))
  (segment (start 94.6 122.95) (end 94.8 122.95) (width 0.1) (layer "In2.Cu") (net 189))
  (segment (start 80.7 123.35) (end 80.95 123.6) (width 0.1) (layer "In2.Cu") (net 189))
  (segment (start 80.95 123.6) (end 82.05 123.6) (width 0.1) (layer "In2.Cu") (net 189))
  (segment (start 82.3 123.35) (end 94.2 123.35) (width 0.1) (layer "In2.Cu") (net 189))
  (segment (start 82.05 123.6) (end 82.3 123.35) (width 0.1) (layer "In2.Cu") (net 189))
  (segment (start 94.2 123.35) (end 94.6 122.95) (width 0.1) (layer "In2.Cu") (net 189))
  (segment (start 85.9 125.35) (end 86.3 125.75) (width 0.1) (layer "F.Cu") (net 190))
  (segment (start 89.75 123.75) (end 88.9 124.6) (width 0.1) (layer "F.Cu") (net 190))
  (segment (start 88.9 124.6) (end 88.9 125.95) (width 0.1) (layer "F.Cu") (net 190))
  (segment (start 94.35 123.75) (end 89.75 123.75) (width 0.1) (layer "F.Cu") (net 190))
  (segment (start 88.2 126.05) (end 87.9 125.75) (width 0.1) (layer "F.Cu") (net 190))
  (segment (start 88.8 126.05) (end 88.2 126.05) (width 0.1) (layer "F.Cu") (net 190))
  (segment (start 88.9 125.95) (end 88.8 126.05) (width 0.1) (layer "F.Cu") (net 190))
  (segment (start 94.4 123.7) (end 94.35 123.75) (width 0.1) (layer "F.Cu") (net 190))
  (segment (start 94.4 123.35) (end 94.4 123.7) (width 0.1) (layer "F.Cu") (net 190))
  (via blind (at 86.3 125.75) (size 0.5) (drill 0.2) (layers "F.Cu" "In5.Cu") (net 190))
  (via (at 87.9 125.75) (size 0.5) (drill 0.2) (layers "F.Cu" "B.Cu") (net 190))
  (segment (start 87.152271 127.047063) (end 87.172063 127.027271) (width 0.1) (layer "In5.Cu") (net 190))
  (segment (start 86.902271 127.298924) (end 86.922063 127.318716) (width 0.1) (layer "In5.Cu") (net 190))
  (segment (start 86.640924 126.881495) (end 86.652482 126.869937) (width 0.1) (layer "In5.Cu") (net 190))
  (segment (start 87.125 127.125) (end 87.128134 127.097184) (width 0.1) (layer "In5.Cu") (net 190))
  (segment (start 86.867771 126.895336) (end 86.873169 126.910764) (width 0.1) (layer "In5.Cu") (net 190))
  (segment (start 88.1 127) (end 88.35 126.75) (width 0.1) (layer "In5.Cu") (net 190))
  (segment (start 86.878134 127.248803) (end 86.887378 127.275223) (width 0.1) (layer "In5.Cu") (net 190))
  (segment (start 86.387378 127.275223) (end 86.402271 127.298924) (width 0.1) (layer "In5.Cu") (net 190))
  (segment (start 87.222184 127.003134) (end 87.25 127) (width 0.1) (layer "In5.Cu") (net 190))
  (segment (start 86.945764 127.333609) (end 86.972184 127.342853) (width 0.1) (layer "In5.Cu") (net 190))
  (segment (start 86.875 127.220988) (end 86.878134 127.248803) (width 0.1) (layer "In5.Cu") (net 190))
  (segment (start 86.62683 126.910764) (end 86.632228 126.895336) (width 0.1) (layer "In5.Cu") (net 190))
  (segment (start 86.375 127.220988) (end 86.378134 127.248803) (width 0.1) (layer "In5.Cu") (net 190))
  (segment (start 86.527815 127.342853) (end 86.554235 127.333609) (width 0.1) (layer "In5.Cu") (net 190))
  (segment (start 86.304235 127.012378) (end 86.327936 127.027271) (width 0.1) (layer "In5.Cu") (net 190))
  (segment (start 88.35 126.75) (end 88.35 126.2) (width 0.1) (layer "In5.Cu") (net 190))
  (segment (start 85.9 126.15) (end 85.9 126.75) (width 0.1) (layer "In5.Cu") (net 190))
  (segment (start 86.833676 126.861241) (end 86.847517 126.869937) (width 0.1) (layer "In5.Cu") (net 190))
  (segment (start 87.137378 127.070764) (end 87.152271 127.047063) (width 0.1) (layer "In5.Cu") (net 190))
  (segment (start 86.327936 127.027271) (end 86.347728 127.047063) (width 0.1) (layer "In5.Cu") (net 190))
  (segment (start 86.621865 127.248803) (end 86.625 127.220988) (width 0.1) (layer "In5.Cu") (net 190))
  (segment (start 86.362621 127.070764) (end 86.371865 127.097184) (width 0.1) (layer "In5.Cu") (net 190))
  (segment (start 86.554235 127.333609) (end 86.577936 127.318716) (width 0.1) (layer "In5.Cu") (net 190))
  (segment (start 87.172063 127.027271) (end 87.195764 127.012378) (width 0.1) (layer "In5.Cu") (net 190))
  (segment (start 86.277815 127.003134) (end 86.304235 127.012378) (width 0.1) (layer "In5.Cu") (net 190))
  (segment (start 86.652482 126.869937) (end 86.666323 126.861241) (width 0.1) (layer "In5.Cu") (net 190))
  (segment (start 86.5 127.345988) (end 86.527815 127.342853) (width 0.1) (layer "In5.Cu") (net 190))
  (segment (start 86.873169 126.910764) (end 86.875 126.927006) (width 0.1) (layer "In5.Cu") (net 190))
  (segment (start 86.802006 126.854012) (end 86.818248 126.855843) (width 0.1) (layer "In5.Cu") (net 190))
  (segment (start 86.445764 127.333609) (end 86.472184 127.342853) (width 0.1) (layer "In5.Cu") (net 190))
  (segment (start 86.681751 126.855843) (end 86.697994 126.854012) (width 0.1) (layer "In5.Cu") (net 190))
  (segment (start 85.9 126.75) (end 86.15 127) (width 0.1) (layer "In5.Cu") (net 190))
  (segment (start 86.666323 126.861241) (end 86.681751 126.855843) (width 0.1) (layer "In5.Cu") (net 190))
  (segment (start 86.632228 126.895336) (end 86.640924 126.881495) (width 0.1) (layer "In5.Cu") (net 190))
  (segment (start 87.097728 127.298924) (end 87.112621 127.275223) (width 0.1) (layer "In5.Cu") (net 190))
  (segment (start 86.597728 127.298924) (end 86.612621 127.275223) (width 0.1) (layer "In5.Cu") (net 190))
  (segment (start 87.054235 127.333609) (end 87.077936 127.318716) (width 0.1) (layer "In5.Cu") (net 190))
  (segment (start 86.818248 126.855843) (end 86.833676 126.861241) (width 0.1) (layer "In5.Cu") (net 190))
  (segment (start 87.077936 127.318716) (end 87.097728 127.298924) (width 0.1) (layer "In5.Cu") (net 190))
  (segment (start 87.25 127) (end 88.1 127) (width 0.1) (layer "In5.Cu") (net 190))
  (segment (start 87.027815 127.342853) (end 87.054235 127.333609) (width 0.1) (layer "In5.Cu") (net 190))
  (segment (start 86.402271 127.298924) (end 86.422063 127.318716) (width 0.1) (layer "In5.Cu") (net 190))
  (segment (start 87.125 127.220988) (end 87.125 127.125) (width 0.1) (layer "In5.Cu") (net 190))
  (segment (start 86.375 127.125) (end 86.375 127.220988) (width 0.1) (layer "In5.Cu") (net 190))
  (segment (start 86.378134 127.248803) (end 86.387378 127.275223) (width 0.1) (layer "In5.Cu") (net 190))
  (segment (start 86.347728 127.047063) (end 86.362621 127.070764) (width 0.1) (layer "In5.Cu") (net 190))
  (segment (start 86.625 126.927006) (end 86.62683 126.910764) (width 0.1) (layer "In5.Cu") (net 190))
  (segment (start 87.128134 127.097184) (end 87.137378 127.070764) (width 0.1) (layer "In5.Cu") (net 190))
  (segment (start 86.422063 127.318716) (end 86.445764 127.333609) (width 0.1) (layer "In5.Cu") (net 190))
  (segment (start 87.195764 127.012378) (end 87.222184 127.003134) (width 0.1) (layer "In5.Cu") (net 190))
  (segment (start 86.25 127) (end 86.277815 127.003134) (width 0.1) (layer "In5.Cu") (net 190))
  (segment (start 88.35 126.2) (end 87.9 125.75) (width 0.1) (layer "In5.Cu") (net 190))
  (segment (start 86.847517 126.869937) (end 86.859075 126.881495) (width 0.1) (layer "In5.Cu") (net 190))
  (segment (start 86.15 127) (end 86.25 127) (width 0.1) (layer "In5.Cu") (net 190))
  (segment (start 86.972184 127.342853) (end 87 127.345988) (width 0.1) (layer "In5.Cu") (net 190))
  (segment (start 87.112621 127.275223) (end 87.121865 127.248803) (width 0.1) (layer "In5.Cu") (net 190))
  (segment (start 86.612621 127.275223) (end 86.621865 127.248803) (width 0.1) (layer "In5.Cu") (net 190))
  (segment (start 86.887378 127.275223) (end 86.902271 127.298924) (width 0.1) (layer "In5.Cu") (net 190))
  (segment (start 86.3 125.75) (end 85.9 126.15) (width 0.1) (layer "In5.Cu") (net 190))
  (segment (start 86.472184 127.342853) (end 86.5 127.345988) (width 0.1) (layer "In5.Cu") (net 190))
  (segment (start 86.859075 126.881495) (end 86.867771 126.895336) (width 0.1) (layer "In5.Cu") (net 190))
  (segment (start 86.371865 127.097184) (end 86.375 127.125) (width 0.1) (layer "In5.Cu") (net 190))
  (segment (start 86.577936 127.318716) (end 86.597728 127.298924) (width 0.1) (layer "In5.Cu") (net 190))
  (segment (start 86.697994 126.854012) (end 86.802006 126.854012) (width 0.1) (layer "In5.Cu") (net 190))
  (segment (start 87.121865 127.248803) (end 87.125 127.220988) (width 0.1) (layer "In5.Cu") (net 190))
  (segment (start 87 127.345988) (end 87.027815 127.342853) (width 0.1) (layer "In5.Cu") (net 190))
  (segment (start 86.875 126.927006) (end 86.875 127.220988) (width 0.1) (layer "In5.Cu") (net 190))
  (segment (start 86.922063 127.318716) (end 86.945764 127.333609) (width 0.1) (layer "In5.Cu") (net 190))
  (segment (start 86.625 127.220988) (end 86.625 126.927006) (width 0.1) (layer "In5.Cu") (net 190))
  (segment (start 81.8898 125.35) (end 82.35 125.35) (width 0.1) (layer "F.Cu") (net 191))
  (segment (start 82.35 125.35) (end 82.55 125.15) (width 0.1) (layer "F.Cu") (net 191))
  (segment (start 96 126.55) (end 95.6 126.15) (width 0.15) (layer "F.Cu") (net 191))
  (via blind (at 82.55 125.15) (size 0.5) (drill 0.2) (layers "F.Cu" "In2.Cu") (net 191))
  (via blind (at 95.6 126.15) (size 0.5) (drill 0.2) (layers "F.Cu" "In2.Cu") (net 191))
  (segment (start 88.2 125.35) (end 82.75 125.35) (width 0.1) (layer "In2.Cu") (net 191))
  (segment (start 88.9 124.65) (end 88.2 125.35) (width 0.1) (layer "In2.Cu") (net 191))
  (segment (start 94.4 125.15) (end 93.9 124.65) (width 0.1) (layer "In2.Cu") (net 191))
  (segment (start 94.4 125.55) (end 94.4 125.15) (width 0.1) (layer "In2.Cu") (net 191))
  (segment (start 95.6 126.15) (end 95.2 125.75) (width 0.1) (layer "In2.Cu") (net 191))
  (segment (start 94.6 125.75) (end 94.4 125.55) (width 0.1) (layer "In2.Cu") (net 191))
  (segment (start 82.75 125.35) (end 82.55 125.15) (width 0.1) (layer "In2.Cu") (net 191))
  (segment (start 95.2 125.75) (end 94.6 125.75) (width 0.1) (layer "In2.Cu") (net 191))
  (segment (start 93.9 124.65) (end 88.9 124.65) (width 0.1) (layer "In2.Cu") (net 191))
  (segment (start 85.1 123.75) (end 85.1 124) (width 0.1) (layer "F.Cu") (net 192))
  (segment (start 84.45 123.75) (end 84.25 123.95) (width 0.1) (layer "F.Cu") (net 192))
  (segment (start 84.6 123.75) (end 84.45 123.75) (width 0.1) (layer "F.Cu") (net 192))
  (segment (start 85.05 124.05) (end 84.9 124.05) (width 0.1) (layer "F.Cu") (net 192))
  (segment (start 84.9 124.05) (end 84.6 123.75) (width 0.1) (layer "F.Cu") (net 192))
  (segment (start 96.8 124.95) (end 96.35 124.5) (width 0.15) (layer "F.Cu") (net 192))
  (segment (start 85.1 124) (end 85.05 124.05) (width 0.1) (layer "F.Cu") (net 192))
  (via blind (at 84.25 123.95) (size 0.5) (drill 0.2) (layers "F.Cu" "In2.Cu") (net 192))
  (via blind (at 96.35 124.5) (size 0.5) (drill 0.2) (layers "F.Cu" "In2.Cu") (net 192))
  (segment (start 84.987651 123.771816) (end 85.006611 123.759903) (width 0.1) (layer "In2.Cu") (net 192))
  (segment (start 84.712348 123.771816) (end 84.728183 123.787651) (width 0.1) (layer "In2.Cu") (net 192))
  (segment (start 85.05 123.75) (end 88.6 123.75) (width 0.1) (layer "In2.Cu") (net 192))
  (segment (start 85.006611 123.759903) (end 85.027747 123.752507) (width 0.1) (layer "In2.Cu") (net 192))
  (segment (start 84.912348 124.261574) (end 84.928183 124.245739) (width 0.1) (layer "In2.Cu") (net 192))
  (segment (start 84.952507 123.827747) (end 84.959903 123.806611) (width 0.1) (layer "In2.Cu") (net 192))
  (segment (start 84.95 124.183391) (end 84.95 123.85) (width 0.1) (layer "In2.Cu") (net 192))
  (segment (start 84.971816 123.787651) (end 84.987651 123.771816) (width 0.1) (layer "In2.Cu") (net 192))
  (segment (start 84.25 123.95) (end 84.45 123.75) (width 0.1) (layer "In2.Cu") (net 192))
  (segment (start 84.827747 124.280883) (end 84.85 124.283391) (width 0.1) (layer "In2.Cu") (net 192))
  (segment (start 85.027747 123.752507) (end 85.05 123.75) (width 0.1) (layer "In2.Cu") (net 192))
  (segment (start 84.759903 124.226779) (end 84.771816 124.245739) (width 0.1) (layer "In2.Cu") (net 192))
  (segment (start 84.75 124.183391) (end 84.752507 124.205643) (width 0.1) (layer "In2.Cu") (net 192))
  (segment (start 84.693388 123.759903) (end 84.712348 123.771816) (width 0.1) (layer "In2.Cu") (net 192))
  (segment (start 84.65 123.75) (end 84.672252 123.752507) (width 0.1) (layer "In2.Cu") (net 192))
  (segment (start 84.928183 124.245739) (end 84.940096 124.226779) (width 0.1) (layer "In2.Cu") (net 192))
  (segment (start 84.95 123.85) (end 84.952507 123.827747) (width 0.1) (layer "In2.Cu") (net 192))
  (segment (start 84.740096 123.806611) (end 84.747492 123.827747) (width 0.1) (layer "In2.Cu") (net 192))
  (segment (start 84.45 123.75) (end 84.65 123.75) (width 0.1) (layer "In2.Cu") (net 192))
  (segment (start 96.35 124.217158) (end 96.35 124.5) (width 0.1) (layer "In2.Cu") (net 192))
  (segment (start 88.65 123.8) (end 94.6 123.8) (width 0.1) (layer "In2.Cu") (net 192))
  (segment (start 84.959903 123.806611) (end 84.971816 123.787651) (width 0.1) (layer "In2.Cu") (net 192))
  (segment (start 88.6 123.75) (end 88.65 123.8) (width 0.1) (layer "In2.Cu") (net 192))
  (segment (start 84.872252 124.280883) (end 84.893388 124.273487) (width 0.1) (layer "In2.Cu") (net 192))
  (segment (start 94.6 123.8) (end 94.699999 123.700001) (width 0.1) (layer "In2.Cu") (net 192))
  (segment (start 95.832843 123.700001) (end 96.35 124.217158) (width 0.1) (layer "In2.Cu") (net 192))
  (segment (start 84.75 123.85) (end 84.75 124.183391) (width 0.1) (layer "In2.Cu") (net 192))
  (segment (start 84.771816 124.245739) (end 84.787651 124.261574) (width 0.1) (layer "In2.Cu") (net 192))
  (segment (start 84.728183 123.787651) (end 84.740096 123.806611) (width 0.1) (layer "In2.Cu") (net 192))
  (segment (start 84.806611 124.273487) (end 84.827747 124.280883) (width 0.1) (layer "In2.Cu") (net 192))
  (segment (start 84.893388 124.273487) (end 84.912348 124.261574) (width 0.1) (layer "In2.Cu") (net 192))
  (segment (start 84.940096 124.226779) (end 84.947492 124.205643) (width 0.1) (layer "In2.Cu") (net 192))
  (segment (start 84.752507 124.205643) (end 84.759903 124.226779) (width 0.1) (layer "In2.Cu") (net 192))
  (segment (start 84.787651 124.261574) (end 84.806611 124.273487) (width 0.1) (layer "In2.Cu") (net 192))
  (segment (start 84.672252 123.752507) (end 84.693388 123.759903) (width 0.1) (layer "In2.Cu") (net 192))
  (segment (start 84.947492 124.205643) (end 84.95 124.183391) (width 0.1) (layer "In2.Cu") (net 192))
  (segment (start 94.699999 123.700001) (end 95.832843 123.700001) (width 0.1) (layer "In2.Cu") (net 192))
  (segment (start 84.85 124.283391) (end 84.872252 124.280883) (width 0.1) (layer "In2.Cu") (net 192))
  (segment (start 84.747492 123.827747) (end 84.75 123.85) (width 0.1) (layer "In2.Cu") (net 192))
  (segment (start 81.1 125.35) (end 81.5 125.75) (width 0.1) (layer "F.Cu") (net 193))
  (segment (start 95.2 127.35) (end 94.8 126.95) (width 0.1) (layer "F.Cu") (net 193))
  (via blind (at 81.5 125.75) (size 0.5) (drill 0.2) (layers "F.Cu" "In2.Cu") (net 193))
  (via blind (at 94.8 126.95) (size 0.5) (drill 0.2) (layers "F.Cu" "In2.Cu") (net 193))
  (segment (start 94.4 126.55) (end 94.8 126.95) (width 0.1) (layer "In2.Cu") (net 193))
  (segment (start 88.925 127.15) (end 89.375 126.7) (width 0.1) (layer "In2.Cu") (net 193))
  (segment (start 91.9 126.55) (end 94.4 126.55) (width 0.1) (layer "In2.Cu") (net 193))
  (segment (start 81.869683 126.179728) (end 81.886056 126.175991) (width 0.1) (layer "In2.Cu") (net 193))
  (segment (start 81.717758 125.978262) (end 81.721495 125.994635) (width 0.1) (layer "In2.Cu") (net 193))
  (segment (start 91.75 126.7) (end 91.9 126.55) (width 0.1) (layer "In2.Cu") (net 193))
  (segment (start 81.902851 126.175991) (end 81.919224 126.179728) (width 0.1) (layer "In2.Cu") (net 193))
  (segment (start 81.721495 126.01143) (end 81.717758 126.027803) (width 0.1) (layer "In2.Cu") (net 193))
  (segment (start 81.682241 126.084328) (end 81.678504 126.100701) (width 0.1) (layer "In2.Cu") (net 193))
  (segment (start 81.682241 126.133869) (end 81.689528 126.149001) (width 0.1) (layer "In2.Cu") (net 193))
  (segment (start 81.7 125.95) (end 81.710471 125.96313) (width 0.1) (layer "In2.Cu") (net 193))
  (segment (start 81.82829 126.207958) (end 81.854551 126.187015) (width 0.1) (layer "In2.Cu") (net 193))
  (segment (start 81.854551 126.187015) (end 81.869683 126.179728) (width 0.1) (layer "In2.Cu") (net 193))
  (segment (start 82.3 126.55) (end 82.7 126.55) (width 0.1) (layer "In2.Cu") (net 193))
  (segment (start 81.813159 126.215245) (end 81.82829 126.207958) (width 0.1) (layer "In2.Cu") (net 193))
  (segment (start 81.7 126.162132) (end 81.735355 126.197487) (width 0.1) (layer "In2.Cu") (net 193))
  (segment (start 83.3 127.15) (end 88.925 127.15) (width 0.1) (layer "In2.Cu") (net 193))
  (segment (start 81.710471 126.042935) (end 81.689528 126.069196) (width 0.1) (layer "In2.Cu") (net 193))
  (segment (start 81.763617 126.215245) (end 81.779991 126.218982) (width 0.1) (layer "In2.Cu") (net 193))
  (segment (start 82.7 126.55) (end 83.3 127.15) (width 0.1) (layer "In2.Cu") (net 193))
  (segment (start 81.717758 126.027803) (end 81.710471 126.042935) (width 0.1) (layer "In2.Cu") (net 193))
  (segment (start 81.748485 126.207958) (end 81.763617 126.215245) (width 0.1) (layer "In2.Cu") (net 193))
  (segment (start 81.886056 126.175991) (end 81.902851 126.175991) (width 0.1) (layer "In2.Cu") (net 193))
  (segment (start 81.678504 126.117496) (end 81.682241 126.133869) (width 0.1) (layer "In2.Cu") (net 193))
  (segment (start 81.678504 126.100701) (end 81.678504 126.117496) (width 0.1) (layer "In2.Cu") (net 193))
  (segment (start 81.796785 126.218982) (end 81.813159 126.215245) (width 0.1) (layer "In2.Cu") (net 193))
  (segment (start 81.934356 126.187015) (end 81.947487 126.197487) (width 0.1) (layer "In2.Cu") (net 193))
  (segment (start 81.5 125.75) (end 81.7 125.95) (width 0.1) (layer "In2.Cu") (net 193))
  (segment (start 81.689528 126.149001) (end 81.7 126.162132) (width 0.1) (layer "In2.Cu") (net 193))
  (segment (start 81.721495 125.994635) (end 81.721495 126.01143) (width 0.1) (layer "In2.Cu") (net 193))
  (segment (start 81.919224 126.179728) (end 81.934356 126.187015) (width 0.1) (layer "In2.Cu") (net 193))
  (segment (start 89.375 126.7) (end 91.75 126.7) (width 0.1) (layer "In2.Cu") (net 193))
  (segment (start 81.779991 126.218982) (end 81.796785 126.218982) (width 0.1) (layer "In2.Cu") (net 193))
  (segment (start 81.689528 126.069196) (end 81.682241 126.084328) (width 0.1) (layer "In2.Cu") (net 193))
  (segment (start 81.710471 125.96313) (end 81.717758 125.978262) (width 0.1) (layer "In2.Cu") (net 193))
  (segment (start 81.735355 126.197487) (end 81.748485 126.207958) (width 0.1) (layer "In2.Cu") (net 193))
  (segment (start 81.947487 126.197487) (end 82.3 126.55) (width 0.1) (layer "In2.Cu") (net 193))
  (segment (start 95.8 124.25) (end 96.3 123.75) (width 0.1) (layer "F.Cu") (net 194))
  (segment (start 96.3 123.75) (end 96.3 123.65) (width 0.1) (layer "F.Cu") (net 194))
  (segment (start 96.3 123.65) (end 96 123.35) (width 0.1) (layer "F.Cu") (net 194))
  (segment (start 85.9 124.55) (end 86.3 124.15) (width 0.1) (layer "F.Cu") (net 194))
  (via blind (at 95.8 124.25) (size 0.5) (drill 0.2) (layers "F.Cu" "In2.Cu") (net 194))
  (via blind (at 86.3 124.15) (size 0.5) (drill 0.2) (layers "F.Cu" "In2.Cu") (net 194))
  (segment (start 95.65 124.7) (end 95.8 124.55) (width 0.1) (layer "In2.Cu") (net 194))
  (segment (start 88.143388 124.332366) (end 88.162348 124.320453) (width 0.1) (layer "In2.Cu") (net 194))
  (segment (start 87.035868 123.958887) (end 87.046135 123.95773) (width 0.1) (layer "In2.Cu") (net 194))
  (segment (start 94.7 124.05) (end 94.778765 124.128765) (width 0.1) (layer "In2.Cu") (net 194))
  (segment (start 88.077747 124.339762) (end 88.1 124.34227) (width 0.1) (layer "In2.Cu") (net 194))
  (segment (start 86.762348 124.071816) (end 86.778183 124.087651) (width 0.1) (layer "In2.Cu") (net 194))
  (segment (start 94.784684 124.138186) (end 94.78593 124.143644) (width 0.1) (layer "In2.Cu") (net 194))
  (segment (start 87.195431 123.983848) (end 87.198843 123.993599) (width 0.1) (layer "In2.Cu") (net 194))
  (segment (start 94.7716 124.184598) (end 94.772846 124.190056) (width 0.1) (layer "In2.Cu") (net 194))
  (segment (start 87.722252 124.339762) (end 87.743388 124.332366) (width 0.1) (layer "In2.Cu") (net 194))
  (segment (start 88 124.24227) (end 88.002507 124.264522) (width 0.1) (layer "In2.Cu") (net 194))
  (segment (start 95.432842 123.934313) (end 95.446804 123.951821) (width 0.1) (layer "In2.Cu") (net 194))
  (segment (start 87.209903 124.285658) (end 87.221816 124.304618) (width 0.1) (layer "In2.Cu") (net 194))
  (segment (start 86.4 124.05) (end 86.7 124.05) (width 0.1) (layer "In2.Cu") (net 194))
  (segment (start 87.001156 123.993599) (end 87.004568 123.983848) (width 0.1) (layer "In2.Cu") (net 194))
  (segment (start 95.136038 124.482492) (end 95.15 124.5) (width 0.1) (layer "In2.Cu") (net 194))
  (segment (start 95.126322 124.462317) (end 95.136038 124.482492) (width 0.1) (layer "In2.Cu") (net 194))
  (segment (start 88.197492 124.264522) (end 88.2 124.24227) (width 0.1) (layer "In2.Cu") (net 194))
  (segment (start 94.778765 124.164121) (end 94.775276 124.168499) (width 0.1) (layer "In2.Cu") (net 194))
  (segment (start 94.784684 124.1547) (end 94.782256 124.159745) (width 0.1) (layer "In2.Cu") (net 194))
  (segment (start 88.178183 124.304618) (end 88.190096 124.285658) (width 0.1) (layer "In2.Cu") (net 194))
  (segment (start 87.404568 123.983848) (end 87.410065 123.975101) (width 0.1) (layer "In2.Cu") (net 194))
  (segment (start 86.990096 124.285658) (end 86.997492 124.264522) (width 0.1) (layer "In2.Cu") (net 194))
  (segment (start 94.90531 124.312709) (end 94.910767 124.311463) (width 0.1) (layer "In2.Cu") (net 194))
  (segment (start 87.743388 124.332366) (end 87.762348 124.320453) (width 0.1) (layer "In2.Cu") (net 194))
  (segment (start 87.173882 123.962299) (end 87.182629 123.967796) (width 0.1) (layer "In2.Cu") (net 194))
  (segment (start 87.953865 123.95773) (end 87.964131 123.958887) (width 0.1) (layer "In2.Cu") (net 194))
  (segment (start 87.237651 124.320453) (end 87.256611 124.332366) (width 0.1) (layer "In2.Cu") (net 194))
  (segment (start 88.1 124.34227) (end 88.122252 124.339762) (width 0.1) (layer "In2.Cu") (net 194))
  (segment (start 87.810065 123.975101) (end 87.81737 123.967796) (width 0.1) (layer "In2.Cu") (net 194))
  (segment (start 87.989934 123.975101) (end 87.995431 123.983848) (width 0.1) (layer "In2.Cu") (net 194))
  (segment (start 88.446135 124.05) (end 94.7 124.05) (width 0.1) (layer "In2.Cu") (net 194))
  (segment (start 87.4 124.24227) (end 87.4 124.003865) (width 0.1) (layer "In2.Cu") (net 194))
  (segment (start 87.677747 124.339762) (end 87.7 124.34227) (width 0.1) (layer "In2.Cu") (net 194))
  (segment (start 87.164131 123.958887) (end 87.173882 123.962299) (width 0.1) (layer "In2.Cu") (net 194))
  (segment (start 87.602507 124.264522) (end 87.609903 124.285658) (width 0.1) (layer "In2.Cu") (net 194))
  (segment (start 86.8 124.15) (end 86.8 124.24227) (width 0.1) (layer "In2.Cu") (net 194))
  (segment (start 88.21737 123.967796) (end 88.226117 123.962299) (width 0.1) (layer "In2.Cu") (net 194))
  (segment (start 87.362348 124.320453) (end 87.378183 124.304618) (width 0.1) (layer "In2.Cu") (net 194))
  (segment (start 87.81737 123.967796) (end 87.826117 123.962299) (width 0.1) (layer "In2.Cu") (net 194))
  (segment (start 94.78593 124.143644) (end 94.78593 124.149242) (width 0.1) (layer "In2.Cu") (net 194))
  (segment (start 88.204568 123.983848) (end 88.210065 123.975101) (width 0.1) (layer "In2.Cu") (net 194))
  (segment (start 87.762348 124.320453) (end 87.778183 124.304618) (width 0.1) (layer "In2.Cu") (net 194))
  (segment (start 95.432842 124.075735) (end 95.15 124.358578) (width 0.1) (layer "In2.Cu") (net 194))
  (segment (start 88 124.003865) (end 88 124.24227) (width 0.1) (layer "In2.Cu") (net 194))
  (segment (start 88.210065 123.975101) (end 88.21737 123.967796) (width 0.1) (layer "In2.Cu") (net 194))
  (segment (start 95.136038 124.376086) (end 95.126322 124.396261) (width 0.1) (layer "In2.Cu") (net 194))
  (segment (start 94.782256 124.159745) (end 94.778765 124.164121) (width 0.1) (layer "In2.Cu") (net 194))
  (segment (start 87.378183 124.304618) (end 87.390096 124.285658) (width 0.1) (layer "In2.Cu") (net 194))
  (segment (start 94.782256 124.133143) (end 94.784684 124.138186) (width 0.1) (layer "In2.Cu") (net 194))
  (segment (start 88.190096 124.285658) (end 88.197492 124.264522) (width 0.1) (layer "In2.Cu") (net 194))
  (segment (start 86.943388 124.332366) (end 86.962348 124.320453) (width 0.1) (layer "In2.Cu") (net 194))
  (segment (start 88.056611 124.332366) (end 88.077747 124.339762) (width 0.1) (layer "In2.Cu") (net 194))
  (segment (start 94.899712 124.312709) (end 94.90531 124.312709) (width 0.1) (layer "In2.Cu") (net 194))
  (segment (start 86.922252 124.339762) (end 86.943388 124.332366) (width 0.1) (layer "In2.Cu") (net 194))
  (segment (start 87.397492 124.264522) (end 87.4 124.24227) (width 0.1) (layer "In2.Cu") (net 194))
  (segment (start 88.395431 123.983848) (end 88.398843 123.993599) (width 0.1) (layer "In2.Cu") (net 194))
  (segment (start 87.778183 124.304618) (end 87.790096 124.285658) (width 0.1) (layer "In2.Cu") (net 194))
  (segment (start 87.435868 123.958887) (end 87.446135 123.95773) (width 0.1) (layer "In2.Cu") (net 194))
  (segment (start 95.415334 123.920351) (end 95.432842 123.934313) (width 0.1) (layer "In2.Cu") (net 194))
  (segment (start 87.595431 123.983848) (end 87.598843 123.993599) (width 0.1) (layer "In2.Cu") (net 194))
  (segment (start 87.995431 123.983848) (end 87.998843 123.993599) (width 0.1) (layer "In2.Cu") (net 194))
  (segment (start 86.997492 124.264522) (end 87 124.24227) (width 0.1) (layer "In2.Cu") (net 194))
  (segment (start 88.353865 123.95773) (end 88.364131 123.958887) (width 0.1) (layer "In2.Cu") (net 194))
  (segment (start 86.790096 124.106611) (end 86.797492 124.127747) (width 0.1) (layer "In2.Cu") (net 194))
  (segment (start 87.573882 123.962299) (end 87.582629 123.967796) (width 0.1) (layer "In2.Cu") (net 194))
  (segment (start 95.461503 124.016221) (end 95.45652 124.038052) (width 0.1) (layer "In2.Cu") (net 194))
  (segment (start 87.4 124.003865) (end 87.401156 123.993599) (width 0.1) (layer "In2.Cu") (net 194))
  (segment (start 88.162348 124.320453) (end 88.178183 124.304618) (width 0.1) (layer "In2.Cu") (net 194))
  (segment (start 88.404568 124.023883) (end 88.410065 124.03263) (width 0.1) (layer "In2.Cu") (net 194))
  (segment (start 87.343388 124.332366) (end 87.362348 124.320453) (width 0.1) (layer "In2.Cu") (net 194))
  (segment (start 87 124.24227) (end 87 124.003865) (width 0.1) (layer "In2.Cu") (net 194))
  (segment (start 88.373882 123.962299) (end 88.382629 123.967796) (width 0.1) (layer "In2.Cu") (net 194))
  (segment (start 94.894253 124.311463) (end 94.899712 124.312709) (width 0.1) (layer "In2.Cu") (net 194))
  (segment (start 88.122252 124.339762) (end 88.143388 124.332366) (width 0.1) (layer "In2.Cu") (net 194))
  (segment (start 94.775276 124.195101) (end 94.778766 124.199477) (width 0.1) (layer "In2.Cu") (net 194))
  (segment (start 87.656611 124.332366) (end 87.677747 124.339762) (width 0.1) (layer "In2.Cu") (net 194))
  (segment (start 87.046135 123.95773) (end 87.153865 123.95773) (width 0.1) (layer "In2.Cu") (net 194))
  (segment (start 86.809903 124.285658) (end 86.821816 124.304618) (width 0.1) (layer "In2.Cu") (net 194))
  (segment (start 87.564131 123.958887) (end 87.573882 123.962299) (width 0.1) (layer "In2.Cu") (net 194))
  (segment (start 87.322252 124.339762) (end 87.343388 124.332366) (width 0.1) (layer "In2.Cu") (net 194))
  (segment (start 87.846135 123.95773) (end 87.953865 123.95773) (width 0.1) (layer "In2.Cu") (net 194))
  (segment (start 87.390096 124.285658) (end 87.397492 124.264522) (width 0.1) (layer "In2.Cu") (net 194))
  (segment (start 87.026117 123.962299) (end 87.035868 123.958887) (width 0.1) (layer "In2.Cu") (net 194))
  (segment (start 86.821816 124.304618) (end 86.837651 124.320453) (width 0.1) (layer "In2.Cu") (net 194))
  (segment (start 87.202507 124.264522) (end 87.209903 124.285658) (width 0.1) (layer "In2.Cu") (net 194))
  (segment (start 86.7 124.05) (end 86.722252 124.052507) (width 0.1) (layer "In2.Cu") (net 194))
  (segment (start 87.277747 124.339762) (end 87.3 124.34227) (width 0.1) (layer "In2.Cu") (net 194))
  (segment (start 87.826117 123.962299) (end 87.835868 123.958887) (width 0.1) (layer "In2.Cu") (net 194))
  (segment (start 87.8 124.003865) (end 87.801156 123.993599) (width 0.1) (layer "In2.Cu") (net 194))
  (segment (start 86.978183 124.304618) (end 86.990096 124.285658) (width 0.1) (layer "In2.Cu") (net 194))
  (segment (start 88.246135 123.95773) (end 88.353865 123.95773) (width 0.1) (layer "In2.Cu") (net 194))
  (segment (start 94.775276 124.168499) (end 94.772846 124.173542) (width 0.1) (layer "In2.Cu") (net 194))
  (segment (start 94.910767 124.311463) (end 94.915812 124.309035) (width 0.1) (layer "In2.Cu") (net 194))
  (segment (start 94.772846 124.173542) (end 94.7716 124.179) (width 0.1) (layer "In2.Cu") (net 194))
  (segment (start 95.15 124.5) (end 95.35 124.7) (width 0.1) (layer "In2.Cu") (net 194))
  (segment (start 95.15 124.358578) (end 95.136038 124.376086) (width 0.1) (layer "In2.Cu") (net 194))
  (segment (start 95.29142 123.934313) (end 95.308928 123.920351) (width 0.1) (layer "In2.Cu") (net 194))
  (segment (start 88.002507 124.264522) (end 88.009903 124.285658) (width 0.1) (layer "In2.Cu") (net 194))
  (segment (start 88.410065 124.03263) (end 88.41737 124.039935) (width 0.1) (layer "In2.Cu") (net 194))
  (segment (start 87.621816 124.304618) (end 87.637651 124.320453) (width 0.1) (layer "In2.Cu") (net 194))
  (segment (start 87.182629 123.967796) (end 87.189934 123.975101) (width 0.1) (layer "In2.Cu") (net 194))
  (segment (start 95.45652 124.038052) (end 95.446804 124.058227) (width 0.1) (layer "In2.Cu") (net 194))
  (segment (start 95.121339 124.418092) (end 95.121339 124.440485) (width 0.1) (layer "In2.Cu") (net 194))
  (segment (start 87.582629 123.967796) (end 87.589934 123.975101) (width 0.1) (layer "In2.Cu") (net 194))
  (segment (start 87.3 124.34227) (end 87.322252 124.339762) (width 0.1) (layer "In2.Cu") (net 194))
  (segment (start 95.461503 123.993828) (end 95.461503 124.016221) (width 0.1) (layer "In2.Cu") (net 194))
  (segment (start 87.797492 124.264522) (end 87.8 124.24227) (width 0.1) (layer "In2.Cu") (net 194))
  (segment (start 88.389934 123.975101) (end 88.395431 123.983848) (width 0.1) (layer "In2.Cu") (net 194))
  (segment (start 88.021816 124.304618) (end 88.037651 124.320453) (width 0.1) (layer "In2.Cu") (net 194))
  (segment (start 95.446804 123.951821) (end 95.45652 123.971996) (width 0.1) (layer "In2.Cu") (net 194))
  (segment (start 87.410065 123.975101) (end 87.41737 123.967796) (width 0.1) (layer "In2.Cu") (net 194))
  (segment (start 94.7716 124.179) (end 94.7716 124.184598) (width 0.1) (layer "In2.Cu") (net 194))
  (segment (start 88.364131 123.958887) (end 88.373882 123.962299) (width 0.1) (layer "In2.Cu") (net 194))
  (segment (start 87.801156 123.993599) (end 87.804568 123.983848) (width 0.1) (layer "In2.Cu") (net 194))
  (segment (start 87.2 124.003865) (end 87.2 124.24227) (width 0.1) (layer "In2.Cu") (net 194))
  (segment (start 94.88921 124.309035) (end 94.894253 124.311463) (width 0.1) (layer "In2.Cu") (net 194))
  (segment (start 87.835868 123.958887) (end 87.846135 123.95773) (width 0.1) (layer "In2.Cu") (net 194))
  (segment (start 87.198843 123.993599) (end 87.2 124.003865) (width 0.1) (layer "In2.Cu") (net 194))
  (segment (start 95.121339 124.440485) (end 95.126322 124.462317) (width 0.1) (layer "In2.Cu") (net 194))
  (segment (start 86.743388 124.059903) (end 86.762348 124.071816) (width 0.1) (layer "In2.Cu") (net 194))
  (segment (start 88.398843 123.993599) (end 88.401156 124.014132) (width 0.1) (layer "In2.Cu") (net 194))
  (segment (start 94.778766 124.199477) (end 94.884833 124.305544) (width 0.1) (layer "In2.Cu") (net 194))
  (segment (start 86.877747 124.339762) (end 86.9 124.34227) (width 0.1) (layer "In2.Cu") (net 194))
  (segment (start 95.395159 123.910635) (end 95.415334 123.920351) (width 0.1) (layer "In2.Cu") (net 194))
  (segment (start 86.797492 124.127747) (end 86.8 124.15) (width 0.1) (layer "In2.Cu") (net 194))
  (segment (start 94.778765 124.128765) (end 94.782256 124.133143) (width 0.1) (layer "In2.Cu") (net 194))
  (segment (start 94.772846 124.190056) (end 94.775276 124.195101) (width 0.1) (layer "In2.Cu") (net 194))
  (segment (start 86.856611 124.332366) (end 86.877747 124.339762) (width 0.1) (layer "In2.Cu") (net 194))
  (segment (start 95.329103 123.910635) (end 95.350934 123.905652) (width 0.1) (layer "In2.Cu") (net 194))
  (segment (start 86.3 124.15) (end 86.4 124.05) (width 0.1) (layer "In2.Cu") (net 194))
  (segment (start 88.426117 124.045432) (end 88.435868 124.048844) (width 0.1) (layer "In2.Cu") (net 194))
  (segment (start 95.126322 124.396261) (end 95.121339 124.418092) (width 0.1) (layer "In2.Cu") (net 194))
  (segment (start 94.884833 124.305544) (end 94.88921 124.309035) (width 0.1) (layer "In2.Cu") (net 194))
  (segment (start 88.382629 123.967796) (end 88.389934 123.975101) (width 0.1) (layer "In2.Cu") (net 194))
  (segment (start 87.426117 123.962299) (end 87.435868 123.958887) (width 0.1) (layer "In2.Cu") (net 194))
  (segment (start 88.2 124.003865) (end 88.201156 123.993599) (width 0.1) (layer "In2.Cu") (net 194))
  (segment (start 88.009903 124.285658) (end 88.021816 124.304618) (width 0.1) (layer "In2.Cu") (net 194))
  (segment (start 87.964131 123.958887) (end 87.973882 123.962299) (width 0.1) (layer "In2.Cu") (net 194))
  (segment (start 88.2 124.24227) (end 88.2 124.003865) (width 0.1) (layer "In2.Cu") (net 194))
  (segment (start 87.401156 123.993599) (end 87.404568 123.983848) (width 0.1) (layer "In2.Cu") (net 194))
  (segment (start 88.201156 123.993599) (end 88.204568 123.983848) (width 0.1) (layer "In2.Cu") (net 194))
  (segment (start 88.435868 124.048844) (end 88.446135 124.05) (width 0.1) (layer "In2.Cu") (net 194))
  (segment (start 86.962348 124.320453) (end 86.978183 124.304618) (width 0.1) (layer "In2.Cu") (net 194))
  (segment (start 87.8 124.24227) (end 87.8 124.003865) (width 0.1) (layer "In2.Cu") (net 194))
  (segment (start 86.802507 124.264522) (end 86.809903 124.285658) (width 0.1) (layer "In2.Cu") (net 194))
  (segment (start 86.9 124.34227) (end 86.922252 124.339762) (width 0.1) (layer "In2.Cu") (net 194))
  (segment (start 95.350934 123.905652) (end 95.373327 123.905652) (width 0.1) (layer "In2.Cu") (net 194))
  (segment (start 87.01737 123.967796) (end 87.026117 123.962299) (width 0.1) (layer "In2.Cu") (net 194))
  (segment (start 87.790096 124.285658) (end 87.797492 124.264522) (width 0.1) (layer "In2.Cu") (net 194))
  (segment (start 88.037651 124.320453) (end 88.056611 124.332366) (width 0.1) (layer "In2.Cu") (net 194))
  (segment (start 87.41737 123.967796) (end 87.426117 123.962299) (width 0.1) (layer "In2.Cu") (net 194))
  (segment (start 86.8 124.24227) (end 86.802507 124.264522) (width 0.1) (layer "In2.Cu") (net 194))
  (segment (start 88.226117 123.962299) (end 88.235868 123.958887) (width 0.1) (layer "In2.Cu") (net 194))
  (segment (start 95.308928 123.920351) (end 95.329103 123.910635) (width 0.1) (layer "In2.Cu") (net 194))
  (segment (start 87.6 124.24227) (end 87.602507 124.264522) (width 0.1) (layer "In2.Cu") (net 194))
  (segment (start 87.256611 124.332366) (end 87.277747 124.339762) (width 0.1) (layer "In2.Cu") (net 194))
  (segment (start 87.010065 123.975101) (end 87.01737 123.967796) (width 0.1) (layer "In2.Cu") (net 194))
  (segment (start 86.837651 124.320453) (end 86.856611 124.332366) (width 0.1) (layer "In2.Cu") (net 194))
  (segment (start 87.998843 123.993599) (end 88 124.003865) (width 0.1) (layer "In2.Cu") (net 194))
  (segment (start 87.598843 123.993599) (end 87.6 124.003865) (width 0.1) (layer "In2.Cu") (net 194))
  (segment (start 87.189934 123.975101) (end 87.195431 123.983848) (width 0.1) (layer "In2.Cu") (net 194))
  (segment (start 88.41737 124.039935) (end 88.426117 124.045432) (width 0.1) (layer "In2.Cu") (net 194))
  (segment (start 86.722252 124.052507) (end 86.743388 124.059903) (width 0.1) (layer "In2.Cu") (net 194))
  (segment (start 87.637651 124.320453) (end 87.656611 124.332366) (width 0.1) (layer "In2.Cu") (net 194))
  (segment (start 87.609903 124.285658) (end 87.621816 124.304618) (width 0.1) (layer "In2.Cu") (net 194))
  (segment (start 87.221816 124.304618) (end 87.237651 124.320453) (width 0.1) (layer "In2.Cu") (net 194))
  (segment (start 94.78593 124.149242) (end 94.784684 124.1547) (width 0.1) (layer "In2.Cu") (net 194))
  (segment (start 87.804568 123.983848) (end 87.810065 123.975101) (width 0.1) (layer "In2.Cu") (net 194))
  (segment (start 95.45652 123.971996) (end 95.461503 123.993828) (width 0.1) (layer "In2.Cu") (net 194))
  (segment (start 88.235868 123.958887) (end 88.246135 123.95773) (width 0.1) (layer "In2.Cu") (net 194))
  (segment (start 87.7 124.34227) (end 87.722252 124.339762) (width 0.1) (layer "In2.Cu") (net 194))
  (segment (start 88.401156 124.014132) (end 88.404568 124.023883) (width 0.1) (layer "In2.Cu") (net 194))
  (segment (start 87.004568 123.983848) (end 87.010065 123.975101) (width 0.1) (layer "In2.Cu") (net 194))
  (segment (start 87.589934 123.975101) (end 87.595431 123.983848) (width 0.1) (layer "In2.Cu") (net 194))
  (segment (start 94.915812 124.309035) (end 94.920189 124.305544) (width 0.1) (layer "In2.Cu") (net 194))
  (segment (start 87.973882 123.962299) (end 87.982629 123.967796) (width 0.1) (layer "In2.Cu") (net 194))
  (segment (start 87 124.003865) (end 87.001156 123.993599) (width 0.1) (layer "In2.Cu") (net 194))
  (segment (start 95.35 124.7) (end 95.65 124.7) (width 0.1) (layer "In2.Cu") (net 194))
  (segment (start 87.982629 123.967796) (end 87.989934 123.975101) (width 0.1) (layer "In2.Cu") (net 194))
  (segment (start 95.8 124.55) (end 95.8 124.25) (width 0.1) (layer "In2.Cu") (net 194))
  (segment (start 87.446135 123.95773) (end 87.553865 123.95773) (width 0.1) (layer "In2.Cu") (net 194))
  (segment (start 86.778183 124.087651) (end 86.790096 124.106611) (width 0.1) (layer "In2.Cu") (net 194))
  (segment (start 87.553865 123.95773) (end 87.564131 123.958887) (width 0.1) (layer "In2.Cu") (net 194))
  (segment (start 94.920189 124.305544) (end 95.29142 123.934313) (width 0.1) (layer "In2.Cu") (net 194))
  (segment (start 95.446804 124.058227) (end 95.432842 124.075735) (width 0.1) (layer "In2.Cu") (net 194))
  (segment (start 87.6 124.003865) (end 87.6 124.24227) (width 0.1) (layer "In2.Cu") (net 194))
  (segment (start 87.153865 123.95773) (end 87.164131 123.958887) (width 0.1) (layer "In2.Cu") (net 194))
  (segment (start 87.2 124.24227) (end 87.202507 124.264522) (width 0.1) (layer "In2.Cu") (net 194))
  (segment (start 95.373327 123.905652) (end 95.395159 123.910635) (width 0.1) (layer "In2.Cu") (net 194))
  (segment (start 81.9 126.95) (end 81.5 126.55) (width 0.1) (layer "F.Cu") (net 195))
  (segment (start 93.2 126.95) (end 93.6 127.35) (width 0.1) (layer "F.Cu") (net 195))
  (via blind (at 93.2 126.95) (size 0.5) (drill 0.2) (layers "F.Cu" "In2.Cu") (net 195))
  (via (at 81.5 126.55) (size 0.5) (drill 0.2) (layers "F.Cu" "B.Cu") (net 195))
  (segment (start 82.770764 127.066718) (end 82.797184 127.057474) (width 0.1) (layer "In2.Cu") (net 195))
  (segment (start 82.486833 127.524317) (end 82.505383 127.535972) (width 0.1) (layer "In2.Cu") (net 195))
  (segment (start 89.475 126.95) (end 93.2 126.95) (width 0.1) (layer "In2.Cu") (net 195))
  (segment (start 81.984663 127.524317) (end 82.003213 127.535972) (width 0.1) (layer "In2.Cu") (net 195))
  (segment (start 82.452452 127.4696) (end 82.459688 127.490277) (width 0.1) (layer "In2.Cu") (net 195))
  (segment (start 81.945377 127.42606) (end 81.950282 127.4696) (width 0.1) (layer "In2.Cu") (net 195))
  (segment (start 82.459688 127.490277) (end 82.471343 127.508827) (width 0.1) (layer "In2.Cu") (net 195))
  (segment (start 82.02389 127.543208) (end 82.04566 127.545661) (width 0.1) (layer "In2.Cu") (net 195))
  (segment (start 83.047184 127.346866) (end 83.075 127.35) (width 0.1) (layer "In2.Cu") (net 195))
  (segment (start 82.1 127.545661) (end 82.121769 127.543208) (width 0.1) (layer "In2.Cu") (net 195))
  (segment (start 81.926486 127.386833) (end 81.938141 127.405383) (width 0.1) (layer "In2.Cu") (net 195))
  (segment (start 82.142446 127.535972) (end 82.160996 127.524317) (width 0.1) (layer "In2.Cu") (net 195))
  (segment (start 82.04566 127.545661) (end 82.1 127.545661) (width 0.1) (layer "In2.Cu") (net 195))
  (segment (start 82.946865 127.151524) (end 82.95 127.179339) (width 0.1) (layer "In2.Cu") (net 195))
  (segment (start 81.969173 127.508827) (end 81.984663 127.524317) (width 0.1) (layer "In2.Cu") (net 195))
  (segment (start 81.938141 127.405383) (end 81.945377 127.42606) (width 0.1) (layer "In2.Cu") (net 195))
  (segment (start 82.697547 127.4696) (end 82.7 127.447831) (width 0.1) (layer "In2.Cu") (net 195))
  (segment (start 82.747063 127.081611) (end 82.770764 127.066718) (width 0.1) (layer "In2.Cu") (net 195))
  (segment (start 81.892446 127.359688) (end 81.910996 127.371343) (width 0.1) (layer "In2.Cu") (net 195))
  (segment (start 82.227271 126.851403) (end 82.247063 126.831611) (width 0.1) (layer "In2.Cu") (net 195))
  (segment (start 82.977271 127.302937) (end 82.997063 127.322729) (width 0.1) (layer "In2.Cu") (net 195))
  (segment (start 81.910996 127.371343) (end 81.926486 127.386833) (width 0.1) (layer "In2.Cu") (net 195))
  (segment (start 83.020764 127.337622) (end 83.047184 127.346866) (width 0.1) (layer "In2.Cu") (net 195))
  (segment (start 82.270764 126.816718) (end 82.297184 126.807474) (width 0.1) (layer "In2.Cu") (net 195))
  (segment (start 82.203134 126.901524) (end 82.212378 126.875104) (width 0.1) (layer "In2.Cu") (net 195))
  (segment (start 82.7 127.447831) (end 82.7 127.179339) (width 0.1) (layer "In2.Cu") (net 195))
  (segment (start 82.19783 127.35) (end 82.2 127.35) (width 0.1) (layer "In2.Cu") (net 195))
  (segment (start 82.7 127.179339) (end 82.703134 127.151524) (width 0.1) (layer "In2.Cu") (net 195))
  (segment (start 82.52606 127.543208) (end 82.54783 127.545661) (width 0.1) (layer "In2.Cu") (net 195))
  (segment (start 82.712378 127.125104) (end 82.727271 127.101403) (width 0.1) (layer "In2.Cu") (net 195))
  (segment (start 82.176486 127.508827) (end 82.188141 127.490277) (width 0.1) (layer "In2.Cu") (net 195))
  (segment (start 82.003213 127.535972) (end 82.02389 127.543208) (width 0.1) (layer "In2.Cu") (net 195))
  (segment (start 81.950282 127.4696) (end 81.957518 127.490277) (width 0.1) (layer "In2.Cu") (net 195))
  (segment (start 82.297184 126.807474) (end 82.325 126.804339) (width 0.1) (layer "In2.Cu") (net 195))
  (segment (start 82.45 127.447831) (end 82.452452 127.4696) (width 0.1) (layer "In2.Cu") (net 195))
  (segment (start 82.45 126.929339) (end 82.45 127.447831) (width 0.1) (layer "In2.Cu") (net 195))
  (segment (start 82.623939 127.543208) (end 82.644616 127.535972) (width 0.1) (layer "In2.Cu") (net 195))
  (segment (start 82.663166 127.524317) (end 82.678656 127.508827) (width 0.1) (layer "In2.Cu") (net 195))
  (segment (start 82.852815 127.057474) (end 82.879235 127.066718) (width 0.1) (layer "In2.Cu") (net 195))
  (segment (start 81.5 126.55) (end 81.5 127.05) (width 0.1) (layer "In2.Cu") (net 195))
  (segment (start 82.422728 126.851403) (end 82.437621 126.875104) (width 0.1) (layer "In2.Cu") (net 195))
  (segment (start 82.437621 126.875104) (end 82.446865 126.901524) (width 0.1) (layer "In2.Cu") (net 195))
  (segment (start 82.446865 126.901524) (end 82.45 126.929339) (width 0.1) (layer "In2.Cu") (net 195))
  (segment (start 82.690311 127.490277) (end 82.697547 127.4696) (width 0.1) (layer "In2.Cu") (net 195))
  (segment (start 82.212378 126.875104) (end 82.227271 126.851403) (width 0.1) (layer "In2.Cu") (net 195))
  (segment (start 81.85 127.35) (end 81.871769 127.352452) (width 0.1) (layer "In2.Cu") (net 195))
  (segment (start 82.703134 127.151524) (end 82.712378 127.125104) (width 0.1) (layer "In2.Cu") (net 195))
  (segment (start 82.2 126.929339) (end 82.203134 126.901524) (width 0.1) (layer "In2.Cu") (net 195))
  (segment (start 89.075 127.35) (end 89.475 126.95) (width 0.1) (layer "In2.Cu") (net 195))
  (segment (start 82.997063 127.322729) (end 83.020764 127.337622) (width 0.1) (layer "In2.Cu") (net 195))
  (segment (start 82.54783 127.545661) (end 82.60217 127.545661) (width 0.1) (layer "In2.Cu") (net 195))
  (segment (start 82.352815 126.807474) (end 82.379235 126.816718) (width 0.1) (layer "In2.Cu") (net 195))
  (segment (start 81.8 127.35) (end 81.85 127.35) (width 0.1) (layer "In2.Cu") (net 195))
  (segment (start 82.325 126.804339) (end 82.352815 126.807474) (width 0.1) (layer "In2.Cu") (net 195))
  (segment (start 82.121769 127.543208) (end 82.142446 127.535972) (width 0.1) (layer "In2.Cu") (net 195))
  (segment (start 82.95 127.179339) (end 82.95 127.225) (width 0.1) (layer "In2.Cu") (net 195))
  (segment (start 82.505383 127.535972) (end 82.52606 127.543208) (width 0.1) (layer "In2.Cu") (net 195))
  (segment (start 82.379235 126.816718) (end 82.402936 126.831611) (width 0.1) (layer "In2.Cu") (net 195))
  (segment (start 81.5 127.05) (end 81.8 127.35) (width 0.1) (layer "In2.Cu") (net 195))
  (segment (start 82.2 127.35) (end 82.2 126.929339) (width 0.1) (layer "In2.Cu") (net 195))
  (segment (start 82.160996 127.524317) (end 82.176486 127.508827) (width 0.1) (layer "In2.Cu") (net 195))
  (segment (start 81.871769 127.352452) (end 81.892446 127.359688) (width 0.1) (layer "In2.Cu") (net 195))
  (segment (start 81.957518 127.490277) (end 81.969173 127.508827) (width 0.1) (layer "In2.Cu") (net 195))
  (segment (start 82.953134 127.252816) (end 82.962378 127.279236) (width 0.1) (layer "In2.Cu") (net 195))
  (segment (start 82.471343 127.508827) (end 82.486833 127.524317) (width 0.1) (layer "In2.Cu") (net 195))
  (segment (start 82.825 127.054339) (end 82.852815 127.057474) (width 0.1) (layer "In2.Cu") (net 195))
  (segment (start 83.075 127.35) (end 89.075 127.35) (width 0.1) (layer "In2.Cu") (net 195))
  (segment (start 82.879235 127.066718) (end 82.902936 127.081611) (width 0.1) (layer "In2.Cu") (net 195))
  (segment (start 82.19783 127.44783) (end 82.19783 127.35) (width 0.1) (layer "In2.Cu") (net 195))
  (segment (start 82.727271 127.101403) (end 82.747063 127.081611) (width 0.1) (layer "In2.Cu") (net 195))
  (segment (start 82.678656 127.508827) (end 82.690311 127.490277) (width 0.1) (layer "In2.Cu") (net 195))
  (segment (start 82.937621 127.125104) (end 82.946865 127.151524) (width 0.1) (layer "In2.Cu") (net 195))
  (segment (start 82.922728 127.101403) (end 82.937621 127.125104) (width 0.1) (layer "In2.Cu") (net 195))
  (segment (start 82.902936 127.081611) (end 82.922728 127.101403) (width 0.1) (layer "In2.Cu") (net 195))
  (segment (start 82.962378 127.279236) (end 82.977271 127.302937) (width 0.1) (layer "In2.Cu") (net 195))
  (segment (start 82.95 127.225) (end 82.953134 127.252816) (width 0.1) (layer "In2.Cu") (net 195))
  (segment (start 82.402936 126.831611) (end 82.422728 126.851403) (width 0.1) (layer "In2.Cu") (net 195))
  (segment (start 82.195377 127.4696) (end 82.19783 127.44783) (width 0.1) (layer "In2.Cu") (net 195))
  (segment (start 82.188141 127.490277) (end 82.195377 127.4696) (width 0.1) (layer "In2.Cu") (net 195))
  (segment (start 82.644616 127.535972) (end 82.663166 127.524317) (width 0.1) (layer "In2.Cu") (net 195))
  (segment (start 82.247063 126.831611) (end 82.270764 126.816718) (width 0.1) (layer "In2.Cu") (net 195))
  (segment (start 82.60217 127.545661) (end 82.623939 127.543208) (width 0.1) (layer "In2.Cu") (net 195))
  (segment (start 82.797184 127.057474) (end 82.825 127.054339) (width 0.1) (layer "In2.Cu") (net 195))
  (segment (start 96 125.75) (end 96.4 125.35) (width 0.1) (layer "F.Cu") (net 196))
  (segment (start 84.25 125.9) (end 84.5 126.15) (width 0.1) (layer "F.Cu") (net 196))
  (segment (start 84.5 126.15) (end 85.1 126.15) (width 0.1) (layer "F.Cu") (net 196))
  (segment (start 84.25 124.55) (end 84.25 125.9) (width 0.1) (layer "F.Cu") (net 196))
  (via blind (at 96.4 125.35) (size 0.5) (drill 0.2) (layers "F.Cu" "In2.Cu") (net 196))
  (via blind (at 84.25 124.55) (size 0.5) (drill 0.2) (layers "F.Cu" "In2.Cu") (net 196))
  (segment (start 95.25 125) (end 96.05 125) (width 0.1) (layer "In2.Cu") (net 196))
  (segment (start 88.675 124.25) (end 94.5 124.25) (width 0.1) (layer "In2.Cu") (net 196))
  (segment (start 84.25 124.55) (end 88.375 124.55) (width 0.1) (layer "In2.Cu") (net 196))
  (segment (start 94.5 124.25) (end 95.25 125) (width 0.1) (layer "In2.Cu") (net 196))
  (segment (start 96.05 125) (end 96.4 125.35) (width 0.1) (layer "In2.Cu") (net 196))
  (segment (start 88.375 124.55) (end 88.675 124.25) (width 0.1) (layer "In2.Cu") (net 196))
  (segment (start 109.175001 100.775001) (end 109.175001 104.874999) (width 0.15) (layer "F.Cu") (net 197))
  (segment (start 108.45 100.05) (end 109.175001 100.775001) (width 0.15) (layer "F.Cu") (net 197))
  (segment (start 108.45 99.45) (end 108.45 100.05) (width 0.15) (layer "F.Cu") (net 197))
  (segment (start 105.8 98.7) (end 106.627149 98.7) (width 0.15) (layer "F.Cu") (net 197))
  (segment (start 109.175001 104.874999) (end 106.4 107.65) (width 0.15) (layer "F.Cu") (net 197))
  (segment (start 107.6 99.46) (end 108.49 99.46) (width 0.15) (layer "F.Cu") (net 197))
  (segment (start 106.4 107.65) (end 106.4 108.15) (width 0.15) (layer "F.Cu") (net 197))
  (via (at 105.8 98.7) (size 0.5) (drill 0.2) (layers "F.Cu" "B.Cu") (net 197))
  (via (at 107.6 99.46) (size 0.5) (drill 0.2) (layers "F.Cu" "B.Cu") (net 197))
  (segment (start 107.16 99.46) (end 107.6 99.46) (width 0.15) (layer "B.Cu") (net 197))
  (segment (start 105.8 98.7) (end 106.4 98.7) (width 0.15) (layer "B.Cu") (net 197))
  (segment (start 106.4 98.7) (end 107.16 99.46) (width 0.15) (layer "B.Cu") (net 197))
  (segment (start 98.322851 97.177149) (end 97.5 98) (width 0.15) (layer "F.Cu") (net 198))
  (segment (start 97.6 107.35) (end 97.5 107.25) (width 0.15) (layer "F.Cu") (net 198))
  (segment (start 97.6 108.15) (end 97.6 107.35) (width 0.15) (layer "F.Cu") (net 198))
  (segment (start 99.772851 97.177149) (end 98.322851 97.177149) (width 0.15) (layer "F.Cu") (net 198))
  (segment (start 97.5 98) (end 97.5 99.55) (width 0.15) (layer "F.Cu") (net 198))
  (via (at 97.5 107.25) (size 0.5) (drill 0.2) (layers "F.Cu" "B.Cu") (net 198))
  (via (at 97.5 99.55) (size 0.5) (drill 0.2) (layers "F.Cu" "B.Cu") (net 198))
  (segment (start 97.066275 100.365082) (end 97.084146 100.393523) (width 0.15) (layer "In2.Cu") (net 198))
  (segment (start 97.051421 100.3) (end 97.055181 100.333378) (width 0.15) (layer "In2.Cu") (net 198))
  (segment (start 97.084146 102.006476) (end 97.066275 102.034917) (width 0.15) (layer "In2.Cu") (net 198))
  (segment (start 97.055181 100.333378) (end 97.066275 100.365082) (width 0.15) (layer "In2.Cu") (net 198))
  (segment (start 97.107897 101.382725) (end 97.084146 101.406476) (width 0.15) (layer "In2.Cu") (net 198))
  (segment (start 97.051421 100.9) (end 97.055181 100.933378) (width 0.15) (layer "In2.Cu") (net 198))
  (segment (start 97.892103 101.082725) (end 97.915854 101.106476) (width 0.15) (layer "In2.Cu") (net 198))
  (segment (start 97.863662 100.735145) (end 97.831958 100.746239) (width 0.15) (layer "In2.Cu") (net 198))
  (segment (start 97.863662 100.464854) (end 97.892103 100.482725) (width 0.15) (layer "In2.Cu") (net 198))
  (segment (start 97.066275 102.034917) (end 97.055181 102.066621) (width 0.15) (layer "In2.Cu") (net 198))
  (segment (start 97.944819 100.566621) (end 97.948579 100.6) (width 0.15) (layer "In2.Cu") (net 198))
  (segment (start 97.055181 100.266621) (end 97.051421 100.3) (width 0.15) (layer "In2.Cu") (net 198))
  (segment (start 97.066275 100.234917) (end 97.055181 100.266621) (width 0.15) (layer "In2.Cu") (net 198))
  (segment (start 97.136338 100.764854) (end 97.107897 100.782725) (width 0.15) (layer "In2.Cu") (net 198))
  (segment (start 97.831958 101.346239) (end 97.798579 101.35) (width 0.15) (layer "In2.Cu") (net 198))
  (segment (start 97.467274 102.306476) (end 97.485145 102.334917) (width 0.15) (layer "In2.Cu") (net 198))
  (segment (start 97.168042 100.446239) (end 97.201421 100.45) (width 0.15) (layer "In2.Cu") (net 198))
  (segment (start 97.915854 101.106476) (end 97.933725 101.134917) (width 0.15) (layer "In2.Cu") (net 198))
  (segment (start 97.798579 101.95) (end 97.201421 101.95) (width 0.15) (layer "In2.Cu") (net 198))
  (segment (start 97.066275 101.565082) (end 97.084146 101.593523) (width 0.15) (layer "In2.Cu") (net 198))
  (segment (start 97.383378 100.146239) (end 97.35 100.15) (width 0.15) (layer "In2.Cu") (net 198))
  (segment (start 97.107897 100.417274) (end 97.136338 100.435145) (width 0.15) (layer "In2.Cu") (net 198))
  (segment (start 97.892103 101.917274) (end 97.863662 101.935145) (width 0.15) (layer "In2.Cu") (net 198))
  (segment (start 97.084146 100.393523) (end 97.107897 100.417274) (width 0.15) (layer "In2.Cu") (net 198))
  (segment (start 97.136338 101.364854) (end 97.107897 101.382725) (width 0.15) (layer "In2.Cu") (net 198))
  (segment (start 97.168042 101.046239) (end 97.201421 101.05) (width 0.15) (layer "In2.Cu") (net 198))
  (segment (start 97.136338 101.964854) (end 97.107897 101.982725) (width 0.15) (layer "In2.Cu") (net 198))
  (segment (start 97.5 102.4) (end 97.5 107.25) (width 0.15) (layer "In2.Cu") (net 198))
  (segment (start 97.798579 101.65) (end 97.831958 101.65376) (width 0.15) (layer "In2.Cu") (net 198))
  (segment (start 97.201421 101.65) (end 97.798579 101.65) (width 0.15) (layer "In2.Cu") (net 198))
  (segment (start 97.863662 101.664854) (end 97.892103 101.682725) (width 0.15) (layer "In2.Cu") (net 198))
  (segment (start 97.066275 102.165082) (end 97.084146 102.193523) (width 0.15) (layer "In2.Cu") (net 198))
  (segment (start 97.915854 101.893523) (end 97.892103 101.917274) (width 0.15) (layer "In2.Cu") (net 198))
  (segment (start 97.168042 100.15376) (end 97.136338 100.164854) (width 0.15) (layer "In2.Cu") (net 198))
  (segment (start 97.084146 101.593523) (end 97.107897 101.617274) (width 0.15) (layer "In2.Cu") (net 198))
  (segment (start 97.944819 101.166621) (end 97.948579 101.2) (width 0.15) (layer "In2.Cu") (net 198))
  (segment (start 97.084146 100.993523) (end 97.107897 101.017274) (width 0.15) (layer "In2.Cu") (net 198))
  (segment (start 97.055181 101.533378) (end 97.066275 101.565082) (width 0.15) (layer "In2.Cu") (net 198))
  (segment (start 97.168042 101.646239) (end 97.201421 101.65) (width 0.15) (layer "In2.Cu") (net 198))
  (segment (start 97.107897 101.617274) (end 97.136338 101.635145) (width 0.15) (layer "In2.Cu") (net 198))
  (segment (start 97.944819 101.766621) (end 97.948579 101.8) (width 0.15) (layer "In2.Cu") (net 198))
  (segment (start 97.944819 101.233378) (end 97.933725 101.265082) (width 0.15) (layer "In2.Cu") (net 198))
  (segment (start 97.443523 102.282725) (end 97.467274 102.306476) (width 0.15) (layer "In2.Cu") (net 198))
  (segment (start 97.051421 102.1) (end 97.055181 102.133378) (width 0.15) (layer "In2.Cu") (net 198))
  (segment (start 97.443523 100.117274) (end 97.415082 100.135145) (width 0.15) (layer "In2.Cu") (net 198))
  (segment (start 97.201421 100.15) (end 97.168042 100.15376) (width 0.15) (layer "In2.Cu") (net 198))
  (segment (start 97.201421 100.75) (end 97.168042 100.75376) (width 0.15) (layer "In2.Cu") (net 198))
  (segment (start 97.831958 101.05376) (end 97.863662 101.064854) (width 0.15) (layer "In2.Cu") (net 198))
  (segment (start 97.168042 101.95376) (end 97.136338 101.964854) (width 0.15) (layer "In2.Cu") (net 198))
  (segment (start 97.933725 101.734917) (end 97.944819 101.766621) (width 0.15) (layer "In2.Cu") (net 198))
  (segment (start 97.055181 100.866621) (end 97.051421 100.9) (width 0.15) (layer "In2.Cu") (net 198))
  (segment (start 97.831958 101.946239) (end 97.798579 101.95) (width 0.15) (layer "In2.Cu") (net 198))
  (segment (start 97.35 102.25) (end 97.383378 102.25376) (width 0.15) (layer "In2.Cu") (net 198))
  (segment (start 97.084146 100.806476) (end 97.066275 100.834917) (width 0.15) (layer "In2.Cu") (net 198))
  (segment (start 97.051421 101.5) (end 97.055181 101.533378) (width 0.15) (layer "In2.Cu") (net 198))
  (segment (start 97.944819 101.833378) (end 97.933725 101.865082) (width 0.15) (layer "In2.Cu") (net 198))
  (segment (start 97.107897 101.982725) (end 97.084146 102.006476) (width 0.15) (layer "In2.Cu") (net 198))
  (segment (start 97.915854 100.693523) (end 97.892103 100.717274) (width 0.15) (layer "In2.Cu") (net 198))
  (segment (start 97.933725 101.865082) (end 97.915854 101.893523) (width 0.15) (layer "In2.Cu") (net 198))
  (segment (start 97.933725 101.265082) (end 97.915854 101.293523) (width 0.15) (layer "In2.Cu") (net 198))
  (segment (start 97.915854 101.293523) (end 97.892103 101.317274) (width 0.15) (layer "In2.Cu") (net 198))
  (segment (start 97.496239 102.366621) (end 97.5 102.4) (width 0.15) (layer "In2.Cu") (net 198))
  (segment (start 97.485145 100.065082) (end 97.467274 100.093523) (width 0.15) (layer "In2.Cu") (net 198))
  (segment (start 97.915854 101.706476) (end 97.933725 101.734917) (width 0.15) (layer "In2.Cu") (net 198))
  (segment (start 97.201421 102.25) (end 97.35 102.25) (width 0.15) (layer "In2.Cu") (net 198))
  (segment (start 97.055181 102.066621) (end 97.051421 102.1) (width 0.15) (layer "In2.Cu") (net 198))
  (segment (start 97.933725 100.665082) (end 97.915854 100.693523) (width 0.15) (layer "In2.Cu") (net 198))
  (segment (start 97.892103 100.482725) (end 97.915854 100.506476) (width 0.15) (layer "In2.Cu") (net 198))
  (segment (start 97.415082 100.135145) (end 97.383378 100.146239) (width 0.15) (layer "In2.Cu") (net 198))
  (segment (start 97.35 100.15) (end 97.201421 100.15) (width 0.15) (layer "In2.Cu") (net 198))
  (segment (start 97.485145 102.334917) (end 97.496239 102.366621) (width 0.15) (layer "In2.Cu") (net 198))
  (segment (start 97.944819 100.633378) (end 97.933725 100.665082) (width 0.15) (layer "In2.Cu") (net 198))
  (segment (start 97.948579 101.8) (end 97.944819 101.833378) (width 0.15) (layer "In2.Cu") (net 198))
  (segment (start 97.5 99.55) (end 97.5 100) (width 0.15) (layer "In2.Cu") (net 198))
  (segment (start 97.892103 101.317274) (end 97.863662 101.335145) (width 0.15) (layer "In2.Cu") (net 198))
  (segment (start 97.107897 100.182725) (end 97.084146 100.206476) (width 0.15) (layer "In2.Cu") (net 198))
  (segment (start 97.168042 102.246239) (end 97.201421 102.25) (width 0.15) (layer "In2.Cu") (net 198))
  (segment (start 97.915854 100.506476) (end 97.933725 100.534917) (width 0.15) (layer "In2.Cu") (net 198))
  (segment (start 97.798579 100.45) (end 97.831958 100.45376) (width 0.15) (layer "In2.Cu") (net 198))
  (segment (start 97.136338 100.435145) (end 97.168042 100.446239) (width 0.15) (layer "In2.Cu") (net 198))
  (segment (start 97.863662 101.335145) (end 97.831958 101.346239) (width 0.15) (layer "In2.Cu") (net 198))
  (segment (start 97.084146 100.206476) (end 97.066275 100.234917) (width 0.15) (layer "In2.Cu") (net 198))
  (segment (start 97.892103 101.682725) (end 97.915854 101.706476) (width 0.15) (layer "In2.Cu") (net 198))
  (segment (start 97.5 100) (end 97.496239 100.033378) (width 0.15) (layer "In2.Cu") (net 198))
  (segment (start 97.168042 100.75376) (end 97.136338 100.764854) (width 0.15) (layer "In2.Cu") (net 198))
  (segment (start 97.201421 101.95) (end 97.168042 101.95376) (width 0.15) (layer "In2.Cu") (net 198))
  (segment (start 97.933725 100.534917) (end 97.944819 100.566621) (width 0.15) (layer "In2.Cu") (net 198))
  (segment (start 97.948579 100.6) (end 97.944819 100.633378) (width 0.15) (layer "In2.Cu") (net 198))
  (segment (start 97.496239 100.033378) (end 97.485145 100.065082) (width 0.15) (layer "In2.Cu") (net 198))
  (segment (start 97.084146 101.406476) (end 97.066275 101.434917) (width 0.15) (layer "In2.Cu") (net 198))
  (segment (start 97.136338 100.164854) (end 97.107897 100.182725) (width 0.15) (layer "In2.Cu") (net 198))
  (segment (start 97.948579 101.2) (end 97.944819 101.233378) (width 0.15) (layer "In2.Cu") (net 198))
  (segment (start 97.107897 102.217274) (end 97.136338 102.235145) (width 0.15) (layer "In2.Cu") (net 198))
  (segment (start 97.066275 100.965082) (end 97.084146 100.993523) (width 0.15) (layer "In2.Cu") (net 198))
  (segment (start 97.136338 101.035145) (end 97.168042 101.046239) (width 0.15) (layer "In2.Cu") (net 198))
  (segment (start 97.831958 100.45376) (end 97.863662 100.464854) (width 0.15) (layer "In2.Cu") (net 198))
  (segment (start 97.136338 102.235145) (end 97.168042 102.246239) (width 0.15) (layer "In2.Cu") (net 198))
  (segment (start 97.168042 101.35376) (end 97.136338 101.364854) (width 0.15) (layer "In2.Cu") (net 198))
  (segment (start 97.055181 100.933378) (end 97.066275 100.965082) (width 0.15) (layer "In2.Cu") (net 198))
  (segment (start 97.831958 100.746239) (end 97.798579 100.75) (width 0.15) (layer "In2.Cu") (net 198))
  (segment (start 97.892103 100.717274) (end 97.863662 100.735145) (width 0.15) (layer "In2.Cu") (net 198))
  (segment (start 97.383378 102.25376) (end 97.415082 102.264854) (width 0.15) (layer "In2.Cu") (net 198))
  (segment (start 97.798579 100.75) (end 97.201421 100.75) (width 0.15) (layer "In2.Cu") (net 198))
  (segment (start 97.467274 100.093523) (end 97.443523 100.117274) (width 0.15) (layer "In2.Cu") (net 198))
  (segment (start 97.066275 100.834917) (end 97.055181 100.866621) (width 0.15) (layer "In2.Cu") (net 198))
  (segment (start 97.107897 100.782725) (end 97.084146 100.806476) (width 0.15) (layer "In2.Cu") (net 198))
  (segment (start 97.415082 102.264854) (end 97.443523 102.282725) (width 0.15) (layer "In2.Cu") (net 198))
  (segment (start 97.863662 101.935145) (end 97.831958 101.946239) (width 0.15) (layer "In2.Cu") (net 198))
  (segment (start 97.084146 102.193523) (end 97.107897 102.217274) (width 0.15) (layer "In2.Cu") (net 198))
  (segment (start 97.201421 101.35) (end 97.168042 101.35376) (width 0.15) (layer "In2.Cu") (net 198))
  (segment (start 97.831958 101.65376) (end 97.863662 101.664854) (width 0.15) (layer "In2.Cu") (net 198))
  (segment (start 97.107897 101.017274) (end 97.136338 101.035145) (width 0.15) (layer "In2.Cu") (net 198))
  (segment (start 97.066275 101.434917) (end 97.055181 101.466621) (width 0.15) (layer "In2.Cu") (net 198))
  (segment (start 97.201421 100.45) (end 97.798579 100.45) (width 0.15) (layer "In2.Cu") (net 198))
  (segment (start 97.201421 101.05) (end 97.798579 101.05) (width 0.15) (layer "In2.Cu") (net 198))
  (segment (start 97.055181 101.466621) (end 97.051421 101.5) (width 0.15) (layer "In2.Cu") (net 198))
  (segment (start 97.136338 101.635145) (end 97.168042 101.646239) (width 0.15) (layer "In2.Cu") (net 198))
  (segment (start 97.798579 101.35) (end 97.201421 101.35) (width 0.15) (layer "In2.Cu") (net 198))
  (segment (start 97.798579 101.05) (end 97.831958 101.05376) (width 0.15) (layer "In2.Cu") (net 198))
  (segment (start 97.055181 102.133378) (end 97.066275 102.165082) (width 0.15) (layer "In2.Cu") (net 198))
  (segment (start 97.863662 101.064854) (end 97.892103 101.082725) (width 0.15) (layer "In2.Cu") (net 198))
  (segment (start 97.933725 101.134917) (end 97.944819 101.166621) (width 0.15) (layer "In2.Cu") (net 198))
  (segment (start 98 107.5) (end 98.25 107.25) (width 0.15) (layer "F.Cu") (net 199))
  (segment (start 97.6 108.95) (end 98 108.55) (width 0.15) (layer "F.Cu") (net 199))
  (segment (start 98.55 97.7) (end 98.25 98) (width 0.15) (layer "F.Cu") (net 199))
  (segment (start 99.772851 97.7) (end 98.55 97.7) (width 0.15) (layer "F.Cu") (net 199))
  (segment (start 98 108.55) (end 98 107.5) (width 0.15) (layer "F.Cu") (net 199))
  (segment (start 98.25 98) (end 98.25 99.55) (width 0.15) (layer "F.Cu") (net 199))
  (via (at 98.25 107.25) (size 0.5) (drill 0.2) (layers "F.Cu" "B.Cu") (net 199))
  (via (at 98.25 99.55) (size 0.5) (drill 0.2) (layers "F.Cu" "B.Cu") (net 199))
  (segment (start 98.610919 102.689854) (end 98.579215 102.67876) (width 0.15) (layer "In2.Cu") (net 199))
  (segment (start 98.264854 102.590082) (end 98.25376 102.558378) (width 0.15) (layer "In2.Cu") (net 199))
  (segment (start 97.836889 104.231476) (end 97.86064 104.207725) (width 0.15) (layer "In2.Cu") (net 199))
  (segment (start 97.86064 103.007725) (end 97.889081 102.989854) (width 0.15) (layer "In2.Cu") (net 199))
  (segment (start 98.25376 102.558378) (end 98.25 102.525) (width 0.15) (layer "In2.Cu") (net 199))
  (segment (start 97.889081 104.189854) (end 97.920785 104.17876) (width 0.15) (layer "In2.Cu") (net 199))
  (segment (start 97.836889 104.418523) (end 97.819018 104.390082) (width 0.15) (layer "In2.Cu") (net 199))
  (segment (start 97.920785 103.271239) (end 97.889081 103.260145) (width 0.15) (layer "In2.Cu") (net 199))
  (segment (start 98.680982 102.890082) (end 98.692076 102.858378) (width 0.15) (layer "In2.Cu") (net 199))
  (segment (start 98.25 107.25) (end 98.25 104.925) (width 0.15) (layer "In2.Cu") (net 199))
  (segment (start 98.610919 103.289854) (end 98.579215 103.27876) (width 0.15) (layer "In2.Cu") (net 199))
  (segment (start 97.807924 103.091621) (end 97.819018 103.059917) (width 0.15) (layer "In2.Cu") (net 199))
  (segment (start 97.920785 104.471239) (end 97.889081 104.460145) (width 0.15) (layer "In2.Cu") (net 199))
  (segment (start 98.579215 103.87876) (end 98.545837 103.875) (width 0.15) (layer "In2.Cu") (net 199))
  (segment (start 98.579215 102.971239) (end 98.610919 102.960145) (width 0.15) (layer "In2.Cu") (net 199))
  (segment (start 98.692076 102.791621) (end 98.680982 102.759917) (width 0.15) (layer "In2.Cu") (net 199))
  (segment (start 98.545837 102.975) (end 98.579215 102.971239) (width 0.15) (layer "In2.Cu") (net 199))
  (segment (start 97.889081 104.460145) (end 97.86064 104.442274) (width 0.15) (layer "In2.Cu") (net 199))
  (segment (start 97.954163 102.975) (end 98.545837 102.975) (width 0.15) (layer "In2.Cu") (net 199))
  (segment (start 98.63936 103.307725) (end 98.610919 103.289854) (width 0.15) (layer "In2.Cu") (net 199))
  (segment (start 98.282725 104.831476) (end 98.306476 104.807725) (width 0.15) (layer "In2.Cu") (net 199))
  (segment (start 97.954163 103.875) (end 97.920785 103.871239) (width 0.15) (layer "In2.Cu") (net 199))
  (segment (start 97.920785 103.871239) (end 97.889081 103.860145) (width 0.15) (layer "In2.Cu") (net 199))
  (segment (start 98.692076 102.858378) (end 98.695837 102.825) (width 0.15) (layer "In2.Cu") (net 199))
  (segment (start 97.86064 103.242274) (end 97.836889 103.218523) (width 0.15) (layer "In2.Cu") (net 199))
  (segment (start 98.663111 104.118523) (end 98.680982 104.090082) (width 0.15) (layer "In2.Cu") (net 199))
  (segment (start 97.804163 103.725) (end 97.807924 103.691621) (width 0.15) (layer "In2.Cu") (net 199))
  (segment (start 97.920785 102.97876) (end 97.954163 102.975) (width 0.15) (layer "In2.Cu") (net 199))
  (segment (start 98.545837 104.475) (end 97.954163 104.475) (width 0.15) (layer "In2.Cu") (net 199))
  (segment (start 98.25 102.525) (end 98.25 99.55) (width 0.15) (layer "In2.Cu") (net 199))
  (segment (start 97.86064 103.607725) (end 97.889081 103.589854) (width 0.15) (layer "In2.Cu") (net 199))
  (segment (start 98.579215 102.67876) (end 98.545837 102.675) (width 0.15) (layer "In2.Cu") (net 199))
  (segment (start 97.807924 104.358378) (end 97.804163 104.325) (width 0.15) (layer "In2.Cu") (net 199))
  (segment (start 98.692076 104.058378) (end 98.695837 104.025) (width 0.15) (layer "In2.Cu") (net 199))
  (segment (start 98.306476 104.807725) (end 98.334917 104.789854) (width 0.15) (layer "In2.Cu") (net 199))
  (segment (start 98.306476 102.642274) (end 98.282725 102.618523) (width 0.15) (layer "In2.Cu") (net 199))
  (segment (start 98.692076 103.391621) (end 98.680982 103.359917) (width 0.15) (layer "In2.Cu") (net 199))
  (segment (start 97.86064 104.442274) (end 97.836889 104.418523) (width 0.15) (layer "In2.Cu") (net 199))
  (segment (start 98.610919 103.889854) (end 98.579215 103.87876) (width 0.15) (layer "In2.Cu") (net 199))
  (segment (start 98.610919 104.489854) (end 98.579215 104.47876) (width 0.15) (layer "In2.Cu") (net 199))
  (segment (start 98.692076 103.458378) (end 98.695837 103.425) (width 0.15) (layer "In2.Cu") (net 199))
  (segment (start 97.819018 104.259917) (end 97.836889 104.231476) (width 0.15) (layer "In2.Cu") (net 199))
  (segment (start 98.366621 102.671239) (end 98.334917 102.660145) (width 0.15) (layer "In2.Cu") (net 199))
  (segment (start 98.663111 103.931476) (end 98.63936 103.907725) (width 0.15) (layer "In2.Cu") (net 199))
  (segment (start 97.86064 103.842274) (end 97.836889 103.818523) (width 0.15) (layer "In2.Cu") (net 199))
  (segment (start 98.680982 104.559917) (end 98.663111 104.531476) (width 0.15) (layer "In2.Cu") (net 199))
  (segment (start 98.610919 104.760145) (end 98.63936 104.742274) (width 0.15) (layer "In2.Cu") (net 199))
  (segment (start 97.889081 103.260145) (end 97.86064 103.242274) (width 0.15) (layer "In2.Cu") (net 199))
  (segment (start 98.545837 104.175) (end 98.579215 104.171239) (width 0.15) (layer "In2.Cu") (net 199))
  (segment (start 97.819018 103.059917) (end 97.836889 103.031476) (width 0.15) (layer "In2.Cu") (net 199))
  (segment (start 98.663111 103.331476) (end 98.63936 103.307725) (width 0.15) (layer "In2.Cu") (net 199))
  (segment (start 98.579215 103.571239) (end 98.610919 103.560145) (width 0.15) (layer "In2.Cu") (net 199))
  (segment (start 98.663111 102.918523) (end 98.680982 102.890082) (width 0.15) (layer "In2.Cu") (net 199))
  (segment (start 98.680982 103.490082) (end 98.692076 103.458378) (width 0.15) (layer "In2.Cu") (net 199))
  (segment (start 98.680982 104.090082) (end 98.692076 104.058378) (width 0.15) (layer "In2.Cu") (net 199))
  (segment (start 97.804163 104.325) (end 97.807924 104.291621) (width 0.15) (layer "In2.Cu") (net 199))
  (segment (start 98.579215 104.171239) (end 98.610919 104.160145) (width 0.15) (layer "In2.Cu") (net 199))
  (segment (start 97.86064 104.207725) (end 97.889081 104.189854) (width 0.15) (layer "In2.Cu") (net 199))
  (segment (start 98.695837 104.625) (end 98.692076 104.591621) (width 0.15) (layer "In2.Cu") (net 199))
  (segment (start 98.63936 103.907725) (end 98.610919 103.889854) (width 0.15) (layer "In2.Cu") (net 199))
  (segment (start 98.4 104.775) (end 98.545837 104.775) (width 0.15) (layer "In2.Cu") (net 199))
  (segment (start 98.692076 104.591621) (end 98.680982 104.559917) (width 0.15) (layer "In2.Cu") (net 199))
  (segment (start 97.819018 103.659917) (end 97.836889 103.631476) (width 0.15) (layer "In2.Cu") (net 199))
  (segment (start 97.807924 103.758378) (end 97.804163 103.725) (width 0.15) (layer "In2.Cu") (net 199))
  (segment (start 98.680982 102.759917) (end 98.663111 102.731476) (width 0.15) (layer "In2.Cu") (net 199))
  (segment (start 98.663111 103.518523) (end 98.680982 103.490082) (width 0.15) (layer "In2.Cu") (net 199))
  (segment (start 97.819018 103.790082) (end 97.807924 103.758378) (width 0.15) (layer "In2.Cu") (net 199))
  (segment (start 98.680982 103.959917) (end 98.663111 103.931476) (width 0.15) (layer "In2.Cu") (net 199))
  (segment (start 97.889081 103.589854) (end 97.920785 103.57876) (width 0.15) (layer "In2.Cu") (net 199))
  (segment (start 98.63936 104.742274) (end 98.663111 104.718523) (width 0.15) (layer "In2.Cu") (net 199))
  (segment (start 98.545837 103.575) (end 98.579215 103.571239) (width 0.15) (layer "In2.Cu") (net 199))
  (segment (start 97.807924 103.691621) (end 97.819018 103.659917) (width 0.15) (layer "In2.Cu") (net 199))
  (segment (start 98.63936 103.542274) (end 98.663111 103.518523) (width 0.15) (layer "In2.Cu") (net 199))
  (segment (start 98.25 104.925) (end 98.25376 104.891621) (width 0.15) (layer "In2.Cu") (net 199))
  (segment (start 98.695837 104.025) (end 98.692076 103.991621) (width 0.15) (layer "In2.Cu") (net 199))
  (segment (start 98.610919 104.160145) (end 98.63936 104.142274) (width 0.15) (layer "In2.Cu") (net 199))
  (segment (start 98.334917 104.789854) (end 98.366621 104.77876) (width 0.15) (layer "In2.Cu") (net 199))
  (segment (start 97.836889 103.818523) (end 97.819018 103.790082) (width 0.15) (layer "In2.Cu") (net 199))
  (segment (start 97.807924 104.291621) (end 97.819018 104.259917) (width 0.15) (layer "In2.Cu") (net 199))
  (segment (start 97.954163 103.275) (end 97.920785 103.271239) (width 0.15) (layer "In2.Cu") (net 199))
  (segment (start 98.63936 104.142274) (end 98.663111 104.118523) (width 0.15) (layer "In2.Cu") (net 199))
  (segment (start 98.692076 104.658378) (end 98.695837 104.625) (width 0.15) (layer "In2.Cu") (net 199))
  (segment (start 98.610919 103.560145) (end 98.63936 103.542274) (width 0.15) (layer "In2.Cu") (net 199))
  (segment (start 98.545837 104.775) (end 98.579215 104.771239) (width 0.15) (layer "In2.Cu") (net 199))
  (segment (start 97.836889 103.218523) (end 97.819018 103.190082) (width 0.15) (layer "In2.Cu") (net 199))
  (segment (start 98.663111 104.531476) (end 98.63936 104.507725) (width 0.15) (layer "In2.Cu") (net 199))
  (segment (start 98.25376 104.891621) (end 98.264854 104.859917) (width 0.15) (layer "In2.Cu") (net 199))
  (segment (start 97.836889 103.631476) (end 97.86064 103.607725) (width 0.15) (layer "In2.Cu") (net 199))
  (segment (start 97.920785 103.57876) (end 97.954163 103.575) (width 0.15) (layer "In2.Cu") (net 199))
  (segment (start 98.545837 103.275) (end 97.954163 103.275) (width 0.15) (layer "In2.Cu") (net 199))
  (segment (start 98.63936 102.707725) (end 98.610919 102.689854) (width 0.15) (layer "In2.Cu") (net 199))
  (segment (start 98.63936 104.507725) (end 98.610919 104.489854) (width 0.15) (layer "In2.Cu") (net 199))
  (segment (start 97.954163 104.175) (end 98.545837 104.175) (width 0.15) (layer "In2.Cu") (net 199))
  (segment (start 98.545837 102.675) (end 98.4 102.675) (width 0.15) (layer "In2.Cu") (net 199))
  (segment (start 97.954163 103.575) (end 98.545837 103.575) (width 0.15) (layer "In2.Cu") (net 199))
  (segment (start 97.889081 102.989854) (end 97.920785 102.97876) (width 0.15) (layer "In2.Cu") (net 199))
  (segment (start 97.807924 103.158378) (end 97.804163 103.125) (width 0.15) (layer "In2.Cu") (net 199))
  (segment (start 98.579215 104.47876) (end 98.545837 104.475) (width 0.15) (layer "In2.Cu") (net 199))
  (segment (start 98.545837 103.875) (end 97.954163 103.875) (width 0.15) (layer "In2.Cu") (net 199))
  (segment (start 98.366621 104.77876) (end 98.4 104.775) (width 0.15) (layer "In2.Cu") (net 199))
  (segment (start 98.4 102.675) (end 98.366621 102.671239) (width 0.15) (layer "In2.Cu") (net 199))
  (segment (start 97.819018 103.190082) (end 97.807924 103.158378) (width 0.15) (layer "In2.Cu") (net 199))
  (segment (start 98.282725 102.618523) (end 98.264854 102.590082) (width 0.15) (layer "In2.Cu") (net 199))
  (segment (start 97.920785 104.17876) (end 97.954163 104.175) (width 0.15) (layer "In2.Cu") (net 199))
  (segment (start 97.804163 103.125) (end 97.807924 103.091621) (width 0.15) (layer "In2.Cu") (net 199))
  (segment (start 98.695837 102.825) (end 98.692076 102.791621) (width 0.15) (layer "In2.Cu") (net 199))
  (segment (start 98.610919 102.960145) (end 98.63936 102.942274) (width 0.15) (layer "In2.Cu") (net 199))
  (segment (start 97.819018 104.390082) (end 97.807924 104.358378) (width 0.15) (layer "In2.Cu") (net 199))
  (segment (start 97.889081 103.860145) (end 97.86064 103.842274) (width 0.15) (layer "In2.Cu") (net 199))
  (segment (start 98.663111 102.731476) (end 98.63936 102.707725) (width 0.15) (layer "In2.Cu") (net 199))
  (segment (start 98.63936 102.942274) (end 98.663111 102.918523) (width 0.15) (layer "In2.Cu") (net 199))
  (segment (start 97.836889 103.031476) (end 97.86064 103.007725) (width 0.15) (layer "In2.Cu") (net 199))
  (segment (start 98.663111 104.718523) (end 98.680982 104.690082) (width 0.15) (layer "In2.Cu") (net 199))
  (segment (start 98.695837 103.425) (end 98.692076 103.391621) (width 0.15) (layer "In2.Cu") (net 199))
  (segment (start 98.692076 103.991621) (end 98.680982 103.959917) (width 0.15) (layer "In2.Cu") (net 199))
  (segment (start 98.680982 103.359917) (end 98.663111 103.331476) (width 0.15) (layer "In2.Cu") (net 199))
  (segment (start 98.680982 104.690082) (end 98.692076 104.658378) (width 0.15) (layer "In2.Cu") (net 199))
  (segment (start 98.264854 104.859917) (end 98.282725 104.831476) (width 0.15) (layer "In2.Cu") (net 199))
  (segment (start 98.334917 102.660145) (end 98.306476 102.642274) (width 0.15) (layer "In2.Cu") (net 199))
  (segment (start 97.954163 104.475) (end 97.920785 104.471239) (width 0.15) (layer "In2.Cu") (net 199))
  (segment (start 98.579215 104.771239) (end 98.610919 104.760145) (width 0.15) (layer "In2.Cu") (net 199))
  (segment (start 98.579215 103.27876) (end 98.545837 103.275) (width 0.15) (layer "In2.Cu") (net 199))
  (segment (start 104.8 109.75) (end 104.4 109.35) (width 0.15) (layer "F.Cu") (net 200))
  (segment (start 99.772851 99.2) (end 99.772851 99.977851) (width 0.15) (layer "F.Cu") (net 200))
  (via (at 104.4 109.35) (size 0.5) (drill 0.2) (layers "F.Cu" "B.Cu") (net 200))
  (via (at 99.772851 99.977851) (size 0.5) (drill 0.2) (layers "F.Cu" "B.Cu") (net 200))
  (segment (start 99.460297 103.392851) (end 100.085405 103.392851) (width 0.15) (layer "In2.Cu") (net 200))
  (segment (start 99.325151 103.307933) (end 99.343022 103.336374) (width 0.15) (layer "In2.Cu") (net 200))
  (segment (start 99.622851 101.892851) (end 99.460297 101.892851) (width 0.15) (layer "In2.Cu") (net 200))
  (segment (start 99.314057 102.676229) (end 99.325151 102.707933) (width 0.15) (layer "In2.Cu") (net 200))
  (segment (start 100.220551 103.477768) (end 100.231645 103.509472) (width 0.15) (layer "In2.Cu") (net 200))
  (segment (start 99.656229 101.88909) (end 99.622851 101.892851) (width 0.15) (layer "In2.Cu") (net 200))
  (segment (start 100.20268 103.036374) (end 100.178929 103.060125) (width 0.15) (layer "In2.Cu") (net 200))
  (segment (start 99.395214 102.177996) (end 99.426918 102.18909) (width 0.15) (layer "In2.Cu") (net 200))
  (segment (start 99.314057 102.609472) (end 99.310297 102.642851) (width 0.15) (layer "In2.Cu") (net 200))
  (segment (start 100.118784 103.68909) (end 100.085405 103.692851) (width 0.15) (layer "In2.Cu") (net 200))
  (segment (start 99.343022 103.149327) (end 99.325151 103.177768) (width 0.15) (layer "In2.Cu") (net 200))
  (segment (start 99.460297 103.992851) (end 99.622851 103.992851) (width 0.15) (layer "In2.Cu") (net 200))
  (segment (start 99.460297 102.192851) (end 100.085405 102.192851) (width 0.15) (layer "In2.Cu") (net 200))
  (segment (start 99.395214 101.907705) (end 99.366773 101.925576) (width 0.15) (layer "In2.Cu") (net 200))
  (segment (start 99.460297 102.792851) (end 100.085405 102.792851) (width 0.15) (layer "In2.Cu") (net 200))
  (segment (start 99.460297 101.892851) (end 99.426918 101.896611) (width 0.15) (layer "In2.Cu") (net 200))
  (segment (start 99.460297 102.492851) (end 99.426918 102.496611) (width 0.15) (layer "In2.Cu") (net 200))
  (segment (start 99.772851 99.977851) (end 99.772851 101.742851) (width 0.15) (layer "In2.Cu") (net 200))
  (segment (start 100.085405 103.692851) (end 99.460297 103.692851) (width 0.15) (layer "In2.Cu") (net 200))
  (segment (start 100.178929 102.460125) (end 100.150488 102.477996) (width 0.15) (layer "In2.Cu") (net 200))
  (segment (start 99.772851 104.722851) (end 104.4 109.35) (width 0.15) (layer "In2.Cu") (net 200))
  (segment (start 100.178929 103.425576) (end 100.20268 103.449327) (width 0.15) (layer "In2.Cu") (net 200))
  (segment (start 99.314057 103.809472) (end 99.310297 103.842851) (width 0.15) (layer "In2.Cu") (net 200))
  (segment (start 99.366773 102.525576) (end 99.343022 102.549327) (width 0.15) (layer "In2.Cu") (net 200))
  (segment (start 99.687933 101.877996) (end 99.656229 101.88909) (width 0.15) (layer "In2.Cu") (net 200))
  (segment (start 99.314057 103.209472) (end 99.310297 103.242851) (width 0.15) (layer "In2.Cu") (net 200))
  (segment (start 100.235405 103.542851) (end 100.231645 103.576229) (width 0.15) (layer "In2.Cu") (net 200))
  (segment (start 99.426918 103.696611) (end 99.395214 103.707705) (width 0.15) (layer "In2.Cu") (net 200))
  (segment (start 100.235405 102.942851) (end 100.231645 102.976229) (width 0.15) (layer "In2.Cu") (net 200))
  (segment (start 100.118784 102.196611) (end 100.150488 102.207705) (width 0.15) (layer "In2.Cu") (net 200))
  (segment (start 100.150488 102.477996) (end 100.118784 102.48909) (width 0.15) (layer "In2.Cu") (net 200))
  (segment (start 100.231645 102.909472) (end 100.235405 102.942851) (width 0.15) (layer "In2.Cu") (net 200))
  (segment (start 100.231645 103.576229) (end 100.220551 103.607933) (width 0.15) (layer "In2.Cu") (net 200))
  (segment (start 100.178929 103.060125) (end 100.150488 103.077996) (width 0.15) (layer "In2.Cu") (net 200))
  (segment (start 99.343022 103.336374) (end 99.366773 103.360125) (width 0.15) (layer "In2.Cu") (net 200))
  (segment (start 99.395214 103.707705) (end 99.366773 103.725576) (width 0.15) (layer "In2.Cu") (net 200))
  (segment (start 100.118784 102.796611) (end 100.150488 102.807705) (width 0.15) (layer "In2.Cu") (net 200))
  (segment (start 100.20268 102.849327) (end 100.220551 102.877768) (width 0.15) (layer "In2.Cu") (net 200))
  (segment (start 99.343022 102.549327) (end 99.325151 102.577768) (width 0.15) (layer "In2.Cu") (net 200))
  (segment (start 99.740125 104.049327) (end 99.757996 104.077768) (width 0.15) (layer "In2.Cu") (net 200))
  (segment (start 99.310297 103.242851) (end 99.314057 103.276229) (width 0.15) (layer "In2.Cu") (net 200))
  (segment (start 99.460297 103.692851) (end 99.426918 103.696611) (width 0.15) (layer "In2.Cu") (net 200))
  (segment (start 99.325151 102.707933) (end 99.343022 102.736374) (width 0.15) (layer "In2.Cu") (net 200))
  (segment (start 99.426918 103.98909) (end 99.460297 103.992851) (width 0.15) (layer "In2.Cu") (net 200))
  (segment (start 99.325151 103.907933) (end 99.343022 103.936374) (width 0.15) (layer "In2.Cu") (net 200))
  (segment (start 99.343022 102.136374) (end 99.366773 102.160125) (width 0.15) (layer "In2.Cu") (net 200))
  (segment (start 99.757996 104.077768) (end 99.76909 104.109472) (width 0.15) (layer "In2.Cu") (net 200))
  (segment (start 100.20268 102.249327) (end 100.220551 102.277768) (width 0.15) (layer "In2.Cu") (net 200))
  (segment (start 99.325151 103.777768) (end 99.314057 103.809472) (width 0.15) (layer "In2.Cu") (net 200))
  (segment (start 99.395214 103.377996) (end 99.426918 103.38909) (width 0.15) (layer "In2.Cu") (net 200))
  (segment (start 100.235405 102.342851) (end 100.231645 102.376229) (width 0.15) (layer "In2.Cu") (net 200))
  (segment (start 99.343022 103.749327) (end 99.325151 103.777768) (width 0.15) (layer "In2.Cu") (net 200))
  (segment (start 99.395214 103.977996) (end 99.426918 103.98909) (width 0.15) (layer "In2.Cu") (net 200))
  (segment (start 99.622851 103.992851) (end 99.656229 103.996611) (width 0.15) (layer "In2.Cu") (net 200))
  (segment (start 99.314057 103.276229) (end 99.325151 103.307933) (width 0.15) (layer "In2.Cu") (net 200))
  (segment (start 100.118784 103.396611) (end 100.150488 103.407705) (width 0.15) (layer "In2.Cu") (net 200))
  (segment (start 99.426918 102.78909) (end 99.460297 102.792851) (width 0.15) (layer "In2.Cu") (net 200))
  (segment (start 100.178929 102.225576) (end 100.20268 102.249327) (width 0.15) (layer "In2.Cu") (net 200))
  (segment (start 99.325151 102.107933) (end 99.343022 102.136374) (width 0.15) (layer "In2.Cu") (net 200))
  (segment (start 100.178929 102.825576) (end 100.20268 102.849327) (width 0.15) (layer "In2.Cu") (net 200))
  (segment (start 99.310297 102.042851) (end 99.314057 102.076229) (width 0.15) (layer "In2.Cu") (net 200))
  (segment (start 99.716374 101.860125) (end 99.687933 101.877996) (width 0.15) (layer "In2.Cu") (net 200))
  (segment (start 99.395214 103.107705) (end 99.366773 103.125576) (width 0.15) (layer "In2.Cu") (net 200))
  (segment (start 99.426918 103.096611) (end 99.395214 103.107705) (width 0.15) (layer "In2.Cu") (net 200))
  (segment (start 99.76909 101.776229) (end 99.757996 101.807933) (width 0.15) (layer "In2.Cu") (net 200))
  (segment (start 99.343022 103.936374) (end 99.366773 103.960125) (width 0.15) (layer "In2.Cu") (net 200))
  (segment (start 100.085405 102.492851) (end 99.460297 102.492851) (width 0.15) (layer "In2.Cu") (net 200))
  (segment (start 99.366773 103.725576) (end 99.343022 103.749327) (width 0.15) (layer "In2.Cu") (net 200))
  (segment (start 100.150488 103.077996) (end 100.118784 103.08909) (width 0.15) (layer "In2.Cu") (net 200))
  (segment (start 99.740125 101.836374) (end 99.716374 101.860125) (width 0.15) (layer "In2.Cu") (net 200))
  (segment (start 100.20268 103.636374) (end 100.178929 103.660125) (width 0.15) (layer "In2.Cu") (net 200))
  (segment (start 99.395214 102.507705) (end 99.366773 102.525576) (width 0.15) (layer "In2.Cu") (net 200))
  (segment (start 99.426918 101.896611) (end 99.395214 101.907705) (width 0.15) (layer "In2.Cu") (net 200))
  (segment (start 100.150488 102.807705) (end 100.178929 102.825576) (width 0.15) (layer "In2.Cu") (net 200))
  (segment (start 99.343022 102.736374) (end 99.366773 102.760125) (width 0.15) (layer "In2.Cu") (net 200))
  (segment (start 99.325151 103.177768) (end 99.314057 103.209472) (width 0.15) (layer "In2.Cu") (net 200))
  (segment (start 99.426918 103.38909) (end 99.460297 103.392851) (width 0.15) (layer "In2.Cu") (net 200))
  (segment (start 99.716374 104.025576) (end 99.740125 104.049327) (width 0.15) (layer "In2.Cu") (net 200))
  (segment (start 100.085405 103.092851) (end 99.460297 103.092851) (width 0.15) (layer "In2.Cu") (net 200))
  (segment (start 99.687933 104.007705) (end 99.716374 104.025576) (width 0.15) (layer "In2.Cu") (net 200))
  (segment (start 100.118784 103.08909) (end 100.085405 103.092851) (width 0.15) (layer "In2.Cu") (net 200))
  (segment (start 99.76909 104.109472) (end 99.772851 104.142851) (width 0.15) (layer "In2.Cu") (net 200))
  (segment (start 100.231645 102.976229) (end 100.220551 103.007933) (width 0.15) (layer "In2.Cu") (net 200))
  (segment (start 99.772851 101.742851) (end 99.76909 101.776229) (width 0.15) (layer "In2.Cu") (net 200))
  (segment (start 99.325151 102.577768) (end 99.314057 102.609472) (width 0.15) (layer "In2.Cu") (net 200))
  (segment (start 99.460297 103.092851) (end 99.426918 103.096611) (width 0.15) (layer "In2.Cu") (net 200))
  (segment (start 100.20268 103.449327) (end 100.220551 103.477768) (width 0.15) (layer "In2.Cu") (net 200))
  (segment (start 100.220551 102.877768) (end 100.231645 102.909472) (width 0.15) (layer "In2.Cu") (net 200))
  (segment (start 100.231645 102.376229) (end 100.220551 102.407933) (width 0.15) (layer "In2.Cu") (net 200))
  (segment (start 99.757996 101.807933) (end 99.740125 101.836374) (width 0.15) (layer "In2.Cu") (net 200))
  (segment (start 100.150488 102.207705) (end 100.178929 102.225576) (width 0.15) (layer "In2.Cu") (net 200))
  (segment (start 100.220551 103.007933) (end 100.20268 103.036374) (width 0.15) (layer "In2.Cu") (net 200))
  (segment (start 100.085405 102.792851) (end 100.118784 102.796611) (width 0.15) (layer "In2.Cu") (net 200))
  (segment (start 100.231645 102.309472) (end 100.235405 102.342851) (width 0.15) (layer "In2.Cu") (net 200))
  (segment (start 100.178929 103.660125) (end 100.150488 103.677996) (width 0.15) (layer "In2.Cu") (net 200))
  (segment (start 100.085405 103.392851) (end 100.118784 103.396611) (width 0.15) (layer "In2.Cu") (net 200))
  (segment (start 99.426918 102.496611) (end 99.395214 102.507705) (width 0.15) (layer "In2.Cu") (net 200))
  (segment (start 100.220551 102.277768) (end 100.231645 102.309472) (width 0.15) (layer "In2.Cu") (net 200))
  (segment (start 99.314057 102.076229) (end 99.325151 102.107933) (width 0.15) (layer "In2.Cu") (net 200))
  (segment (start 99.656229 103.996611) (end 99.687933 104.007705) (width 0.15) (layer "In2.Cu") (net 200))
  (segment (start 100.220551 102.407933) (end 100.20268 102.436374) (width 0.15) (layer "In2.Cu") (net 200))
  (segment (start 99.314057 102.009472) (end 99.310297 102.042851) (width 0.15) (layer "In2.Cu") (net 200))
  (segment (start 99.772851 104.142851) (end 99.772851 104.722851) (width 0.15) (layer "In2.Cu") (net 200))
  (segment (start 99.310297 103.842851) (end 99.314057 103.876229) (width 0.15) (layer "In2.Cu") (net 200))
  (segment (start 100.220551 103.607933) (end 100.20268 103.636374) (width 0.15) (layer "In2.Cu") (net 200))
  (segment (start 99.366773 103.960125) (end 99.395214 103.977996) (width 0.15) (layer "In2.Cu") (net 200))
  (segment (start 100.118784 102.48909) (end 100.085405 102.492851) (width 0.15) (layer "In2.Cu") (net 200))
  (segment (start 99.325151 101.977768) (end 99.314057 102.009472) (width 0.15) (layer "In2.Cu") (net 200))
  (segment (start 99.395214 102.777996) (end 99.426918 102.78909) (width 0.15) (layer "In2.Cu") (net 200))
  (segment (start 100.150488 103.407705) (end 100.178929 103.425576) (width 0.15) (layer "In2.Cu") (net 200))
  (segment (start 99.366773 103.125576) (end 99.343022 103.149327) (width 0.15) (layer "In2.Cu") (net 200))
  (segment (start 99.343022 101.949327) (end 99.325151 101.977768) (width 0.15) (layer "In2.Cu") (net 200))
  (segment (start 99.314057 103.876229) (end 99.325151 103.907933) (width 0.15) (layer "In2.Cu") (net 200))
  (segment (start 100.085405 102.192851) (end 100.118784 102.196611) (width 0.15) (layer "In2.Cu") (net 200))
  (segment (start 99.366773 103.360125) (end 99.395214 103.377996) (width 0.15) (layer "In2.Cu") (net 200))
  (segment (start 99.366773 101.925576) (end 99.343022 101.949327) (width 0.15) (layer "In2.Cu") (net 200))
  (segment (start 100.231645 103.509472) (end 100.235405 103.542851) (width 0.15) (layer "In2.Cu") (net 200))
  (segment (start 100.150488 103.677996) (end 100.118784 103.68909) (width 0.15) (layer "In2.Cu") (net 200))
  (segment (start 99.366773 102.160125) (end 99.395214 102.177996) (width 0.15) (layer "In2.Cu") (net 200))
  (segment (start 99.310297 102.642851) (end 99.314057 102.676229) (width 0.15) (layer "In2.Cu") (net 200))
  (segment (start 99.426918 102.18909) (end 99.460297 102.192851) (width 0.15) (layer "In2.Cu") (net 200))
  (segment (start 100.20268 102.436374) (end 100.178929 102.460125) (width 0.15) (layer "In2.Cu") (net 200))
  (segment (start 99.366773 102.760125) (end 99.395214 102.777996) (width 0.15) (layer "In2.Cu") (net 200))
  (segment (start 98.6 110.15) (end 98 110.15) (width 0.15) (layer "F.Cu") (net 201))
  (segment (start 98.825 98.2) (end 98.624991 98.400009) (width 0.15) (layer "F.Cu") (net 201))
  (segment (start 98.8 107.45) (end 98.8 109.95) (width 0.15) (layer "F.Cu") (net 201))
  (segment (start 99 107.25) (end 98.8 107.45) (width 0.15) (layer "F.Cu") (net 201))
  (segment (start 98.8 109.95) (end 98.6 110.15) (width 0.15) (layer "F.Cu") (net 201))
  (segment (start 99.772851 98.2) (end 98.825 98.2) (width 0.15) (layer "F.Cu") (net 201))
  (segment (start 98 110.15) (end 97.6 110.55) (width 0.15) (layer "F.Cu") (net 201))
  (segment (start 98.624991 99.174991) (end 99 99.55) (width 0.15) (layer "F.Cu") (net 201))
  (segment (start 98.624991 98.400009) (end 98.624991 99.174991) (width 0.15) (layer "F.Cu") (net 201))
  (via (at 99 99.55) (size 0.5) (drill 0.2) (layers "F.Cu" "B.Cu") (net 201))
  (via (at 99 107.25) (size 0.5) (drill 0.2) (layers "F.Cu" "B.Cu") (net 201))
  (segment (start 99.351494 105.746239) (end 99.318115 105.75) (width 0.15) (layer "In2.Cu") (net 201))
  (segment (start 98.61461 105.806476) (end 98.596739 105.834917) (width 0.15) (layer "In2.Cu") (net 201))
  (segment (start 99.383198 106.064854) (end 99.411639 106.082725) (width 0.15) (layer "In2.Cu") (net 201))
  (segment (start 98.731885 105.15) (end 98.698506 105.15376) (width 0.15) (layer "In2.Cu") (net 201))
  (segment (start 98.585645 105.866621) (end 98.581885 105.9) (width 0.15) (layer "In2.Cu") (net 201))
  (segment (start 99.411639 105.482725) (end 99.43539 105.506476) (width 0.15) (layer "In2.Cu") (net 201))
  (segment (start 99.464355 105.633378) (end 99.453261 105.665082) (width 0.15) (layer "In2.Cu") (net 201))
  (segment (start 99.453261 106.265082) (end 99.43539 106.293523) (width 0.15) (layer "In2.Cu") (net 201))
  (segment (start 98.666802 105.764854) (end 98.638361 105.782725) (width 0.15) (layer "In2.Cu") (net 201))
  (segment (start 98.883378 106.65376) (end 98.915082 106.664854) (width 0.15) (layer "In2.Cu") (net 201))
  (segment (start 98.698506 105.75376) (end 98.666802 105.764854) (width 0.15) (layer "In2.Cu") (net 201))
  (segment (start 99.383198 105.464854) (end 99.411639 105.482725) (width 0.15) (layer "In2.Cu") (net 201))
  (segment (start 98.698506 105.446239) (end 98.731885 105.45) (width 0.15) (layer "In2.Cu") (net 201))
  (segment (start 99.43539 106.106476) (end 99.453261 106.134917) (width 0.15) (layer "In2.Cu") (net 201))
  (segment (start 98.85 106.65) (end 98.883378 106.65376) (width 0.15) (layer "In2.Cu") (net 201))
  (segment (start 98.666802 105.164854) (end 98.638361 105.182725) (width 0.15) (layer "In2.Cu") (net 201))
  (segment (start 98.698506 105.15376) (end 98.666802 105.164854) (width 0.15) (layer "In2.Cu") (net 201))
  (segment (start 98.943523 105.117274) (end 98.915082 105.135145) (width 0.15) (layer "In2.Cu") (net 201))
  (segment (start 98.596739 105.965082) (end 98.61461 105.993523) (width 0.15) (layer "In2.Cu") (net 201))
  (segment (start 98.585645 105.933378) (end 98.596739 105.965082) (width 0.15) (layer "In2.Cu") (net 201))
  (segment (start 99.411639 105.717274) (end 99.383198 105.735145) (width 0.15) (layer "In2.Cu") (net 201))
  (segment (start 98.585645 106.533378) (end 98.596739 106.565082) (width 0.15) (layer "In2.Cu") (net 201))
  (segment (start 98.596739 106.565082) (end 98.61461 106.593523) (width 0.15) (layer "In2.Cu") (net 201))
  (segment (start 99.453261 105.665082) (end 99.43539 105.693523) (width 0.15) (layer "In2.Cu") (net 201))
  (segment (start 98.698506 106.646239) (end 98.731885 106.65) (width 0.15) (layer "In2.Cu") (net 201))
  (segment (start 98.638361 106.382725) (end 98.61461 106.406476) (width 0.15) (layer "In2.Cu") (net 201))
  (segment (start 99 99.55) (end 99 105) (width 0.15) (layer "In2.Cu") (net 201))
  (segment (start 99 107.023116) (end 99 107.25) (width 0.15) (layer "In2.Cu") (net 201))
  (segment (start 98.731885 106.65) (end 98.85 106.65) (width 0.15) (layer "In2.Cu") (net 201))
  (segment (start 98.638361 105.417274) (end 98.666802 105.435145) (width 0.15) (layer "In2.Cu") (net 201))
  (segment (start 98.883378 105.146239) (end 98.85 105.15) (width 0.15) (layer "In2.Cu") (net 201))
  (segment (start 99.464355 106.233378) (end 99.453261 106.265082) (width 0.15) (layer "In2.Cu") (net 201))
  (segment (start 98.585645 105.333378) (end 98.596739 105.365082) (width 0.15) (layer "In2.Cu") (net 201))
  (segment (start 99.464355 106.166621) (end 99.468115 106.2) (width 0.15) (layer "In2.Cu") (net 201))
  (segment (start 99 105) (end 98.996239 105.033378) (width 0.15) (layer "In2.Cu") (net 201))
  (segment (start 99.383198 105.735145) (end 99.351494 105.746239) (width 0.15) (layer "In2.Cu") (net 201))
  (segment (start 98.596739 105.234917) (end 98.585645 105.266621) (width 0.15) (layer "In2.Cu") (net 201))
  (segment (start 99.383198 106.335145) (end 99.351494 106.346239) (width 0.15) (layer "In2.Cu") (net 201))
  (segment (start 98.585645 106.466621) (end 98.581885 106.5) (width 0.15) (layer "In2.Cu") (net 201))
  (segment (start 98.85 105.15) (end 98.731885 105.15) (width 0.15) (layer "In2.Cu") (net 201))
  (segment (start 98.638361 105.182725) (end 98.61461 105.206476) (width 0.15) (layer "In2.Cu") (net 201))
  (segment (start 98.61461 105.393523) (end 98.638361 105.417274) (width 0.15) (layer "In2.Cu") (net 201))
  (segment (start 98.985145 106.734917) (end 98.996239 106.766621) (width 0.15) (layer "In2.Cu") (net 201))
  (segment (start 98.666802 106.364854) (end 98.638361 106.382725) (width 0.15) (layer "In2.Cu") (net 201))
  (segment (start 99.468115 106.2) (end 99.464355 106.233378) (width 0.15) (layer "In2.Cu") (net 201))
  (segment (start 98.596739 105.365082) (end 98.61461 105.393523) (width 0.15) (layer "In2.Cu") (net 201))
  (segment (start 99.351494 105.45376) (end 99.383198 105.464854) (width 0.15) (layer "In2.Cu") (net 201))
  (segment (start 98.996239 106.766621) (end 99 106.8) (width 0.15) (layer "In2.Cu") (net 201))
  (segment (start 99.468115 105.6) (end 99.464355 105.633378) (width 0.15) (layer "In2.Cu") (net 201))
  (segment (start 99.43539 105.693523) (end 99.411639 105.717274) (width 0.15) (layer "In2.Cu") (net 201))
  (segment (start 98.731885 105.45) (end 99.318115 105.45) (width 0.15) (layer "In2.Cu") (net 201))
  (segment (start 98.731885 106.05) (end 99.318115 106.05) (width 0.15) (layer "In2.Cu") (net 201))
  (segment (start 98.61461 105.206476) (end 98.596739 105.234917) (width 0.15) (layer "In2.Cu") (net 201))
  (segment (start 98.915082 105.135145) (end 98.883378 105.146239) (width 0.15) (layer "In2.Cu") (net 201))
  (segment (start 98.996239 105.033378) (end 98.985145 105.065082) (width 0.15) (layer "In2.Cu") (net 201))
  (segment (start 98.638361 106.617274) (end 98.666802 106.635145) (width 0.15) (layer "In2.Cu") (net 201))
  (segment (start 99.453261 105.534917) (end 99.464355 105.566621) (width 0.15) (layer "In2.Cu") (net 201))
  (segment (start 98.581885 105.3) (end 98.585645 105.333378) (width 0.15) (layer "In2.Cu") (net 201))
  (segment (start 98.666802 106.635145) (end 98.698506 106.646239) (width 0.15) (layer "In2.Cu") (net 201))
  (segment (start 98.698506 106.35376) (end 98.666802 106.364854) (width 0.15) (layer "In2.Cu") (net 201))
  (segment (start 98.985145 105.065082) (end 98.967274 105.093523) (width 0.15) (layer "In2.Cu") (net 201))
  (segment (start 98.943523 106.682725) (end 98.967274 106.706476) (width 0.15) (layer "In2.Cu") (net 201))
  (segment (start 99.411639 106.082725) (end 99.43539 106.106476) (width 0.15) (layer "In2.Cu") (net 201))
  (segment (start 99.464355 105.566621) (end 99.468115 105.6) (width 0.15) (layer "In2.Cu") (net 201))
  (segment (start 98.698506 106.046239) (end 98.731885 106.05) (width 0.15) (layer "In2.Cu") (net 201))
  (segment (start 99.351494 106.346239) (end 99.318115 106.35) (width 0.15) (layer "In2.Cu") (net 201))
  (segment (start 98.731885 106.35) (end 98.698506 106.35376) (width 0.15) (layer "In2.Cu") (net 201))
  (segment (start 98.915082 106.664854) (end 98.943523 106.682725) (width 0.15) (layer "In2.Cu") (net 201))
  (segment (start 98.61461 106.593523) (end 98.638361 106.617274) (width 0.15) (layer "In2.Cu") (net 201))
  (segment (start 98.638361 105.782725) (end 98.61461 105.806476) (width 0.15) (layer "In2.Cu") (net 201))
  (segment (start 98.967274 105.093523) (end 98.943523 105.117274) (width 0.15) (layer "In2.Cu") (net 201))
  (segment (start 99.351494 106.05376) (end 99.383198 106.064854) (width 0.15) (layer "In2.Cu") (net 201))
  (segment (start 99.453261 106.134917) (end 99.464355 106.166621) (width 0.15) (layer "In2.Cu") (net 201))
  (segment (start 98.581885 106.5) (end 98.585645 106.533378) (width 0.15) (layer "In2.Cu") (net 201))
  (segment (start 99.43539 105.506476) (end 99.453261 105.534917) (width 0.15) (layer "In2.Cu") (net 201))
  (segment (start 99.318115 106.35) (end 98.731885 106.35) (width 0.15) (layer "In2.Cu") (net 201))
  (segment (start 98.666802 105.435145) (end 98.698506 105.446239) (width 0.15) (layer "In2.Cu") (net 201))
  (segment (start 98.581885 105.9) (end 98.585645 105.933378) (width 0.15) (layer "In2.Cu") (net 201))
  (segment (start 98.61461 105.993523) (end 98.638361 106.017274) (width 0.15) (layer "In2.Cu") (net 201))
  (segment (start 98.585645 105.266621) (end 98.581885 105.3) (width 0.15) (layer "In2.Cu") (net 201))
  (segment (start 98.61461 106.406476) (end 98.596739 106.434917) (width 0.15) (layer "In2.Cu") (net 201))
  (segment (start 98.638361 106.017274) (end 98.666802 106.035145) (width 0.15) (layer "In2.Cu") (net 201))
  (segment (start 98.596739 106.434917) (end 98.585645 106.466621) (width 0.15) (layer "In2.Cu") (net 201))
  (segment (start 98.731885 105.75) (end 98.698506 105.75376) (width 0.15) (layer "In2.Cu") (net 201))
  (segment (start 99.318115 105.75) (end 98.731885 105.75) (width 0.15) (layer "In2.Cu") (net 201))
  (segment (start 99.318115 106.05) (end 99.351494 106.05376) (width 0.15) (layer "In2.Cu") (net 201))
  (segment (start 98.967274 106.706476) (end 98.985145 106.734917) (width 0.15) (layer "In2.Cu") (net 201))
  (segment (start 99 106.8) (end 99 107.023116) (width 0.15) (layer "In2.Cu") (net 201))
  (segment (start 98.666802 106.035145) (end 98.698506 106.046239) (width 0.15) (layer "In2.Cu") (net 201))
  (segment (start 99.318115 105.45) (end 99.351494 105.45376) (width 0.15) (layer "In2.Cu") (net 201))
  (segment (start 98.596739 105.834917) (end 98.585645 105.866621) (width 0.15) (layer "In2.Cu") (net 201))
  (segment (start 99.43539 106.293523) (end 99.411639 106.317274) (width 0.15) (layer "In2.Cu") (net 201))
  (segment (start 99.411639 106.317274) (end 99.383198 106.335145) (width 0.15) (layer "In2.Cu") (net 201))
  (segment (start 96.75 98.25) (end 96.75 99.55) (width 0.15) (layer "F.Cu") (net 202))
  (segment (start 98.3 96.7) (end 96.75 98.25) (width 0.15) (layer "F.Cu") (net 202))
  (segment (start 99.772851 96.7) (end 98.3 96.7) (width 0.15) (layer "F.Cu") (net 202))
  (segment (start 97.25 106.7) (end 96.8 106.25) (width 0.15) (layer "F.Cu") (net 202))
  (segment (start 100.95 106.7) (end 97.25 106.7) (width 0.15) (layer "F.Cu") (net 202))
  (segment (start 102.4 108.15) (end 100.95 106.7) (width 0.15) (layer "F.Cu") (net 202))
  (via (at 96.8 106.25) (size 0.5) (drill 0.2) (layers "F.Cu" "B.Cu") (net 202))
  (via (at 96.75 99.55) (size 0.5) (drill 0.2) (layers "F.Cu" "B.Cu") (net 202))
  (segment (start 96.8 106.25) (end 96.75 106.2) (width 0.15) (layer "In2.Cu") (net 202))
  (segment (start 96.75 106.2) (end 96.75 99.55) (width 0.15) (layer "In2.Cu") (net 202))
  (segment (start 82.33 163.37) (end 82.33 151.38) (width 0.15) (layer "F.Cu") (net 203))
  (segment (start 82.3 163.4) (end 82.33 163.37) (width 0.15) (layer "F.Cu") (net 203))
  (segment (start 86.175 147.535) (end 90.65 147.535) (width 0.15) (layer "F.Cu") (net 203))
  (segment (start 82.33 151.38) (end 86.175 147.535) (width 0.15) (layer "F.Cu") (net 203))
  (via (at 82.3 163.4) (size 0.5) (drill 0.2) (layers "F.Cu" "B.Cu") (net 203))
  (segment (start 81.1 166.95) (end 81.1 177.4) (width 0.15) (layer "B.Cu") (net 203))
  (segment (start 82.3 163.4) (end 82.3 165.75) (width 0.15) (layer "B.Cu") (net 203))
  (segment (start 82.3 165.75) (end 81.1 166.95) (width 0.15) (layer "B.Cu") (net 203))
  (segment (start 81.75 161.921408) (end 81.75 163.9) (width 0.15) (layer "F.Cu") (net 204))
  (segment (start 82.079989 151.276443) (end 82.079989 161.591419) (width 0.15) (layer "F.Cu") (net 204))
  (segment (start 86.256432 147.1) (end 82.079989 151.276443) (width 0.15) (layer "F.Cu") (net 204))
  (segment (start 89.715 147.1) (end 86.256432 147.1) (width 0.15) (layer "F.Cu") (net 204))
  (segment (start 82.079989 161.591419) (end 81.75 161.921408) (width 0.15) (layer "F.Cu") (net 204))
  (via (at 81.75 163.9) (size 0.5) (drill 0.2) (layers "F.Cu" "B.Cu") (net 204))
  (segment (start 80.725 175.775) (end 80.485 176.015) (width 0.15) (layer "B.Cu") (net 204))
  (segment (start 80.725 174.975) (end 80.725 175.775) (width 0.15) (layer "B.Cu") (net 204))
  (segment (start 80.485 174.735) (end 80.725 174.975) (width 0.15) (layer "B.Cu") (net 204))
  (segment (start 81.75 165.8) (end 81.75 163.9) (width 0.15) (layer "B.Cu") (net 204))
  (segment (start 80.49 167.06) (end 81.75 165.8) (width 0.15) (layer "B.Cu") (net 204))
  (segment (start 80.475 174.75) (end 80.49 167.06) (width 0.15) (layer "B.Cu") (net 204))
  (segment (start 80.485 176.015) (end 80.485 177.315) (width 0.15) (layer "B.Cu") (net 204))
  (segment (start 80.829934 150.758658) (end 86.988592 144.6) (width 0.15) (layer "F.Cu") (net 205))
  (segment (start 79.25 164.35) (end 79.25 162.653568) (width 0.15) (layer "F.Cu") (net 205))
  (segment (start 86.988592 144.6) (end 89.715 144.6) (width 0.15) (layer "F.Cu") (net 205))
  (segment (start 79.25 162.653568) (end 80.829934 161.073634) (width 0.15) (layer "F.Cu") (net 205))
  (segment (start 80.829934 161.073634) (end 80.829934 150.758658) (width 0.15) (layer "F.Cu") (net 205))
  (via (at 79.25 164.35) (size 0.5) (drill 0.2) (layers "F.Cu" "B.Cu") (net 205))
  (segment (start 77.49 177.345) (end 77.49 175.94) (width 0.15) (layer "B.Cu") (net 205))
  (segment (start 77.25 174.9) (end 77.49 174.66) (width 0.15) (layer "B.Cu") (net 205))
  (segment (start 77.49 175.94) (end 77.25 175.7) (width 0.15) (layer "B.Cu") (net 205))
  (segment (start 77.25 175.7) (end 77.25 174.9) (width 0.15) (layer "B.Cu") (net 205))
  (segment (start 77.49 166.11) (end 79.25 164.35) (width 0.15) (layer "B.Cu") (net 205))
  (segment (start 77.49 174.66) (end 77.49 166.11) (width 0.15) (layer "B.Cu") (net 205))
  (segment (start 80.57 160.98) (end 78.7 162.85) (width 0.15) (layer "F.Cu") (net 206))
  (segment (start 89.715 144.1) (end 87.135024 144.1) (width 0.15) (layer "F.Cu") (net 206))
  (segment (start 78.7 162.85) (end 78.7 163.9) (width 0.15) (layer "F.Cu") (net 206))
  (segment (start 80.57 150.665024) (end 80.57 160.98) (width 0.15) (layer "F.Cu") (net 206))
  (segment (start 87.135024 144.1) (end 80.57 150.665024) (width 0.15) (layer "F.Cu") (net 206))
  (via (at 78.7 163.9) (size 0.5) (drill 0.2) (layers "F.Cu" "B.Cu") (net 206))
  (segment (start 76.89 165.71) (end 78.7 163.9) (width 0.15) (layer "B.Cu") (net 206))
  (segment (start 76.89 177.345) (end 76.89 165.71) (width 0.15) (layer "B.Cu") (net 206))
  (segment (start 81.329956 150.965772) (end 86.695728 145.6) (width 0.15) (layer "F.Cu") (net 207))
  (segment (start 81.329956 161.280748) (end 81.329956 150.965772) (width 0.15) (layer "F.Cu") (net 207))
  (segment (start 86.695728 145.6) (end 89.715 145.6) (width 0.15) (layer "F.Cu") (net 207))
  (segment (start 80.2 162.410704) (end 81.329956 161.280748) (width 0.15) (layer "F.Cu") (net 207))
  (segment (start 80.2 164.55) (end 80.2 162.410704) (width 0.15) (layer "F.Cu") (net 207))
  (segment (start 80.2 165.4) (end 80.2 164.55) (width 0.1) (layer "F.Cu") (net 207))
  (via (at 80.2 165.4) (size 0.5) (drill 0.2) (layers "F.Cu" "B.Cu") (net 207))
  (segment (start 80.2 165.4) (end 80.25 165.4) (width 0.1) (layer "B.Cu") (net 207))
  (segment (start 78.7 166.95) (end 78.7 177.4) (width 0.15) (layer "B.Cu") (net 207))
  (segment (start 80.25 165.4) (end 78.7 166.95) (width 0.15) (layer "B.Cu") (net 207))
  (segment (start 86.84216 145.1) (end 81.079945 150.862215) (width 0.15) (layer "F.Cu") (net 208))
  (segment (start 79.75 162.507136) (end 79.75 164.9) (width 0.15) (layer "F.Cu") (net 208))
  (segment (start 81.079945 161.177191) (end 79.75 162.507136) (width 0.15) (layer "F.Cu") (net 208))
  (segment (start 81.079945 150.862215) (end 81.079945 161.177191) (width 0.15) (layer "F.Cu") (net 208))
  (segment (start 89.715 145.1) (end 86.84216 145.1) (width 0.15) (layer "F.Cu") (net 208))
  (via (at 79.75 164.9) (size 0.5) (drill 0.2) (layers "F.Cu" "B.Cu") (net 208))
  (segment (start 78.09 174.59) (end 78.09 166.56) (width 0.15) (layer "B.Cu") (net 208))
  (segment (start 78.35 174.85) (end 78.35 175.85) (width 0.15) (layer "B.Cu") (net 208))
  (segment (start 78.35 175.85) (end 78.1 176.1) (width 0.15) (layer "B.Cu") (net 208))
  (segment (start 78.1 176.1) (end 78.1 177.35) (width 0.15) (layer "B.Cu") (net 208))
  (segment (start 78.09 166.56) (end 79.75 164.9) (width 0.15) (layer "B.Cu") (net 208))
  (segment (start 78.09 174.59) (end 78.35 174.85) (width 0.15) (layer "B.Cu") (net 208))
  (segment (start 81.15 162.16784) (end 81.829978 161.487862) (width 0.15) (layer "F.Cu") (net 209))
  (segment (start 81.15 164.4) (end 81.15 162.16784) (width 0.15) (layer "F.Cu") (net 209))
  (segment (start 81.829978 151.172886) (end 86.402864 146.6) (width 0.15) (layer "F.Cu") (net 209))
  (segment (start 86.402864 146.6) (end 89.715 146.6) (width 0.15) (layer "F.Cu") (net 209))
  (segment (start 81.829978 161.487862) (end 81.829978 151.172886) (width 0.15) (layer "F.Cu") (net 209))
  (via (at 81.15 164.4) (size 0.5) (drill 0.2) (layers "F.Cu" "B.Cu") (net 209))
  (segment (start 79.65 174.85) (end 79.9 174.6) (width 0.15) (layer "B.Cu") (net 209))
  (segment (start 79.65 175.85) (end 79.65 174.85) (width 0.15) (layer "B.Cu") (net 209))
  (segment (start 79.91 176.11) (end 79.65 175.85) (width 0.15) (layer "B.Cu") (net 209))
  (segment (start 79.91 176.11) (end 79.91 177.39) (width 0.15) (layer "B.Cu") (net 209))
  (segment (start 81.15 165.75) (end 79.9 167) (width 0.15) (layer "B.Cu") (net 209))
  (segment (start 81.15 164.4) (end 81.15 165.75) (width 0.15) (layer "B.Cu") (net 209))
  (segment (start 79.9 167) (end 79.9 174.6) (width 0.15) (layer "B.Cu") (net 209))
  (segment (start 81.579967 151.069329) (end 81.579967 161.384305) (width 0.15) (layer "F.Cu") (net 210))
  (segment (start 89.715 146.1) (end 86.549296 146.1) (width 0.15) (layer "F.Cu") (net 210))
  (segment (start 80.65001 162.314262) (end 80.65001 164.9) (width 0.15) (layer "F.Cu") (net 210))
  (segment (start 81.579967 161.384305) (end 80.65001 162.314262) (width 0.15) (layer "F.Cu") (net 210))
  (segment (start 86.549296 146.1) (end 81.579967 151.069329) (width 0.15) (layer "F.Cu") (net 210))
  (via (at 80.65001 164.9) (size 0.5) (drill 0.2) (layers "F.Cu" "B.Cu") (net 210))
  (segment (start 80.8 165.04999) (end 80.65001 164.9) (width 0.15) (layer "B.Cu") (net 210))
  (segment (start 79.345 177.345) (end 79.345 167.005) (width 0.15) (layer "B.Cu") (net 210))
  (segment (start 79.345 167.005) (end 80.8 165.55) (width 0.15) (layer "B.Cu") (net 210))
  (segment (start 80.8 165.55) (end 80.8 165.04999) (width 0.15) (layer "B.Cu") (net 210))
  (segment (start 107.5 98.45) (end 107.5 98.75) (width 0.2) (layer "F.Cu") (net 211))
  (segment (start 107.25 98.2) (end 107.5 98.45) (width 0.2) (layer "F.Cu") (net 211))
  (segment (start 106.627149 98.2) (end 107.25 98.2) (width 0.2) (layer "F.Cu") (net 211))
  (segment (start 102.95 100.9) (end 103 100.95) (width 0.2) (layer "F.Cu") (net 211))
  (segment (start 102.95 99.877149) (end 102.95 100.9) (width 0.2) (layer "F.Cu") (net 211))
  (segment (start 103.2 116.95) (end 102.8 116.55) (width 0.15) (layer "F.Cu") (net 211))
  (segment (start 100.8 123.35) (end 100.4 122.95) (width 0.15) (layer "F.Cu") (net 211))
  (segment (start 100.8 122.55) (end 100.4 122.95) (width 0.15) (layer "F.Cu") (net 211))
  (segment (start 90.55 80.1) (end 93.75 80.1) (width 0.7) (layer "F.Cu") (net 211))
  (segment (start 100.8 124.15) (end 101.2 124.55) (width 0.15) (layer "F.Cu") (net 211))
  (segment (start 108 116.95) (end 107.6 116.55) (width 0.15) (layer "F.Cu") (net 211))
  (segment (start 101.6 116.95) (end 101.2 116.55) (width 0.15) (layer "F.Cu") (net 211))
  (segment (start 107.2 124.15) (end 107.6 124.55) (width 0.15) (layer "F.Cu") (net 211))
  (segment (start 108 120.95) (end 108.4 121.35) (width 0.15) (layer "F.Cu") (net 211))
  (segment (start 101.6 124.15) (end 101.2 124.55) (width 0.15) (layer "F.Cu") (net 211))
  (segment (start 102.4 116.95) (end 102.8 116.55) (width 0.15) (layer "F.Cu") (net 211))
  (segment (start 106.4 124.15) (end 106 124.55) (width 0.15) (layer "F.Cu") (net 211))
  (segment (start 100.8 120.15) (end 100.4 119.75) (width 0.15) (layer "F.Cu") (net 211))
  (segment (start 108 120.15) (end 107.6 119.75) (width 0.15) (layer "F.Cu") (net 211))
  (segment (start 104.8 116.95) (end 104.4 116.55) (width 0.15) (layer "F.Cu") (net 211))
  (segment (start 105.6 116.95) (end 106 116.55) (width 0.15) (layer "F.Cu") (net 211))
  (segment (start 100.4 119.75) (end 100.8 119.35) (width 0.15) (layer "F.Cu") (net 211))
  (segment (start 99.772851 98.7) (end 99.05 98.7) (width 0.2) (layer "F.Cu") (net 211))
  (segment (start 100.8 116.95) (end 101.2 116.55) (width 0.15) (layer "F.Cu") (net 211))
  (segment (start 108 121.75) (end 108.4 121.35) (width 0.15) (layer "F.Cu") (net 211))
  (segment (start 90.2 79.75) (end 90.55 80.1) (width 0.5) (layer "F.Cu") (net 211))
  (segment (start 108 122.55) (end 108.4 122.95) (width 0.15) (layer "F.Cu") (net 211))
  (segment (start 99.05 98.7) (end 99.049992 98.700008) (width 0.2) (layer "F.Cu") (net 211))
  (segment (start 108.4 122.95) (end 108 123.35) (width 0.15) (layer "F.Cu") (net 211))
  (segment (start 100.8 117.75) (end 100.4 118.15) (width 0.15) (layer "F.Cu") (net 211))
  (segment (start 103.2 124.15) (end 102.8 124.55) (width 0.15) (layer "F.Cu") (net 211))
  (segment (start 90.2 79.15) (end 90.2 79.75) (width 0.5) (layer "F.Cu") (net 211))
  (segment (start 106.4 116.95) (end 106 116.55) (width 0.15) (layer "F.Cu") (net 211))
  (segment (start 104.8 124.15) (end 104.4 124.55) (width 0.15) (layer "F.Cu") (net 211))
  (segment (start 100.8 120.95) (end 100.4 121.35) (width 0.15) (layer "F.Cu") (net 211))
  (segment (start 108 117.75) (end 107.6 118.15) (width 0.15) (layer "F.Cu") (net 211))
  (segment (start 108 124.15) (end 107.6 124.55) (width 0.15) (layer "F.Cu") (net 211))
  (segment (start 108 119.35) (end 107.6 119.75) (width 0.15) (layer "F.Cu") (net 211))
  (segment (start 100.8 118.55) (end 100.4 118.15) (width 0.15) (layer "F.Cu") (net 211))
  (segment (start 99.772851 94.2) (end 98.85 94.2) (width 0.2) (layer "F.Cu") (net 211))
  (segment (start 100.95 99.877149) (end 100.95 100.660002) (width 0.2) (layer "F.Cu") (net 211))
  (segment (start 104 116.95) (end 104.4 116.55) (width 0.15) (layer "F.Cu") (net 211))
  (segment (start 104 124.15) (end 104.4 124.55) (width 0.15) (layer "F.Cu") (net 211))
  (segment (start 99.772851 96.2) (end 98.75 96.2) (width 0.15) (layer "F.Cu") (net 211))
  (segment (start 107.2 116.95) (end 107.6 116.55) (width 0.15) (layer "F.Cu") (net 211))
  (segment (start 102.4 124.15) (end 102.8 124.55) (width 0.15) (layer "F.Cu") (net 211))
  (segment (start 98.85 94.2) (end 98.8 94.15) (width 0.2) (layer "F.Cu") (net 211))
  (segment (start 100.8 121.75) (end 100.4 121.35) (width 0.15) (layer "F.Cu") (net 211))
  (segment (start 108 118.55) (end 107.6 118.15) (width 0.15) (layer "F.Cu") (net 211))
  (segment (start 105.6 124.15) (end 106 124.55) (width 0.15) (layer "F.Cu") (net 211))
  (via (at 107.5 98.75) (size 0.5) (drill 0.2) (layers "F.Cu" "B.Cu") (net 211))
  (via (at 98.8 94.15) (size 0.5) (drill 0.2) (layers "F.Cu" "B.Cu") (net 211))
  (via (at 103 100.95) (size 0.5) (drill 0.2) (layers "F.Cu" "B.Cu") (net 211))
  (via (at 100.4 122.95) (size 0.5) (drill 0.2) (layers "F.Cu" "B.Cu") (net 211))
  (via (at 92.25 80.1) (size 0.6) (drill 0.3) (layers "F.Cu" "B.Cu") (net 211))
  (via (at 101.2 116.55) (size 0.5) (drill 0.2) (layers "F.Cu" "B.Cu") (net 211))
  (via (at 102.1 89.25) (size 0.5) (drill 0.2) (layers "F.Cu" "B.Cu") (net 211))
  (via (at 99.049992 98.700008) (size 0.5) (drill 0.2) (layers "F.Cu" "B.Cu") (net 211))
  (via (at 98.2 127.5) (size 0.5) (drill 0.2) (layers "F.Cu" "B.Cu") (net 211))
  (via (at 106 124.55) (size 0.5) (drill 0.2) (layers "F.Cu" "B.Cu") (net 211))
  (via (at 108.4 122.95) (size 0.5) (drill 0.2) (layers "F.Cu" "B.Cu") (net 211))
  (via (at 100.4 121.35) (size 0.5) (drill 0.2) (layers "F.Cu" "B.Cu") (net 211))
  (via (at 107.6 118.15) (size 0.5) (drill 0.2) (layers "F.Cu" "B.Cu") (net 211))
  (via (at 100.95 100.660002) (size 0.5) (drill 0.2) (layers "F.Cu" "B.Cu") (net 211))
  (via (at 107.6 116.55) (size 0.5) (drill 0.2) (layers "F.Cu" "B.Cu") (net 211))
  (via (at 93 80.1) (size 0.6) (drill 0.3) (layers "F.Cu" "B.Cu") (net 211))
  (via (at 98.75 96.2) (size 0.5) (drill 0.2) (layers "F.Cu" "B.Cu") (net 211))
  (via (at 97.7 128) (size 0.5) (drill 0.2) (layers "F.Cu" "B.Cu") (net 211))
  (via (at 107.75 92.05) (size 0.5) (drill 0.2) (layers "F.Cu" "B.Cu") (net 211))
  (via (at 106 116.55) (size 0.5) (drill 0.2) (layers "F.Cu" "B.Cu") (net 211))
  (via (at 102.8 116.55) (size 0.5) (drill 0.2) (layers "F.Cu" "B.Cu") (net 211))
  (via (at 102.8 124.55) (size 0.5) (drill 0.2) (layers "F.Cu" "B.Cu") (net 211))
  (via (at 100.4 118.15) (size 0.5) (drill 0.2) (layers "F.Cu" "B.Cu") (net 211))
  (via (at 104.4 124.55) (size 0.5) (drill 0.2) (layers "F.Cu" "B.Cu") (net 211))
  (via (at 112.4 128) (size 0.5) (drill 0.2) (layers "F.Cu" "B.Cu") (net 211))
  (via (at 100.4 119.75) (size 0.5) (drill 0.2) (layers "F.Cu" "B.Cu") (net 211))
  (via (at 101.2 124.55) (size 0.5) (drill 0.2) (layers "F.Cu" "B.Cu") (net 211))
  (via (at 107.6 119.75) (size 0.5) (drill 0.2) (layers "F.Cu" "B.Cu") (net 211))
  (via (at 93.75 80.1) (size 0.6) (drill 0.3) (layers "F.Cu" "B.Cu") (net 211))
  (via (at 112.1 128.7) (size 0.5) (drill 0.2) (layers "F.Cu" "B.Cu") (net 211))
  (via (at 104.4 116.55) (size 0.5) (drill 0.2) (layers "F.Cu" "B.Cu") (net 211))
  (via (at 107.6 124.55) (size 0.5) (drill 0.2) (layers "F.Cu" "B.Cu") (net 211))
  (via (at 108.4 121.35) (size 0.5) (drill 0.2) (layers "F.Cu" "B.Cu") (net 211))
  (segment (start 107.5 98.75) (end 108.415 98.75) (width 0.2) (layer "B.Cu") (net 211))
  (segment (start 98.8 94.15) (end 97.785 94.15) (width 0.2) (layer "B.Cu") (net 211))
  (segment (start 100.95 100.05) (end 100.95 100.660002) (width 0.2) (layer "B.Cu") (net 211))
  (segment (start 98.085 128.235) (end 98.76 128.235) (width 0.3) (layer "B.Cu") (net 211))
  (segment (start 102 124.55) (end 102.8 124.55) (width 0.15) (layer "B.Cu") (net 211))
  (segment (start 98.4 127.3) (end 99.1 127.3) (width 0.3) (layer "B.Cu") (net 211))
  (segment (start 105.985 124.535) (end 106 124.55) (width 0.15) (layer "B.Cu") (net 211))
  (segment (start 103 100.95) (end 103.9 100.95) (width 0.2) (layer "B.Cu") (net 211))
  (segment (start 112.4 128) (end 112.4 127.8) (width 0.3) (layer "B.Cu") (net 211))
  (segment (start 112.75 127.3) (end 112.75 126.8) (width 0.3) (layer "B.Cu") (net 211))
  (segment (start 105.2 124.535) (end 105.985 124.535) (width 0.15) (layer "B.Cu") (net 211))
  (segment (start 107.75 92.05) (end 108.7 92.05) (width 0.2) (layer "B.Cu") (net 211))
  (segment (start 107.685 122) (end 108.335 121.35) (width 0.15) (layer "B.Cu") (net 211))
  (segment (start 101.2 124.55) (end 100.55 124.55) (width 0.15) (layer "B.Cu") (net 211))
  (segment (start 107.585 124.535) (end 107.6 124.55) (width 0.15) (layer "B.Cu") (net 211))
  (segment (start 100.915 122.435) (end 100.4 122.95) (width 0.15) (layer "B.Cu") (net 211))
  (segment (start 112.4 127.8) (end 111.9 127.3) (width 0.3) (layer "B.Cu") (net 211))
  (segment (start 108.085 116.065) (end 107.6 116.55) (width 0.15) (layer "B.Cu") (net 211))
  (segment (start 97.45 127.75) (end 97.7 128) (width 0.15) (layer "B.Cu") (net 211))
  (segment (start 107.6 118.15) (end 107.6 118.835) (width 0.15) (layer "B.Cu") (net 211))
  (segment (start 99.615 96.95) (end 99.615 98.135) (width 0.2) (layer "B.Cu") (net 211))
  (segment (start 102.55 89.25) (end 102.7 89.4) (width 0.2) (layer "B.Cu") (net 211))
  (segment (start 108.35 116.065) (end 108.085 116.065) (width 0.15) (layer "B.Cu") (net 211))
  (segment (start 104.4 116.55) (end 104.4 120.245) (width 0.15) (layer "B.Cu") (net 211))
  (segment (start 106.85 124.535) (end 107.585 124.535) (width 0.15) (layer "B.Cu") (net 211))
  (segment (start 100.915 122.15) (end 100.915 122.435) (width 0.15) (layer "B.Cu") (net 211))
  (segment (start 111.9 127.3) (end 111.45 127.3) (width 0.3) (layer "B.Cu") (net 211))
  (segment (start 100.915 120.835) (end 100.4 121.35) (width 0.15) (layer "B.Cu") (net 211))
  (segment (start 102.7 89.4) (end 103.05 89.4) (width 0.2) (layer "B.Cu") (net 211))
  (segment (start 108.335 121.35) (end 108.4 121.35) (width 0.15) (layer "B.Cu") (net 211))
  (segment (start 102.1 89.25) (end 102.55 89.25) (width 0.2) (layer "B.Cu") (net 211))
  (segment (start 107.635 120.45) (end 107.635 119.785) (width 0.15) (layer "B.Cu") (net 211))
  (segment (start 103.6 124.55) (end 104.4 124.55) (width 0.15) (layer "B.Cu") (net 211))
  (segment (start 108.4 123.465) (end 108.4 122.95) (width 0.15) (layer "B.Cu") (net 211))
  (segment (start 112.4 127.65) (end 112.75 127.3) (width 0.3) (layer "B.Cu") (net 211))
  (segment (start 112.4 128) (end 112.4 127.65) (width 0.3) (layer "B.Cu") (net 211))
  (segment (start 100.5 118.05) (end 100.4 118.15) (width 0.15) (layer "B.Cu") (net 211))
  (segment (start 98.2 127.5) (end 98.4 127.3) (width 0.3) (layer "B.Cu") (net 211))
  (segment (start 100.915 120.5) (end 100.915 120.835) (width 0.15) (layer "B.Cu") (net 211))
  (segment (start 101.2 116.55) (end 101.935 116.55) (width 0.15) (layer "B.Cu") (net 211))
  (segment (start 98.75 96.6) (end 98.75 96.2) (width 0.15) (layer "B.Cu") (net 211))
  (segment (start 104.4 116.55) (end 105.135 116.55) (width 0.15) (layer "B.Cu") (net 211))
  (segment (start 102.8 116.55) (end 103.485 116.55) (width 0.15) (layer "B.Cu") (net 211))
  (segment (start 100.915 118.95) (end 100.915 119.235) (width 0.15) (layer "B.Cu") (net 211))
  (segment (start 111.85 128.45) (end 111.15 128.45) (width 0.3) (layer "B.Cu") (net 211))
  (segment (start 106 116.55) (end 106.735 116.55) (width 0.15) (layer "B.Cu") (net 211))
  (segment (start 100.5 117.485) (end 100.5 118.05) (width 0.15) (layer "B.Cu") (net 211))
  (segment (start 99.615 98.135) (end 99.049992 98.700008) (width 0.2) (layer "B.Cu") (net 211))
  (segment (start 103 100.05) (end 103 100.95) (width 0.2) (layer "B.Cu") (net 211))
  (segment (start 100.915 119.235) (end 100.4 119.75) (width 0.15) (layer "B.Cu") (net 211))
  (segment (start 96.885 127.75) (end 97.45 127.75) (width 0.15) (layer "B.Cu") (net 211))
  (segment (start 103 100.95) (end 102.2 100.95) (width 0.2) (layer "B.Cu") (net 211))
  (segment (start 99.615 96.95) (end 99.1 96.95) (width 0.15) (layer "B.Cu") (net 211))
  (segment (start 97.85 128) (end 98.085 128.235) (width 0.3) (layer "B.Cu") (net 211))
  (segment (start 99.1 96.95) (end 98.75 96.6) (width 0.15) (layer "B.Cu") (net 211))
  (segment (start 107.635 119.785) (end 107.6 119.75) (width 0.15) (layer "B.Cu") (net 211))
  (segment (start 112.1 128.7) (end 111.85 128.45) (width 0.3) (layer "B.Cu") (net 211))
  (segment (start 99.615 94.15) (end 98.8 94.15) (width 0.2) (layer "B.Cu") (net 211))
  (segment (start 135.93 166.167501) (end 135.93 167.446) (width 0.15) (layer "F.Cu") (net 212))
  (segment (start 135.805 164.88) (end 135.805 166.042501) (width 0.15) (layer "F.Cu") (net 212))
  (segment (start 135.93 167.446) (end 135.55 167.826) (width 0.15) (layer "F.Cu") (net 212))
  (segment (start 135.805 166.042501) (end 135.93 166.167501) (width 0.15) (layer "F.Cu") (net 212))
  (segment (start 127.18 167.446) (end 127.56 167.826) (width 0.15) (layer "F.Cu") (net 213))
  (segment (start 127.18 166.167501) (end 127.18 167.446) (width 0.15) (layer "F.Cu") (net 213))
  (segment (start 127.305 164.88) (end 127.305 166.042501) (width 0.15) (layer "F.Cu") (net 213))
  (segment (start 127.305 166.042501) (end 127.18 166.167501) (width 0.15) (layer "F.Cu") (net 213))
  (segment (start 130.18 166.167501) (end 130.18 167.446) (width 0.15) (layer "F.Cu") (net 214))
  (segment (start 130.305 166.042501) (end 130.18 166.167501) (width 0.15) (layer "F.Cu") (net 214))
  (segment (start 130.18 167.446) (end 130.56 167.826) (width 0.15) (layer "F.Cu") (net 214))
  (segment (start 130.305 164.88) (end 130.305 166.042501) (width 0.15) (layer "F.Cu") (net 214))
  (segment (start 133.18 167.446) (end 133.56 167.826) (width 0.15) (layer "F.Cu") (net 215))
  (segment (start 133.18 166.167501) (end 133.18 167.446) (width 0.15) (layer "F.Cu") (net 215))
  (segment (start 133.305 166.042501) (end 133.18 166.167501) (width 0.15) (layer "F.Cu") (net 215))
  (segment (start 133.305 164.88) (end 133.305 166.042501) (width 0.15) (layer "F.Cu") (net 215))
  (segment (start 136.305 164.88) (end 136.305 166.042501) (width 0.15) (layer "F.Cu") (net 216))
  (segment (start 136.305 166.042501) (end 136.18 166.167501) (width 0.15) (layer "F.Cu") (net 216))
  (segment (start 136.18 167.446) (end 136.56 167.826) (width 0.15) (layer "F.Cu") (net 216))
  (segment (start 136.18 166.167501) (end 136.18 167.446) (width 0.15) (layer "F.Cu") (net 216))
  (segment (start 74.835 117.07) (end 74.835 118.07) (width 0.2) (layer "F.Cu") (net 217))
  (segment (start 81.1 120.55) (end 81.5 120.95) (width 0.15) (layer "F.Cu") (net 217))
  (segment (start 74.82 119.4325) (end 74.82 118.13) (width 0.15) (layer "F.Cu") (net 217))
  (segment (start 94.4 121.75) (end 94 122.15) (width 0.15) (layer "F.Cu") (net 217))
  (segment (start 87.45 122.985) (end 86.69 123.745) (width 0.15) (layer "F.Cu") (net 217))
  (segment (start 87.45 122.7) (end 87.45 122.985) (width 0.15) (layer "F.Cu") (net 217))
  (via (at 81.5 120.95) (size 0.5) (drill 0.2) (layers "F.Cu" "B.Cu") (net 217))
  (via (at 74.81 118.56) (size 0.5) (drill 0.2) (layers "F.Cu" "B.Cu") (net 217))
  (via (at 94 122.15) (size 0.5) (drill 0.2) (layers "F.Cu" "B.Cu") (net 217))
  (via (at 87.45 122.7) (size 0.5) (drill 0.2) (layers "F.Cu" "B.Cu") (net 217))
  (segment (start 87.75 122.55) (end 87.75 122.1) (width 0.3) (layer "B.Cu") (net 217))
  (segment (start 91.45 121.4) (end 91.25 121.6) (width 0.3) (layer "B.Cu") (net 217))
  (segment (start 94 122.15) (end 93.25 121.4) (width 0.3) (layer "B.Cu") (net 217))
  (segment (start 87.75 122.085) (end 91.235 122.085) (width 0.3) (layer "B.Cu") (net 217))
  (segment (start 93.25 121.4) (end 91.45 121.4) (width 0.3) (layer "B.Cu") (net 217))
  (segment (start 87.45 122.7) (end 87.6 122.7) (width 0.3) (layer "B.Cu") (net 217))
  (segment (start 91.25 121.6) (end 91.25 122.1) (width 0.3) (layer "B.Cu") (net 217))
  (segment (start 94 122.15) (end 94 123) (width 0.15) (layer "B.Cu") (net 217))
  (segment (start 87.6 122.7) (end 87.75 122.55) (width 0.3) (layer "B.Cu") (net 217))
  (segment (start 81.5 120.95) (end 81.95 120.5) (width 0.1) (layer "B.Cu") (net 217))
  (segment (start 121.484056 85.468104) (end 121.484056 87.718104) (width 0.7) (layer "F.Cu") (net 218))
  (segment (start 109.6 118.55) (end 109.2 118.95) (width 0.15) (layer "F.Cu") (net 218))
  (segment (start 109.6 119.35) (end 109.2 118.95) (width 0.15) (layer "F.Cu") (net 218))
  (segment (start 128.115 153.775) (end 128.115 153.055) (width 0.25) (layer "F.Cu") (net 218))
  (segment (start 109.6 116.95) (end 109.2 116.55) (width 0.15) (layer "F.Cu") (net 218))
  (segment (start 109.6 120.15) (end 109.2 120.55) (width 0.15) (layer "F.Cu") (net 218))
  (via (at 121.484056 87.018104) (size 0.6) (drill 0.3) (layers "F.Cu" "B.Cu") (net 218))
  (via (at 121.484056 87.718104) (size 0.6) (drill 0.3) (layers "F.Cu" "B.Cu") (net 218))
  (via (at 121.484056 86.318104) (size 0.6) (drill 0.3) (layers "F.Cu" "B.Cu") (net 218))
  (via (at 109.2 118.95) (size 0.5) (drill 0.2) (layers "F.Cu" "B.Cu") (net 218))
  (via (at 109.2 120.55) (size 0.5) (drill 0.2) (layers "F.Cu" "B.Cu") (net 218))
  (via (at 109.2 116.55) (size 0.5) (drill 0.2) (layers "F.Cu" "B.Cu") (net 218))
  (via (at 128.1 153.045) (size 0.5) (drill 0.2) (layers "F.Cu" "B.Cu") (net 218))
  (segment (start 109.2 121.25) (end 109.2 120.55) (width 0.15) (layer "B.Cu") (net 218))
  (segment (start 109.7 116.05) (end 109.2 116.55) (width 0.15) (layer "B.Cu") (net 218))
  (segment (start 109.585 118.565) (end 109.2 118.95) (width 0.15) (layer "B.Cu") (net 218))
  (segment (start 110.015 116.05) (end 109.7 116.05) (width 0.15) (layer "B.Cu") (net 218))
  (segment (start 110.715 118.15) (end 109.65 118.15) (width 0.15) (layer "B.Cu") (net 218))
  (segment (start 109.635 120.115) (end 109.2 120.55) (width 0.15) (layer "B.Cu") (net 218))
  (segment (start 109.585 118.15) (end 109.585 118.565) (width 0.15) (layer "B.Cu") (net 218))
  (segment (start 109.635 119.65) (end 109.635 120.115) (width 0.15) (layer "B.Cu") (net 218))
  (segment (start 84.3 99.6) (end 83.8 99.1) (width 0.25) (layer "F.Cu") (net 219))
  (via (at 83.8 99.1) (size 0.5) (drill 0.2) (layers "F.Cu" "B.Cu") (net 219))
  (segment (start 83.31 98.61) (end 83.8 99.1) (width 0.25) (layer "B.Cu") (net 219))
  (segment (start 83.31 98.435) (end 83.31 98.61) (width 0.25) (layer "B.Cu") (net 219))
  (segment (start 83.31 99.59) (end 83.8 99.1) (width 0.25) (layer "B.Cu") (net 219))
  (segment (start 92.085 143.6) (end 92.75 143.6) (width 0.2) (layer "F.Cu") (net 220))
  (segment (start 91.15 143.165) (end 91.15 141.6) (width 0.2) (layer "F.Cu") (net 220))
  (segment (start 92.8 142.75) (end 91.6 141.55) (width 0.2) (layer "F.Cu") (net 220))
  (segment (start 92.75 143.6) (end 92.8 143.55) (width 0.2) (layer "F.Cu") (net 220))
  (segment (start 91.6 141.55) (end 91.1 141.55) (width 0.2) (layer "F.Cu") (net 220))
  (segment (start 91.15 141.6) (end 91.1 141.55) (width 0.2) (layer "F.Cu") (net 220))
  (segment (start 92.8 143.55) (end 92.8 142.75) (width 0.2) (layer "F.Cu") (net 220))
  (segment (start 91.1 141.55) (end 86.2 141.55) (width 0.2) (layer "F.Cu") (net 220))
  (segment (start 125.175 129.9) (end 125.175 129.735) (width 0.15) (layer "F.Cu") (net 221))
  (segment (start 125.175 129.735) (end 125.205 129.705) (width 0.15) (layer "F.Cu") (net 221))
  (segment (start 125.205 129.705) (end 125.205 129.05) (width 0.15) (layer "F.Cu") (net 221))
  (via (at 125.175 129.9) (size 0.5) (drill 0.2) (layers "F.Cu" "B.Cu") (net 221))
  (segment (start 125.175 129.9) (end 125.175 130.65) (width 0.2) (layer "B.Cu") (net 221))
  (segment (start 125.16 130.7) (end 126.125 130.7) (width 0.2) (layer "B.Cu") (net 221))
  (segment (start 82.35 85.9) (end 81.9 86.35) (width 0.15) (layer "F.Cu") (net 222))
  (segment (start 81.9 86.35) (end 81.75 86.35) (width 0.15) (layer "F.Cu") (net 222))
  (segment (start 82.35 85.475) (end 82.35 85.9) (width 0.15) (layer "F.Cu") (net 222))
  (via (at 81.75 86.35) (size 0.5) (drill 0.2) (layers "F.Cu" "B.Cu") (net 222))
  (via (at 75 91.2) (size 0.5) (drill 0.2) (layers "F.Cu" "B.Cu") (net 222))
  (segment (start 81.75 86.35) (end 79.85 86.35) (width 0.15) (layer "In5.Cu") (net 222))
  (segment (start 79.85 86.35) (end 75 91.2) (width 0.15) (layer "In5.Cu") (net 222))
  (segment (start 81.75 86.35) (end 82.15 86.35) (width 0.15) (layer "B.Cu") (net 222))
  (segment (start 68.9 91.2) (end 68.4 91.7) (width 0.15) (layer "B.Cu") (net 222))
  (segment (start 68.4 91.7) (end 68.4 92.15) (width 0.15) (layer "B.Cu") (net 222))
  (segment (start 75 91.2) (end 68.9 91.2) (width 0.15) (layer "B.Cu") (net 222))
  (segment (start 82.55 86.75) (end 82.55 87.55) (width 0.15) (layer "B.Cu") (net 222))
  (segment (start 82.15 86.35) (end 82.55 86.75) (width 0.15) (layer "B.Cu") (net 222))
  (segment (start 116.4 83) (end 117.20716 83) (width 0.15) (layer "F.Cu") (net 223))
  (via (at 76.2 91.5) (size 0.5) (drill 0.2) (layers "F.Cu" "B.Cu") (net 223))
  (via (at 116.4 83) (size 0.5) (drill 0.2) (layers "F.Cu" "B.Cu") (net 223))
  (segment (start 76.2 90.8) (end 76.2 91.5) (width 0.15) (layer "In5.Cu") (net 223))
  (segment (start 117.4 84) (end 116.4 83) (width 0.15) (layer "In5.Cu") (net 223))
  (segment (start 95.15 86.525) (end 93.55 88.125) (width 0.15) (layer "In5.Cu") (net 223))
  (segment (start 117.4 84.5) (end 115.375 86.525) (width 0.15) (layer "In5.Cu") (net 223))
  (segment (start 115.375 86.525) (end 95.15 86.525) (width 0.15) (layer "In5.Cu") (net 223))
  (segment (start 78.875 88.125) (end 76.2 90.8) (width 0.15) (layer "In5.Cu") (net 223))
  (segment (start 93.55 88.125) (end 78.875 88.125) (width 0.15) (layer "In5.Cu") (net 223))
  (segment (start 117.4 84.5) (end 117.4 84) (width 0.15) (layer "In5.Cu") (net 223))
  (segment (start 117.424056 84.024056) (end 116.4 83) (width 0.15) (layer "B.Cu") (net 223))
  (segment (start 117.424056 89.493104) (end 117.424056 84.024056) (width 0.15) (layer "B.Cu") (net 223))
  (segment (start 76.2 91.5) (end 76.2 92.25) (width 0.15) (layer "B.Cu") (net 223))
  (segment (start 76.175 85.475) (end 76.4 85.475) (width 0.25) (layer "F.Cu") (net 224))
  (segment (start 75.5 86.15) (end 76.175 85.475) (width 0.25) (layer "F.Cu") (net 224))
  (via (at 75.5 86.15) (size 0.5) (drill 0.2) (layers "F.Cu" "B.Cu") (net 224))
  (segment (start 75.5 86.15) (end 74.75 86.9) (width 0.15) (layer "B.Cu") (net 224))
  (segment (start 73.85 86.9) (end 73.7 87.05) (width 0.15) (layer "B.Cu") (net 224))
  (segment (start 69.8 87.55) (end 69.2 88.15) (width 0.15) (layer "B.Cu") (net 224))
  (segment (start 69.2 88.15) (end 68.25 88.15) (width 0.15) (layer "B.Cu") (net 224))
  (segment (start 73.715 87.55) (end 69.8 87.55) (width 0.15) (layer "B.Cu") (net 224))
  (segment (start 74.75 86.9) (end 73.85 86.9) (width 0.15) (layer "B.Cu") (net 224))
  (segment (start 73.7 87.05) (end 73.7 87.45) (width 0.15) (layer "B.Cu") (net 224))
  (segment (start 92.6 87.95) (end 92.6 90.2) (width 0.7) (layer "F.Cu") (net 225))
  (via (at 92.6 89.5) (size 0.6) (drill 0.3) (layers "F.Cu" "B.Cu") (net 225))
  (via (at 92.6 90.2) (size 0.6) (drill 0.3) (layers "F.Cu" "B.Cu") (net 225))
  (via (at 92.6 88.8) (size 0.6) (drill 0.3) (layers "F.Cu" "B.Cu") (net 225))
  (via (at 113.48 134.67) (size 0.5) (drill 0.2) (layers "F.Cu" "B.Cu") (net 225))
  (segment (start 113.8 134.35) (end 113.48 134.67) (width 0.25) (layer "B.Cu") (net 225))
  (segment (start 113.45 134.64) (end 113.48 134.67) (width 0.3) (layer "B.Cu") (net 225))
  (segment (start 113.8 133.25) (end 113.8 134.35) (width 0.25) (layer "B.Cu") (net 225))
  (segment (start 127.42 115.55) (end 128.235 115.55) (width 0.15) (layer "F.Cu") (net 226))
  (segment (start 128.235 115.55) (end 128.285 115.5) (width 0.15) (layer "F.Cu") (net 226))
  (via (at 128.285 115.5) (size 0.5) (drill 0.2) (layers "F.Cu" "B.Cu") (net 226))
  (segment (start 128.87 115.5) (end 128.885 115.515) (width 0.15) (layer "B.Cu") (net 226))
  (segment (start 128.285 115.5) (end 128.87 115.5) (width 0.15) (layer "B.Cu") (net 226))
  (segment (start 129.165 115.525) (end 129.165 116.54) (width 0.2) (layer "B.Cu") (net 226))
  (segment (start 123.705 124.18) (end 123.705 123.290497) (width 0.15) (layer "F.Cu") (net 227))
  (segment (start 123.705 123.290497) (end 123.655565 123.241062) (width 0.15) (layer "F.Cu") (net 227))
  (segment (start 123.475 129.975) (end 123.475 129.86) (width 0.15) (layer "F.Cu") (net 227))
  (segment (start 123.475 129.86) (end 123.705 129.63) (width 0.15) (layer "F.Cu") (net 227))
  (segment (start 123.705 129.63) (end 123.705 129.05) (width 0.15) (layer "F.Cu") (net 227))
  (via (at 123.655565 123.241062) (size 0.5) (drill 0.2) (layers "F.Cu" "B.Cu") (net 227))
  (via (at 123.475 130) (size 0.5) (drill 0.2) (layers "F.Cu" "B.Cu") (net 227))
  (segment (start 123.475 130) (end 123.655565 129.819435) (width 0.5) (layer "In6.Cu") (net 227))
  (segment (start 123.655565 129.819435) (end 123.655565 123.241062) (width 0.5) (layer "In6.Cu") (net 227))
  (segment (start 123.475 130) (end 123.475 130.225) (width 0.2) (layer "B.Cu") (net 227))
  (segment (start 123.655565 123.241062) (end 123.655565 124.105565) (width 0.2) (layer "B.Cu") (net 227))
  (segment (start 123.475 130.225) (end 123 130.7) (width 0.2) (layer "B.Cu") (net 227))
  (segment (start 80.64 124.61) (end 80.64 122.56) (width 0.15) (layer "B.Cu") (net 228))
  (segment (start 75.95 75.525) (end 74.849143 75.525) (width 0.2) (layer "F.Cu") (net 229))
  (segment (start 76.25 75.225) (end 75.95 75.525) (width 0.2) (layer "F.Cu") (net 229))
  (segment (start 76.25 74.235) (end 76.25 75.225) (width 0.2) (layer "F.Cu") (net 229))
  (segment (start 87.825 86.875) (end 88.35 86.875) (width 0.25) (layer "F.Cu") (net 230))
  (segment (start 71.4 76) (end 71.75 75.65) (width 0.15) (layer "F.Cu") (net 230))
  (segment (start 71.75 75.65) (end 72.2 75.65) (width 0.15) (layer "F.Cu") (net 230))
  (via (at 87.75 87) (size 0.5) (drill 0.2) (layers "F.Cu" "B.Cu") (net 230))
  (via (at 71.4 76) (size 0.5) (drill 0.2) (layers "F.Cu" "B.Cu") (net 230))
  (segment (start 82.25 85.85) (end 81.3 85.85) (width 0.15) (layer "B.Cu") (net 230))
  (segment (start 72 76) (end 71.4 76) (width 0.15) (layer "B.Cu") (net 230))
  (segment (start 77 86.95) (end 76.6 86.55) (width 0.15) (layer "B.Cu") (net 230))
  (segment (start 72.2 77.6) (end 72.2 76.2) (width 0.15) (layer "B.Cu") (net 230))
  (segment (start 87.65 86.9) (end 83.3 86.9) (width 0.15) (layer "B.Cu") (net 230))
  (segment (start 87.75 87) (end 87.65 86.9) (width 0.15) (layer "B.Cu") (net 230))
  (segment (start 81.3 85.85) (end 80.2 86.95) (width 0.15) (layer "B.Cu") (net 230))
  (segment (start 80.2 86.95) (end 77 86.95) (width 0.15) (layer "B.Cu") (net 230))
  (segment (start 76.6 86.55) (end 76.6 82) (width 0.15) (layer "B.Cu") (net 230))
  (segment (start 72.2 76.2) (end 72 76) (width 0.15) (layer "B.Cu") (net 230))
  (segment (start 76.6 82) (end 72.2 77.6) (width 0.15) (layer "B.Cu") (net 230))
  (segment (start 83.3 86.9) (end 82.25 85.85) (width 0.15) (layer "B.Cu") (net 230))
  (segment (start 81.825 86.875) (end 82.35 86.875) (width 0.25) (layer "F.Cu") (net 231))
  (segment (start 116.714056 84.368104) (end 117.239056 84.368104) (width 0.25) (layer "F.Cu") (net 231))
  (segment (start 75.95 87.45) (end 76.2 87.45) (width 0.2) (layer "F.Cu") (net 231))
  (segment (start 71.4 76.7) (end 72.25 76.7) (width 0.15) (layer "F.Cu") (net 231))
  (segment (start 76.4 87.25) (end 76.4 86.825) (width 0.2) (layer "F.Cu") (net 231))
  (segment (start 76.2 87.45) (end 76.4 87.25) (width 0.2) (layer "F.Cu") (net 231))
  (via (at 116.639056 84.493104) (size 0.5) (drill 0.2) (layers "F.Cu" "B.Cu") (net 231))
  (via (at 81.75 87) (size 0.5) (drill 0.2) (layers "F.Cu" "B.Cu") (net 231))
  (via (at 71.4 76.7) (size 0.5) (drill 0.2) (layers "F.Cu" "B.Cu") (net 231))
  (via (at 75.95 87.45) (size 0.5) (drill 0.2) (layers "F.Cu" "B.Cu") (net 231))
  (segment (start 93.55 87.5) (end 94.875 86.175) (width 0.15) (layer "In5.Cu") (net 231))
  (segment (start 114.95716 86.175) (end 116.639056 84.493104) (width 0.15) (layer "In5.Cu") (net 231))
  (segment (start 86.65 86.85) (end 87.3 87.5) (width 0.15) (layer "In5.Cu") (net 231))
  (segment (start 81.75 87) (end 81.9 86.85) (width 0.15) (layer "In5.Cu") (net 231))
  (segment (start 87.3 87.5) (end 93.55 87.5) (width 0.15) (layer "In5.Cu") (net 231))
  (segment (start 94.875 86.175) (end 114.95716 86.175) (width 0.15) (layer "In5.Cu") (net 231))
  (segment (start 81.9 86.85) (end 86.65 86.85) (width 0.15) (layer "In5.Cu") (net 231))
  (segment (start 80.9 87.25) (end 76.4 87.25) (width 0.15) (layer "B.Cu") (net 231))
  (segment (start 76.3 87.15) (end 76 87.45) (width 0.15) (layer "B.Cu") (net 231))
  (segment (start 76.3 82.15) (end 76.3 87.15) (width 0.15) (layer "B.Cu") (net 231))
  (segment (start 76 87.45) (end 75.95 87.45) (width 0.15) (layer "B.Cu") (net 231))
  (segment (start 81.15 87) (end 80.9 87.25) (width 0.15) (layer "B.Cu") (net 231))
  (segment (start 71.4 77.25) (end 76.3 82.15) (width 0.15) (layer "B.Cu") (net 231))
  (segment (start 81.75 87) (end 81.15 87) (width 0.15) (layer "B.Cu") (net 231))
  (segment (start 76.4 87.25) (end 76.3 87.15) (width 0.15) (layer "B.Cu") (net 231))
  (segment (start 71.4 76.7) (end 71.4 77.25) (width 0.15) (layer "B.Cu") (net 231))
  (segment (start 91.95 62.25) (end 93.1 62.25) (width 0.25) (layer "F.Cu") (net 232))
  (segment (start 91.92 64.55) (end 91.92 62.28) (width 0.25) (layer "F.Cu") (net 232))
  (segment (start 74.485 62.35) (end 75.45 62.35) (width 0.25) (layer "F.Cu") (net 233))
  (segment (start 91.28 71.425) (end 90.81 71.895) (width 0.25) (layer "F.Cu") (net 234))
  (segment (start 90.62 70.45) (end 90.62 71.43) (width 0.25) (layer "F.Cu") (net 234))
  (segment (start 90.62 71.43) (end 90.15 71.9) (width 0.25) (layer "F.Cu") (net 234))
  (segment (start 90.15 71.595) (end 90.15 71.9) (width 0.25) (layer "F.Cu") (net 234))
  (segment (start 89.98 70.45) (end 89.98 71.425) (width 0.25) (layer "F.Cu") (net 234))
  (segment (start 89.98 71.425) (end 90.15 71.595) (width 0.25) (layer "F.Cu") (net 234))
  (segment (start 91.28 70.45) (end 91.28 71.425) (width 0.25) (layer "F.Cu") (net 234))
  (segment (start 89.41 71.505) (end 89.41 71.9) (width 0.25) (layer "F.Cu") (net 234))
  (segment (start 88.68 70.45) (end 88.68 71.89) (width 0.25) (layer "F.Cu") (net 234))
  (segment (start 88.68 71.89) (end 88.69 71.9) (width 0.25) (layer "F.Cu") (net 234))
  (segment (start 88.03 70.45) (end 88.03 71.84) (width 0.25) (layer "F.Cu") (net 234))
  (segment (start 89.33 70.45) (end 89.33 71.425) (width 0.25) (layer "F.Cu") (net 234))
  (segment (start 89.33 71.425) (end 89.41 71.505) (width 0.25) (layer "F.Cu") (net 234))
  (segment (start 90.65 71.9) (end 85.895 71.9) (width 0.8) (layer "F.Cu") (net 234))
  (segment (start 85.895 71.9) (end 84.9 72.895) (width 0.8) (layer "F.Cu") (net 234))
  (segment (start 84.9 72.895) (end 84.9 75.25) (width 0.8) (layer "F.Cu") (net 234))
  (segment (start 91.92 70.45) (end 91.92 71.59) (width 0.25) (layer "F.Cu") (net 235))
  (segment (start 91.92 71.59) (end 91.68 71.83) (width 0.25) (layer "F.Cu") (net 235))
  (segment (start 84.75 78.9) (end 85.6 78.9) (width 0.2) (layer "F.Cu") (net 235))
  (via (at 91.68 71.83) (size 0.5) (drill 0.2) (layers "F.Cu" "B.Cu") (net 235))
  (via (at 84.75 78.9) (size 0.5) (drill 0.2) (layers "F.Cu" "B.Cu") (net 235))
  (via (at 68.65 86.55) (size 0.5) (drill 0.2) (layers "F.Cu" "B.Cu") (net 235))
  (segment (start 76.45 78) (end 76.2 78.25) (width 0.15) (layer "In5.Cu") (net 235))
  (segment (start 76.2 84.45) (end 73.95 86.7) (width 0.15) (layer "In5.Cu") (net 235))
  (segment (start 89.08 74.43) (end 89.08 77.42) (width 0.15) (layer "In5.Cu") (net 235))
  (segment (start 68.8 86.7) (end 68.65 86.55) (width 0.15) (layer "In5.Cu") (net 235))
  (segment (start 73.95 86.7) (end 68.8 86.7) (width 0.15) (layer "In5.Cu") (net 235))
  (segment (start 77.6 77.55) (end 77.15 78) (width 0.15) (layer "In5.Cu") (net 235))
  (segment (start 83.425 77.55) (end 77.6 77.55) (width 0.15) (layer "In5.Cu") (net 235))
  (segment (start 84.775 78.9) (end 83.425 77.55) (width 0.15) (layer "In5.Cu") (net 235))
  (segment (start 89.08 77.42) (end 87.6 78.9) (width 0.15) (layer "In5.Cu") (net 235))
  (segment (start 76.2 78.25) (end 76.2 84.45) (width 0.15) (layer "In5.Cu") (net 235))
  (segment (start 77.15 78) (end 76.45 78) (width 0.15) (layer "In5.Cu") (net 235))
  (segment (start 91.68 71.83) (end 89.08 74.43) (width 0.15) (layer "In5.Cu") (net 235))
  (segment (start 87.6 78.9) (end 84.775 78.9) (width 0.15) (layer "In5.Cu") (net 235))
  (segment (start 70.15 86) (end 69.2 86) (width 0.15) (layer "B.Cu") (net 235))
  (segment (start 69.2 86) (end 68.65 86.55) (width 0.15) (layer "B.Cu") (net 235))
  (segment (start 87.825 85.475) (end 88.35 85.475) (width 0.25) (layer "F.Cu") (net 236))
  (segment (start 87.725 85.375) (end 87.825 85.475) (width 0.25) (layer "F.Cu") (net 236))
  (via (at 87.725 85.375) (size 0.5) (drill 0.2) (layers "F.Cu" "B.Cu") (net 236))
  (segment (start 88.4 88.25) (end 88.65 88) (width 0.15) (layer "B.Cu") (net 236))
  (segment (start 88.65 86.3) (end 88.65 87.55) (width 0.15) (layer "B.Cu") (net 236))
  (segment (start 87.725 85.375) (end 88.65 86.3) (width 0.15) (layer "B.Cu") (net 236))
  (segment (start 88.65 88) (end 88.65 87.55) (width 0.15) (layer "B.Cu") (net 236))
  (segment (start 72.3 88.25) (end 88.4 88.25) (width 0.15) (layer "B.Cu") (net 236))
  (segment (start 94.4 120.15) (end 94 120.55) (width 0.1) (layer "F.Cu") (net 237))
  (segment (start 83.721757 118.968979) (end 83.71925 118.991232) (width 0.1) (layer "F.Cu") (net 237))
  (segment (start 83.81925 119.091232) (end 83.9 119.091232) (width 0.1) (layer "F.Cu") (net 237))
  (segment (start 84 119.191232) (end 84 119.95) (width 0.1) (layer "F.Cu") (net 237))
  (segment (start 84.611111 117.352533) (end 84.593604 117.338571) (width 0.1) (layer "F.Cu") (net 237))
  (segment (start 84.100033 118.308911) (end 84.09505 118.330743) (width 0.1) (layer "F.Cu") (net 237))
  (segment (start 84.443159 118.042872) (end 84.442244 118.046878) (width 0.1) (layer "F.Cu") (net 237))
  (segment (start 84.290588 117.611697) (end 84.268756 117.606714) (width 0.1) (layer "F.Cu") (net 237))
  (segment (start 83.990096 118.83462) (end 83.978183 118.85358) (width 0.1) (layer "F.Cu") (net 237))
  (segment (start 84.299691 118.171829) (end 84.29648 118.169267) (width 0.1) (layer "F.Cu") (net 237))
  (segment (start 83.796997 119.088724) (end 83.81925 119.091232) (width 0.1) (layer "F.Cu") (net 237))
  (segment (start 84.442245 118.034758) (end 84.443159 118.038764) (width 0.1) (layer "F.Cu") (net 237))
  (segment (start 84.551597 117.323872) (end 84.529204 117.323872) (width 0.1) (layer "F.Cu") (net 237))
  (segment (start 84.882217 117.543577) (end 84.860385 117.54856) (width 0.1) (layer "F.Cu") (net 237))
  (segment (start 84.02792 117.904256) (end 84.007745 117.89454) (width 0.1) (layer "F.Cu") (net 237))
  (segment (start 84.32827 117.635374) (end 84.310763 117.621413) (width 0.1) (layer "F.Cu") (net 237))
  (segment (start 84.224532 117.611697) (end 84.204356 117.621413) (width 0.1) (layer "F.Cu") (net 237))
  (segment (start 83.890044 118.04213) (end 83.904006 118.059638) (width 0.1) (layer "F.Cu") (net 237))
  (segment (start 83.741066 119.05358) (end 83.756901 119.069415) (width 0.1) (layer "F.Cu") (net 237))
  (segment (start 84.441029 117.43444) (end 84.446012 117.456271) (width 0.1) (layer "F.Cu") (net 237))
  (segment (start 83.756901 118.913048) (end 83.741066 118.928883) (width 0.1) (layer "F.Cu") (net 237))
  (segment (start 84.778478 117.5199) (end 84.611111 117.352533) (width 0.1) (layer "F.Cu") (net 237))
  (segment (start 83.943388 118.881328) (end 83.922252 118.888724) (width 0.1) (layer "F.Cu") (net 237))
  (segment (start 83.904006 117.918217) (end 83.890044 117.935724) (width 0.1) (layer "F.Cu") (net 237))
  (segment (start 84.246363 117.606714) (end 84.224532 117.611697) (width 0.1) (layer "F.Cu") (net 237))
  (segment (start 84.158188 117.717281) (end 84.163171 117.739112) (width 0.1) (layer "F.Cu") (net 237))
  (segment (start 84.685577 117.937964) (end 84.670656 117.941369) (width 0.1) (layer "F.Cu") (net 237))
  (segment (start 84.507372 117.328855) (end 84.487197 117.338571) (width 0.1) (layer "F.Cu") (net 237))
  (segment (start 84.310763 117.621413) (end 84.290588 117.611697) (width 0.1) (layer "F.Cu") (net 237))
  (segment (start 84.311506 118.174526) (end 84.307398 118.174526) (width 0.1) (layer "F.Cu") (net 237))
  (segment (start 84.4379 118.027846) (end 84.440462 118.031058) (width 0.1) (layer "F.Cu") (net 237))
  (segment (start 84.440462 118.031058) (end 84.442245 118.034758) (width 0.1) (layer "F.Cu") (net 237))
  (segment (start 85.0898 117.35) (end 84.9199 117.5199) (width 0.1) (layer "F.Cu") (net 237))
  (segment (start 84.085334 118.350918) (end 84.071372 118.368425) (width 0.1) (layer "F.Cu") (net 237))
  (segment (start 84.071372 118.368425) (end 84 118.4398) (width 0.1) (layer "F.Cu") (net 237))
  (segment (start 84.442244 118.046878) (end 84.440463 118.050578) (width 0.1) (layer "F.Cu") (net 237))
  (segment (start 84.455728 117.476446) (end 84.46969 117.493954) (width 0.1) (layer "F.Cu") (net 237))
  (segment (start 84.775685 117.836341) (end 84.77228 117.851261) (width 0.1) (layer "F.Cu") (net 237))
  (segment (start 84.487197 117.338571) (end 84.46969 117.352533) (width 0.1) (layer "F.Cu") (net 237))
  (segment (start 84.100033 118.286518) (end 84.100033 118.308911) (width 0.1) (layer "F.Cu") (net 237))
  (segment (start 83.922252 119.093739) (end 83.943388 119.101135) (width 0.1) (layer "F.Cu") (net 237))
  (segment (start 84.446012 117.390215) (end 84.441029 117.412047) (width 0.1) (layer "F.Cu") (net 237))
  (segment (start 83.921513 117.904256) (end 83.904006 117.918217) (width 0.1) (layer "F.Cu") (net 237))
  (segment (start 83.729153 118.947843) (end 83.721757 118.968979) (width 0.1) (layer "F.Cu") (net 237))
  (segment (start 84.837992 117.54856) (end 84.816161 117.543577) (width 0.1) (layer "F.Cu") (net 237))
  (segment (start 84.172887 117.652881) (end 84.163171 117.673056) (width 0.1) (layer "F.Cu") (net 237))
  (segment (start 84.09505 118.330743) (end 84.085334 118.350918) (width 0.1) (layer "F.Cu") (net 237))
  (segment (start 84.593604 117.338571) (end 84.573428 117.328855) (width 0.1) (layer "F.Cu") (net 237))
  (segment (start 83.775861 118.901135) (end 83.756901 118.913048) (width 0.1) (layer "F.Cu") (net 237))
  (segment (start 84.071372 118.227004) (end 84.085334 118.244511) (width 0.1) (layer "F.Cu") (net 237))
  (segment (start 83.81925 118.891232) (end 83.796997 118.893739) (width 0.1) (layer "F.Cu") (net 237))
  (segment (start 84.772279 117.806115) (end 84.775686 117.821035) (width 0.1) (layer "F.Cu") (net 237))
  (segment (start 84.756096 117.78036) (end 84.76564 117.792325) (width 0.1) (layer "F.Cu") (net 237))
  (segment (start 83.796997 118.893739) (end 83.775861 118.901135) (width 0.1) (layer "F.Cu") (net 237))
  (segment (start 83.741066 118.928883) (end 83.729153 118.947843) (width 0.1) (layer "F.Cu") (net 237))
  (segment (start 83.9 119.091232) (end 83.922252 119.093739) (width 0.1) (layer "F.Cu") (net 237))
  (segment (start 83.962348 118.869415) (end 83.943388 118.881328) (width 0.1) (layer "F.Cu") (net 237))
  (segment (start 84.268756 117.606714) (end 84.246363 117.606714) (width 0.1) (layer "F.Cu") (net 237))
  (segment (start 84.529204 117.323872) (end 84.507372 117.328855) (width 0.1) (layer "F.Cu") (net 237))
  (segment (start 84.756096 117.877016) (end 84.711332 117.921781) (width 0.1) (layer "F.Cu") (net 237))
  (segment (start 83.943388 119.101135) (end 83.962348 119.113048) (width 0.1) (layer "F.Cu") (net 237))
  (segment (start 84.670656 117.941369) (end 84.655352 117.941369) (width 0.1) (layer "F.Cu") (net 237))
  (segment (start 84.795986 117.533861) (end 84.778478 117.5199) (width 0.1) (layer "F.Cu") (net 237))
  (segment (start 83.9 118.891232) (end 83.81925 118.891232) (width 0.1) (layer "F.Cu") (net 237))
  (segment (start 83.997492 118.813484) (end 83.990096 118.83462) (width 0.1) (layer "F.Cu") (net 237))
  (segment (start 83.775861 119.081328) (end 83.796997 119.088724) (width 0.1) (layer "F.Cu") (net 237))
  (segment (start 84.322424 118.169268) (end 84.319213 118.171828) (width 0.1) (layer "F.Cu") (net 237))
  (segment (start 84.303392 118.173612) (end 84.299691 118.171829) (width 0.1) (layer "F.Cu") (net 237))
  (segment (start 84.315512 118.173611) (end 84.311506 118.174526) (width 0.1) (layer "F.Cu") (net 237))
  (segment (start 84.573428 117.328855) (end 84.551597 117.323872) (width 0.1) (layer "F.Cu") (net 237))
  (segment (start 84.163171 117.739112) (end 84.172887 117.759287) (width 0.1) (layer "F.Cu") (net 237))
  (segment (start 84.699366 117.931323) (end 84.685577 117.937964) (width 0.1) (layer "F.Cu") (net 237))
  (segment (start 84.158188 117.694888) (end 84.158188 117.717281) (width 0.1) (layer "F.Cu") (net 237))
  (segment (start 83.978183 118.85358) (end 83.962348 118.869415) (width 0.1) (layer "F.Cu") (net 237))
  (segment (start 83.96352 117.889557) (end 83.941689 117.89454) (width 0.1) (layer "F.Cu") (net 237))
  (segment (start 83.941689 117.89454) (end 83.921513 117.904256) (width 0.1) (layer "F.Cu") (net 237))
  (segment (start 84.045427 117.918217) (end 84.02792 117.904256) (width 0.1) (layer "F.Cu") (net 237))
  (segment (start 84.614676 117.921781) (end 84.32827 117.635374) (width 0.1) (layer "F.Cu") (net 237))
  (segment (start 84.441029 117.412047) (end 84.441029 117.43444) (width 0.1) (layer "F.Cu") (net 237))
  (segment (start 83.875345 118.000124) (end 83.880328 118.021955) (width 0.1) (layer "F.Cu") (net 237))
  (segment (start 84.440463 118.050578) (end 84.437901 118.05379) (width 0.1) (layer "F.Cu") (net 237))
  (segment (start 83.880328 117.955899) (end 83.875345 117.977731) (width 0.1) (layer "F.Cu") (net 237))
  (segment (start 84 118.4398) (end 84 118.791232) (width 0.1) (layer "F.Cu") (net 237))
  (segment (start 83.729153 119.03462) (end 83.741066 119.05358) (width 0.1) (layer "F.Cu") (net 237))
  (segment (start 84.307398 118.174526) (end 84.303392 118.173612) (width 0.1) (layer "F.Cu") (net 237))
  (segment (start 84.655352 117.941369) (end 84.640431 117.937964) (width 0.1) (layer "F.Cu") (net 237))
  (segment (start 83.990096 119.147843) (end 83.997492 119.168979) (width 0.1) (layer "F.Cu") (net 237))
  (segment (start 84.860385 117.54856) (end 84.837992 117.54856) (width 0.1) (layer "F.Cu") (net 237))
  (segment (start 84.46969 117.352533) (end 84.455728 117.37004) (width 0.1) (layer "F.Cu") (net 237))
  (segment (start 84.163171 117.673056) (end 84.158188 117.694888) (width 0.1) (layer "F.Cu") (net 237))
  (segment (start 84.186849 117.776795) (end 84.4379 118.027846) (width 0.1) (layer "F.Cu") (net 237))
  (segment (start 83.721757 119.013484) (end 83.729153 119.03462) (width 0.1) (layer "F.Cu") (net 237))
  (segment (start 84.204356 117.621413) (end 84.186849 117.635374) (width 0.1) (layer "F.Cu") (net 237))
  (segment (start 84.319213 118.171828) (end 84.315512 118.173611) (width 0.1) (layer "F.Cu") (net 237))
  (segment (start 84.816161 117.543577) (end 84.795986 117.533861) (width 0.1) (layer "F.Cu") (net 237))
  (segment (start 83.880328 118.021955) (end 83.890044 118.04213) (width 0.1) (layer "F.Cu") (net 237))
  (segment (start 84.640431 117.937964) (end 84.626642 117.931323) (width 0.1) (layer "F.Cu") (net 237))
  (segment (start 83.904006 118.059638) (end 84.071372 118.227004) (width 0.1) (layer "F.Cu") (net 237))
  (segment (start 84.77228 117.851261) (end 84.765639 117.865051) (width 0.1) (layer "F.Cu") (net 237))
  (segment (start 84 118.791232) (end 83.997492 118.813484) (width 0.1) (layer "F.Cu") (net 237))
  (segment (start 84.76564 117.792325) (end 84.772279 117.806115) (width 0.1) (layer "F.Cu") (net 237))
  (segment (start 84.007745 117.89454) (end 83.985913 117.889557) (width 0.1) (layer "F.Cu") (net 237))
  (segment (start 84.283508 118.156295) (end 84.283505 118.156295) (width 0.1) (layer "F.Cu") (net 237))
  (segment (start 83.985913 117.889557) (end 83.96352 117.889557) (width 0.1) (layer "F.Cu") (net 237))
  (segment (start 84.437901 118.05379) (end 84.322424 118.169268) (width 0.1) (layer "F.Cu") (net 237))
  (segment (start 84.711332 117.921781) (end 84.699366 117.931323) (width 0.1) (layer "F.Cu") (net 237))
  (segment (start 84.283505 118.156295) (end 84.045427 117.918217) (width 0.1) (layer "F.Cu") (net 237))
  (segment (start 84.46969 117.493954) (end 84.756096 117.78036) (width 0.1) (layer "F.Cu") (net 237))
  (segment (start 83.71925 118.991232) (end 83.721757 119.013484) (width 0.1) (layer "F.Cu") (net 237))
  (segment (start 84.9199 117.5199) (end 84.902392 117.533861) (width 0.1) (layer "F.Cu") (net 237))
  (segment (start 84.443159 118.038764) (end 84.443159 118.042872) (width 0.1) (layer "F.Cu") (net 237))
  (segment (start 83.756901 119.069415) (end 83.775861 119.081328) (width 0.1) (layer "F.Cu") (net 237))
  (segment (start 84.09505 118.264687) (end 84.100033 118.286518) (width 0.1) (layer "F.Cu") (net 237))
  (segment (start 83.922252 118.888724) (end 83.9 118.891232) (width 0.1) (layer "F.Cu") (net 237))
  (segment (start 84.186849 117.635374) (end 84.172887 117.652881) (width 0.1) (layer "F.Cu") (net 237))
  (segment (start 83.997492 119.168979) (end 84 119.191232) (width 0.1) (layer "F.Cu") (net 237))
  (segment (start 84.446012 117.456271) (end 84.455728 117.476446) (width 0.1) (layer "F.Cu") (net 237))
  (segment (start 84.626642 117.931323) (end 84.614676 117.921781) (width 0.1) (layer "F.Cu") (net 237))
  (segment (start 84.775686 117.821035) (end 84.775685 117.836341) (width 0.1) (layer "F.Cu") (net 237))
  (segment (start 84.29648 118.169267) (end 84.283508 118.156295) (width 0.1) (layer "F.Cu") (net 237))
  (segment (start 83.962348 119.113048) (end 83.978183 119.128883) (width 0.1) (layer "F.Cu") (net 237))
  (segment (start 83.978183 119.128883) (end 83.990096 119.147843) (width 0.1) (layer "F.Cu") (net 237))
  (segment (start 84.902392 117.533861) (end 84.882217 117.543577) (width 0.1) (layer "F.Cu") (net 237))
  (segment (start 84.085334 118.244511) (end 84.09505 118.264687) (width 0.1) (layer "F.Cu") (net 237))
  (segment (start 84.172887 117.759287) (end 84.186849 117.776795) (width 0.1) (layer "F.Cu") (net 237))
  (segment (start 83.875345 117.977731) (end 83.875345 118.000124) (width 0.1) (layer "F.Cu") (net 237))
  (segment (start 84.455728 117.37004) (end 84.446012 117.390215) (width 0.1) (layer "F.Cu") (net 237))
  (segment (start 83.890044 117.935724) (end 83.880328 117.955899) (width 0.1) (layer "F.Cu") (net 237))
  (segment (start 84.765639 117.865051) (end 84.756096 117.877016) (width 0.1) (layer "F.Cu") (net 237))
  (via (at 94 120.55) (size 0.5) (drill 0.2) (layers "F.Cu" "B.Cu") (net 237))
  (via (at 84 119.95) (size 0.5) (drill 0.2) (layers "F.Cu" "B.Cu") (net 237))
  (segment (start 84.2 120.15) (end 92.6 120.15) (width 0.1) (layer "In2.Cu") (net 237))
  (segment (start 84 119.95) (end 84.2 120.15) (width 0.1) (layer "In2.Cu") (net 237))
  (segment (start 93 120.55) (end 94 120.55) (width 0.1) (layer "In2.Cu") (net 237))
  (segment (start 92.6 120.15) (end 93 120.55) (width 0.1) (layer "In2.Cu") (net 237))
  (segment (start 83.99 119.94) (end 83.99 117.195) (width 0.1) (layer "B.Cu") (net 237))
  (segment (start 83.99 119.94) (end 84 119.95) (width 0.1) (layer "B.Cu") (net 237))
  (segment (start 96 120.15) (end 96.4 120.55) (width 0.1) (layer "F.Cu") (net 238))
  (segment (start 82.93864 118.3907) (end 82.922752 118.400684) (width 0.1) (layer "F.Cu") (net 238))
  (segment (start 82.826049 118.547898) (end 82.807402 118.55) (width 0.1) (layer "F.Cu") (net 238))
  (segment (start 82.922752 118.400684) (end 82.909483 118.413953) (width 0.1) (layer "F.Cu") (net 238))
  (segment (start 82.956352 118.384503) (end 82.93864 118.3907) (width 0.1) (layer "F.Cu") (net 238))
  (segment (start 83.059649 118.400684) (end 83.043761 118.3907) (width 0.1) (layer "F.Cu") (net 238))
  (segment (start 83.109483 118.518448) (end 83.099499 118.50256) (width 0.1) (layer "F.Cu") (net 238))
  (segment (start 82.023929 118.273929) (end 81.9 118.15) (width 0.1) (layer "F.Cu") (net 238))
  (segment (start 83.089099 118.447553) (end 83.082902 118.429841) (width 0.1) (layer "F.Cu") (net 238))
  (segment (start 82.889099 118.484848) (end 82.882902 118.50256) (width 0.1) (layer "F.Cu") (net 238))
  (segment (start 82.843761 118.541701) (end 82.826049 118.547898) (width 0.1) (layer "F.Cu") (net 238))
  (segment (start 83.043761 118.3907) (end 83.026049 118.384503) (width 0.1) (layer "F.Cu") (net 238))
  (segment (start 83.082902 118.429841) (end 83.072918 118.413953) (width 0.1) (layer "F.Cu") (net 238))
  (segment (start 82.859649 118.531717) (end 82.843761 118.541701) (width 0.1) (layer "F.Cu") (net 238))
  (segment (start 83.13864 118.541701) (end 83.122752 118.531717) (width 0.1) (layer "F.Cu") (net 238))
  (segment (start 82.3 118.55) (end 82.023929 118.273929) (width 0.1) (layer "F.Cu") (net 238))
  (segment (start 83.122752 118.531717) (end 83.109483 118.518448) (width 0.1) (layer "F.Cu") (net 238))
  (segment (start 82.807402 118.55) (end 82.3 118.55) (width 0.1) (layer "F.Cu") (net 238))
  (segment (start 83.026049 118.384503) (end 83.007402 118.382402) (width 0.1) (layer "F.Cu") (net 238))
  (segment (start 82.975 118.382402) (end 82.956352 118.384503) (width 0.1) (layer "F.Cu") (net 238))
  (segment (start 83.099499 118.50256) (end 83.093302 118.484848) (width 0.1) (layer "F.Cu") (net 238))
  (segment (start 82.909483 118.413953) (end 82.899499 118.429841) (width 0.1) (layer "F.Cu") (net 238))
  (segment (start 83.007402 118.382402) (end 82.975 118.382402) (width 0.1) (layer "F.Cu") (net 238))
  (segment (start 82.893302 118.447553) (end 82.889099 118.484848) (width 0.1) (layer "F.Cu") (net 238))
  (segment (start 82.872918 118.518448) (end 82.859649 118.531717) (width 0.1) (layer "F.Cu") (net 238))
  (segment (start 82.882902 118.50256) (end 82.872918 118.518448) (width 0.1) (layer "F.Cu") (net 238))
  (segment (start 83.093302 118.484848) (end 83.089099 118.447553) (width 0.1) (layer "F.Cu") (net 238))
  (segment (start 83.5 118.55) (end 83.175 118.55) (width 0.1) (layer "F.Cu") (net 238))
  (segment (start 83.072918 118.413953) (end 83.059649 118.400684) (width 0.1) (layer "F.Cu") (net 238))
  (segment (start 83.175 118.55) (end 83.156352 118.547898) (width 0.1) (layer "F.Cu") (net 238))
  (segment (start 82.899499 118.429841) (end 82.893302 118.447553) (width 0.1) (layer "F.Cu") (net 238))
  (segment (start 83.156352 118.547898) (end 83.13864 118.541701) (width 0.1) (layer "F.Cu") (net 238))
  (via blind (at 96.4 120.55) (size 0.5) (drill 0.2) (layers "F.Cu" "In2.Cu") (net 238))
  (via (at 83.5 118.55) (size 0.5) (drill 0.2) (layers "F.Cu" "B.Cu") (net 238))
  (segment (start 84.3 118.55) (end 83.5 118.55) (width 0.1) (layer "In2.Cu") (net 238))
  (segment (start 94.4 118.7) (end 94.15 118.45) (width 0.1) (layer "In2.Cu") (net 238))
  (segment (start 87.6 118.45) (end 87.3 118.15) (width 0.1) (layer "In2.Cu") (net 238))
  (segment (start 95.428928 120.15) (end 94.4 119.121072) (width 0.1) (layer "In2.Cu") (net 238))
  (segment (start 96.4 120.55) (end 96 120.15) (width 0.1) (layer "In2.Cu") (net 238))
  (segment (start 94.15 118.45) (end 87.6 118.45) (width 0.1) (layer "In2.Cu") (net 238))
  (segment (start 94.4 119.121072) (end 94.4 118.7) (width 0.1) (layer "In2.Cu") (net 238))
  (segment (start 96 120.15) (end 95.428928 120.15) (width 0.1) (layer "In2.Cu") (net 238))
  (segment (start 87.3 118.15) (end 84.7 118.15) (width 0.1) (layer "In2.Cu") (net 238))
  (segment (start 84.7 118.15) (end 84.3 118.55) (width 0.1) (layer "In2.Cu") (net 238))
  (segment (start 83.5 118.55) (end 83.5 117.225) (width 0.1) (layer "B.Cu") (net 238))
  (segment (start 84.5 119) (end 84.522252 119.002507) (width 0.1) (layer "F.Cu") (net 239))
  (segment (start 84.202507 118.922252) (end 84.209903 118.943388) (width 0.1) (layer "F.Cu") (net 239))
  (segment (start 84.8 118.7) (end 84.797493 118.722252) (width 0.1) (layer "F.Cu") (net 239))
  (segment (start 84.722253 118.797492) (end 84.7 118.8) (width 0.1) (layer "F.Cu") (net 239))
  (segment (start 84.7 118.15) (end 84.6 118.25) (width 0.1) (layer "F.Cu") (net 239))
  (segment (start 84.562348 118.378183) (end 84.543388 118.390096) (width 0.1) (layer "F.Cu") (net 239))
  (segment (start 84.202507 118.877747) (end 84.2 118.9) (width 0.1) (layer "F.Cu") (net 239))
  (segment (start 84.6 118.25) (end 84.6 118.3) (width 0.1) (layer "F.Cu") (net 239))
  (segment (start 84.337651 118.421816) (end 84.321816 118.437651) (width 0.1) (layer "F.Cu") (net 239))
  (segment (start 84.522252 118.397492) (end 84.5 118.4) (width 0.1) (layer "F.Cu") (net 239))
  (segment (start 84.3 118.5) (end 84.302507 118.522252) (width 0.1) (layer "F.Cu") (net 239))
  (segment (start 84.237651 118.978183) (end 84.256611 118.990096) (width 0.1) (layer "F.Cu") (net 239))
  (segment (start 84.377747 118.402507) (end 84.356611 118.409903) (width 0.1) (layer "F.Cu") (net 239))
  (segment (start 84.221816 118.837651) (end 84.209903 118.856611) (width 0.1) (layer "F.Cu") (net 239))
  (segment (start 84.590096 118.343388) (end 84.578183 118.362348) (width 0.1) (layer "F.Cu") (net 239))
  (segment (start 84.722253 118.602507) (end 84.743389 118.609903) (width 0.1) (layer "F.Cu") (net 239))
  (segment (start 84.277747 118.802507) (end 84.256611 118.809903) (width 0.1) (layer "F.Cu") (net 239))
  (segment (start 84.209903 118.943388) (end 84.221816 118.962348) (width 0.1) (layer "F.Cu") (net 239))
  (segment (start 84.597492 118.322252) (end 84.590096 118.343388) (width 0.1) (layer "F.Cu") (net 239))
  (segment (start 94.4 119.35) (end 94 119.75) (width 0.1) (layer "F.Cu") (net 239))
  (segment (start 84.790097 118.743388) (end 84.778184 118.762348) (width 0.1) (layer "F.Cu") (net 239))
  (segment (start 84.237651 118.821816) (end 84.221816 118.837651) (width 0.1) (layer "F.Cu") (net 239))
  (segment (start 84.7 118.6) (end 84.722253 118.602507) (width 0.1) (layer "F.Cu") (net 239))
  (segment (start 84.4 118.6) (end 84.7 118.6) (width 0.1) (layer "F.Cu") (net 239))
  (segment (start 84.256611 118.990096) (end 84.277747 118.997492) (width 0.1) (layer "F.Cu") (net 239))
  (segment (start 84.778184 118.762348) (end 84.762349 118.778183) (width 0.1) (layer "F.Cu") (net 239))
  (segment (start 84.221816 118.962348) (end 84.237651 118.978183) (width 0.1) (layer "F.Cu") (net 239))
  (segment (start 84.778184 118.637651) (end 84.790097 118.656611) (width 0.1) (layer "F.Cu") (net 239))
  (segment (start 84.743389 118.609903) (end 84.762349 118.621816) (width 0.1) (layer "F.Cu") (net 239))
  (segment (start 84.3 119) (end 84.5 119) (width 0.1) (layer "F.Cu") (net 239))
  (segment (start 84.590096 119.056611) (end 84.597492 119.077747) (width 0.1) (layer "F.Cu") (net 239))
  (segment (start 84.6 119.1) (end 84.6 119.35) (width 0.1) (layer "F.Cu") (net 239))
  (segment (start 84.5 118.4) (end 84.4 118.4) (width 0.1) (layer "F.Cu") (net 239))
  (segment (start 84.309903 118.543388) (end 84.321816 118.562348) (width 0.1) (layer "F.Cu") (net 239))
  (segment (start 84.302507 118.522252) (end 84.309903 118.543388) (width 0.1) (layer "F.Cu") (net 239))
  (segment (start 84.578183 119.037651) (end 84.590096 119.056611) (width 0.1) (layer "F.Cu") (net 239))
  (segment (start 84.2 118.9) (end 84.202507 118.922252) (width 0.1) (layer "F.Cu") (net 239))
  (segment (start 84.209903 118.856611) (end 84.202507 118.877747) (width 0.1) (layer "F.Cu") (net 239))
  (segment (start 84.337651 118.578183) (end 84.356611 118.590096) (width 0.1) (layer "F.Cu") (net 239))
  (segment (start 84.762349 118.778183) (end 84.743389 118.790096) (width 0.1) (layer "F.Cu") (net 239))
  (segment (start 85.1 118.15) (end 84.7 118.15) (width 0.1) (layer "F.Cu") (net 239))
  (segment (start 84.797493 118.722252) (end 84.790097 118.743388) (width 0.1) (layer "F.Cu") (net 239))
  (segment (start 84.256611 118.809903) (end 84.237651 118.821816) (width 0.1) (layer "F.Cu") (net 239))
  (segment (start 84.578183 118.362348) (end 84.562348 118.378183) (width 0.1) (layer "F.Cu") (net 239))
  (segment (start 84.7 118.8) (end 84.3 118.8) (width 0.1) (layer "F.Cu") (net 239))
  (segment (start 84.321816 118.562348) (end 84.337651 118.578183) (width 0.1) (layer "F.Cu") (net 239))
  (segment (start 84.762349 118.621816) (end 84.778184 118.637651) (width 0.1) (layer "F.Cu") (net 239))
  (segment (start 84.790097 118.656611) (end 84.797493 118.677747) (width 0.1) (layer "F.Cu") (net 239))
  (segment (start 84.4 118.4) (end 84.377747 118.402507) (width 0.1) (layer "F.Cu") (net 239))
  (segment (start 84.277747 118.997492) (end 84.3 119) (width 0.1) (layer "F.Cu") (net 239))
  (segment (start 84.377747 118.597492) (end 84.4 118.6) (width 0.1) (layer "F.Cu") (net 239))
  (segment (start 84.321816 118.437651) (end 84.309903 118.456611) (width 0.1) (layer "F.Cu") (net 239))
  (segment (start 84.543388 118.390096) (end 84.522252 118.397492) (width 0.1) (layer "F.Cu") (net 239))
  (segment (start 84.356611 118.590096) (end 84.377747 118.597492) (width 0.1) (layer "F.Cu") (net 239))
  (segment (start 84.797493 118.677747) (end 84.8 118.7) (width 0.1) (layer "F.Cu") (net 239))
  (segment (start 84.743389 118.790096) (end 84.722253 118.797492) (width 0.1) (layer "F.Cu") (net 239))
  (segment (start 84.522252 119.002507) (end 84.543388 119.009903) (width 0.1) (layer "F.Cu") (net 239))
  (segment (start 84.6 118.3) (end 84.597492 118.322252) (width 0.1) (layer "F.Cu") (net 239))
  (segment (start 84.597492 119.077747) (end 84.6 119.1) (width 0.1) (layer "F.Cu") (net 239))
  (segment (start 84.3 118.8) (end 84.277747 118.802507) (width 0.1) (layer "F.Cu") (net 239))
  (segment (start 84.302507 118.477747) (end 84.3 118.5) (width 0.1) (layer "F.Cu") (net 239))
  (segment (start 84.543388 119.009903) (end 84.562348 119.021816) (width 0.1) (layer "F.Cu") (net 239))
  (segment (start 84.309903 118.456611) (end 84.302507 118.477747) (width 0.1) (layer "F.Cu") (net 239))
  (segment (start 84.356611 118.409903) (end 84.337651 118.421816) (width 0.1) (layer "F.Cu") (net 239))
  (segment (start 84.562348 119.021816) (end 84.578183 119.037651) (width 0.1) (layer "F.Cu") (net 239))
  (via (at 84.6 119.35) (size 0.5) (drill 0.2) (layers "F.Cu" "B.Cu") (net 239))
  (via blind (at 94 119.75) (size 0.5) (drill 0.2) (layers "F.Cu" "In2.Cu") (net 239))
  (segment (start 89.65 119.33651) (end 89.65 119.25) (width 0.1) (layer "In2.Cu") (net 239))
  (segment (start 88.25 119.25) (end 88.25 119.582542) (width 0.1) (layer "In2.Cu") (net 239))
  (segment (start 88.628183 119.187651) (end 88.640096 119.206611) (width 0.1) (layer "In2.Cu") (net 239))
  (segment (start 89.640096 119.379898) (end 89.647492 119.358762) (width 0.1) (layer "In2.Cu") (net 239))
  (segment (start 89.247492 119.604794) (end 89.25 119.582542) (width 0.1) (layer "In2.Cu") (net 239))
  (segment (start 88.972252 119.152507) (end 88.993388 119.159903) (width 0.1) (layer "In2.Cu") (net 239))
  (segment (start 89.393388 119.159903) (end 89.412348 119.171816) (width 0.1) (layer "In2.Cu") (net 239))
  (segment (start 88.487651 119.171816) (end 88.506611 119.159903) (width 0.1) (layer "In2.Cu") (net 239))
  (segment (start 88.852507 119.227747) (end 88.859903 119.206611) (width 0.1) (layer "In2.Cu") (net 239))
  (segment (start 89.127747 119.680034) (end 89.15 119.682542) (width 0.1) (layer "In2.Cu") (net 239))
  (segment (start 88.527747 119.152507) (end 88.55 119.15) (width 0.1) (layer "In2.Cu") (net 239))
  (segment (start 89.727747 119.152507) (end 89.75 119.15) (width 0.1) (layer "In2.Cu") (net 239))
  (segment (start 88.593388 119.159903) (end 88.612348 119.171816) (width 0.1) (layer "In2.Cu") (net 239))
  (segment (start 88.15 119.15) (end 88.172252 119.152507) (width 0.1) (layer "In2.Cu") (net 239))
  (segment (start 88.85 119.582542) (end 88.85 119.25) (width 0.1) (layer "In2.Cu") (net 239))
  (segment (start 89.047492 119.227747) (end 89.05 119.25) (width 0.1) (layer "In2.Cu") (net 239))
  (segment (start 88.640096 119.206611) (end 88.647492 119.227747) (width 0.1) (layer "In2.Cu") (net 239))
  (segment (start 89.087651 119.660725) (end 89.106611 119.672638) (width 0.1) (layer "In2.Cu") (net 239))
  (segment (start 89.45 119.25) (end 89.45 119.33651) (width 0.1) (layer "In2.Cu") (net 239))
  (segment (start 88.45 119.25) (end 88.452507 119.227747) (width 0.1) (layer "In2.Cu") (net 239))
  (segment (start 88.859903 119.206611) (end 88.871816 119.187651) (width 0.1) (layer "In2.Cu") (net 239))
  (segment (start 88.993388 119.159903) (end 89.012348 119.171816) (width 0.1) (layer "In2.Cu") (net 239))
  (segment (start 89.687651 119.171816) (end 89.706611 119.159903) (width 0.1) (layer "In2.Cu") (net 239))
  (segment (start 89.287651 119.171816) (end 89.306611 119.159903) (width 0.1) (layer "In2.Cu") (net 239))
  (segment (start 88.840096 119.62593) (end 88.847492 119.604794) (width 0.1) (layer "In2.Cu") (net 239))
  (segment (start 88 119.15) (end 88.15 119.15) (width 0.1) (layer "In2.Cu") (net 239))
  (segment (start 89.75 119.15) (end 92.45 119.15) (width 0.1) (layer "In2.Cu") (net 239))
  (segment (start 89.628183 119.398858) (end 89.640096 119.379898) (width 0.1) (layer "In2.Cu") (net 239))
  (segment (start 88.327747 119.680034) (end 88.35 119.682542) (width 0.1) (layer "In2.Cu") (net 239))
  (segment (start 89.447492 119.227747) (end 89.45 119.25) (width 0.1) (layer "In2.Cu") (net 239))
  (segment (start 88.612348 119.171816) (end 88.628183 119.187651) (width 0.1) (layer "In2.Cu") (net 239))
  (segment (start 89.306611 119.159903) (end 89.327747 119.152507) (width 0.1) (layer "In2.Cu") (net 239))
  (segment (start 89.05 119.582542) (end 89.052507 119.604794) (width 0.1) (layer "In2.Cu") (net 239))
  (segment (start 89.028183 119.187651) (end 89.040096 119.206611) (width 0.1) (layer "In2.Cu") (net 239))
  (segment (start 88.75 119.682542) (end 88.772252 119.680034) (width 0.1) (layer "In2.Cu") (net 239))
  (segment (start 88.447492 119.604794) (end 88.45 119.582542) (width 0.1) (layer "In2.Cu") (net 239))
  (segment (start 88.659903 119.62593) (end 88.671816 119.64489) (width 0.1) (layer "In2.Cu") (net 239))
  (segment (start 88.393388 119.672638) (end 88.412348 119.660725) (width 0.1) (layer "In2.Cu") (net 239))
  (segment (start 88.452507 119.227747) (end 88.459903 119.206611) (width 0.1) (layer "In2.Cu") (net 239))
  (segment (start 89.240096 119.62593) (end 89.247492 119.604794) (width 0.1) (layer "In2.Cu") (net 239))
  (segment (start 88.252507 119.604794) (end 88.259903 119.62593) (width 0.1) (layer "In2.Cu") (net 239))
  (segment (start 88.65 119.25) (end 88.65 119.582542) (width 0.1) (layer "In2.Cu") (net 239))
  (segment (start 89.040096 119.206611) (end 89.047492 119.227747) (width 0.1) (layer "In2.Cu") (net 239))
  (segment (start 88.193388 119.159903) (end 88.212348 119.171816) (width 0.1) (layer "In2.Cu") (net 239))
  (segment (start 89.071816 119.64489) (end 89.087651 119.660725) (width 0.1) (layer "In2.Cu") (net 239))
  (segment (start 87.4 119.75) (end 88 119.15) (width 0.1) (layer "In2.Cu") (net 239))
  (segment (start 88.440096 119.62593) (end 88.447492 119.604794) (width 0.1) (layer "In2.Cu") (net 239))
  (segment (start 88.95 119.15) (end 88.972252 119.152507) (width 0.1) (layer "In2.Cu") (net 239))
  (segment (start 88.247492 119.227747) (end 88.25 119.25) (width 0.1) (layer "In2.Cu") (net 239))
  (segment (start 88.172252 119.152507) (end 88.193388 119.159903) (width 0.1) (layer "In2.Cu") (net 239))
  (segment (start 88.228183 119.187651) (end 88.240096 119.206611) (width 0.1) (layer "In2.Cu") (net 239))
  (segment (start 88.727747 119.680034) (end 88.75 119.682542) (width 0.1) (layer "In2.Cu") (net 239))
  (segment (start 89.459903 119.379898) (end 89.471816 119.398858) (width 0.1) (layer "In2.Cu") (net 239))
  (segment (start 89.193388 119.672638) (end 89.212348 119.660725) (width 0.1) (layer "In2.Cu") (net 239))
  (segment (start 88.85 119.25) (end 88.852507 119.227747) (width 0.1) (layer "In2.Cu") (net 239))
  (segment (start 88.459903 119.206611) (end 88.471816 119.187651) (width 0.1) (layer "In2.Cu") (net 239))
  (segment (start 88.212348 119.171816) (end 88.228183 119.187651) (width 0.1) (layer "In2.Cu") (net 239))
  (segment (start 89.671816 119.187651) (end 89.687651 119.171816) (width 0.1) (layer "In2.Cu") (net 239))
  (segment (start 89.471816 119.398858) (end 89.487651 119.414693) (width 0.1) (layer "In2.Cu") (net 239))
  (segment (start 88.65 119.582542) (end 88.652507 119.604794) (width 0.1) (layer "In2.Cu") (net 239))
  (segment (start 88.772252 119.680034) (end 88.793388 119.672638) (width 0.1) (layer "In2.Cu") (net 239))
  (segment (start 88.428183 119.64489) (end 88.440096 119.62593) (width 0.1) (layer "In2.Cu") (net 239))
  (segment (start 89.412348 119.171816) (end 89.428183 119.187651) (width 0.1) (layer "In2.Cu") (net 239))
  (segment (start 88.687651 119.660725) (end 88.706611 119.672638) (width 0.1) (layer "In2.Cu") (net 239))
  (segment (start 89.55 119.43651) (end 89.572252 119.434002) (width 0.1) (layer "In2.Cu") (net 239))
  (segment (start 89.212348 119.660725) (end 89.228183 119.64489) (width 0.1) (layer "In2.Cu") (net 239))
  (segment (start 88.871816 119.187651) (end 88.887651 119.171816) (width 0.1) (layer "In2.Cu") (net 239))
  (segment (start 89.572252 119.434002) (end 89.593388 119.426606) (width 0.1) (layer "In2.Cu") (net 239))
  (segment (start 89.012348 119.171816) (end 89.028183 119.187651) (width 0.1) (layer "In2.Cu") (net 239))
  (segment (start 88.45 119.582542) (end 88.45 119.25) (width 0.1) (layer "In2.Cu") (net 239))
  (segment (start 89.25 119.582542) (end 89.25 119.25) (width 0.1) (layer "In2.Cu") (net 239))
  (segment (start 89.659903 119.206611) (end 89.671816 119.187651) (width 0.1) (layer "In2.Cu") (net 239))
  (segment (start 88.240096 119.206611) (end 88.247492 119.227747) (width 0.1) (layer "In2.Cu") (net 239))
  (segment (start 88.812348 119.660725) (end 88.828183 119.64489) (width 0.1) (layer "In2.Cu") (net 239))
  (segment (start 89.45 119.33651) (end 89.452507 119.358762) (width 0.1) (layer "In2.Cu") (net 239))
  (segment (start 89.506611 119.426606) (end 89.527747 119.434002) (width 0.1) (layer "In2.Cu") (net 239))
  (segment (start 88.906611 119.159903) (end 88.927747 119.152507) (width 0.1) (layer "In2.Cu") (net 239))
  (segment (start 89.259903 119.206611) (end 89.271816 119.187651) (width 0.1) (layer "In2.Cu") (net 239))
  (segment (start 89.440096 119.206611) (end 89.447492 119.227747) (width 0.1) (layer "In2.Cu") (net 239))
  (segment (start 89.25 119.25) (end 89.252507 119.227747) (width 0.1) (layer "In2.Cu") (net 239))
  (segment (start 88.287651 119.660725) (end 88.306611 119.672638) (width 0.1) (layer "In2.Cu") (net 239))
  (segment (start 89.059903 119.62593) (end 89.071816 119.64489) (width 0.1) (layer "In2.Cu") (net 239))
  (segment (start 88.412348 119.660725) (end 88.428183 119.64489) (width 0.1) (layer "In2.Cu") (net 239))
  (segment (start 89.252507 119.227747) (end 89.259903 119.206611) (width 0.1) (layer "In2.Cu") (net 239))
  (segment (start 93.05 119.75) (end 94 119.75) (width 0.1) (layer "In2.Cu") (net 239))
  (segment (start 84.6 119.35) (end 85 119.75) (width 0.1) (layer "In2.Cu") (net 239))
  (segment (start 85 119.75) (end 87.4 119.75) (width 0.1) (layer "In2.Cu") (net 239))
  (segment (start 89.428183 119.187651) (end 89.440096 119.206611) (width 0.1) (layer "In2.Cu") (net 239))
  (segment (start 89.652507 119.227747) (end 89.659903 119.206611) (width 0.1) (layer "In2.Cu") (net 239))
  (segment (start 89.35 119.15) (end 89.372252 119.152507) (width 0.1) (layer "In2.Cu") (net 239))
  (segment (start 88.306611 119.672638) (end 88.327747 119.680034) (width 0.1) (layer "In2.Cu") (net 239))
  (segment (start 88.652507 119.604794) (end 88.659903 119.62593) (width 0.1) (layer "In2.Cu") (net 239))
  (segment (start 88.887651 119.171816) (end 88.906611 119.159903) (width 0.1) (layer "In2.Cu") (net 239))
  (segment (start 89.271816 119.187651) (end 89.287651 119.171816) (width 0.1) (layer "In2.Cu") (net 239))
  (segment (start 88.271816 119.64489) (end 88.287651 119.660725) (width 0.1) (layer "In2.Cu") (net 239))
  (segment (start 88.706611 119.672638) (end 88.727747 119.680034) (width 0.1) (layer "In2.Cu") (net 239))
  (segment (start 88.35 119.682542) (end 88.372252 119.680034) (width 0.1) (layer "In2.Cu") (net 239))
  (segment (start 89.647492 119.358762) (end 89.65 119.33651) (width 0.1) (layer "In2.Cu") (net 239))
  (segment (start 88.671816 119.64489) (end 88.687651 119.660725) (width 0.1) (layer "In2.Cu") (net 239))
  (segment (start 88.572252 119.152507) (end 88.593388 119.159903) (width 0.1) (layer "In2.Cu") (net 239))
  (segment (start 89.612348 119.414693) (end 89.628183 119.398858) (width 0.1) (layer "In2.Cu") (net 239))
  (segment (start 88.828183 119.64489) (end 88.840096 119.62593) (width 0.1) (layer "In2.Cu") (net 239))
  (segment (start 89.65 119.25) (end 89.652507 119.227747) (width 0.1) (layer "In2.Cu") (net 239))
  (segment (start 88.471816 119.187651) (end 88.487651 119.171816) (width 0.1) (layer "In2.Cu") (net 239))
  (segment (start 89.527747 119.434002) (end 89.55 119.43651) (width 0.1) (layer "In2.Cu") (net 239))
  (segment (start 88.847492 119.604794) (end 88.85 119.582542) (width 0.1) (layer "In2.Cu") (net 239))
  (segment (start 89.228183 119.64489) (end 89.240096 119.62593) (width 0.1) (layer "In2.Cu") (net 239))
  (segment (start 88.647492 119.227747) (end 88.65 119.25) (width 0.1) (layer "In2.Cu") (net 239))
  (segment (start 89.593388 119.426606) (end 89.612348 119.414693) (width 0.1) (layer "In2.Cu") (net 239))
  (segment (start 89.452507 119.358762) (end 89.459903 119.379898) (width 0.1) (layer "In2.Cu") (net 239))
  (segment (start 88.55 119.15) (end 88.572252 119.152507) (width 0.1) (layer "In2.Cu") (net 239))
  (segment (start 89.15 119.682542) (end 89.172252 119.680034) (width 0.1) (layer "In2.Cu") (net 239))
  (segment (start 89.487651 119.414693) (end 89.506611 119.426606) (width 0.1) (layer "In2.Cu") (net 239))
  (segment (start 89.05 119.25) (end 89.05 119.582542) (width 0.1) (layer "In2.Cu") (net 239))
  (segment (start 89.372252 119.152507) (end 89.393388 119.159903) (width 0.1) (layer "In2.Cu") (net 239))
  (segment (start 89.052507 119.604794) (end 89.059903 119.62593) (width 0.1) (layer "In2.Cu") (net 239))
  (segment (start 88.372252 119.680034) (end 88.393388 119.672638) (width 0.1) (layer "In2.Cu") (net 239))
  (segment (start 88.25 119.582542) (end 88.252507 119.604794) (width 0.1) (layer "In2.Cu") (net 239))
  (segment (start 88.927747 119.152507) (end 88.95 119.15) (width 0.1) (layer "In2.Cu") (net 239))
  (segment (start 89.172252 119.680034) (end 89.193388 119.672638) (width 0.1) (layer "In2.Cu") (net 239))
  (segment (start 92.45 119.15) (end 93.05 119.75) (width 0.1) (layer "In2.Cu") (net 239))
  (segment (start 88.259903 119.62593) (end 88.271816 119.64489) (width 0.1) (layer "In2.Cu") (net 239))
  (segment (start 89.706611 119.159903) (end 89.727747 119.152507) (width 0.1) (layer "In2.Cu") (net 239))
  (segment (start 88.793388 119.672638) (end 88.812348 119.660725) (width 0.1) (layer "In2.Cu") (net 239))
  (segment (start 88.506611 119.159903) (end 88.527747 119.152507) (width 0.1) (layer "In2.Cu") (net 239))
  (segment (start 89.106611 119.672638) (end 89.127747 119.680034) (width 0.1) (layer "In2.Cu") (net 239))
  (segment (start 89.327747 119.152507) (end 89.35 119.15) (width 0.1) (layer "In2.Cu") (net 239))
  (segment (start 84.49 117.2) (end 84.49 119.24) (width 0.1) (layer "B.Cu") (net 239))
  (segment (start 84.49 119.24) (end 84.6 119.35) (width 0.1) (layer "B.Cu") (net 239))
  (segment (start 86.3 118.55) (end 85.9 118.15) (width 0.1) (layer "F.Cu") (net 240))
  (segment (start 95.2 120.95) (end 94.8 121.35) (width 0.1) (layer "F.Cu") (net 240))
  (via (at 86.3 118.55) (size 0.5) (drill 0.2) (layers "F.Cu" "B.Cu") (net 240))
  (via (at 94.8 121.35) (size 0.5) (drill 0.2) (layers "F.Cu" "B.Cu") (net 240))
  (segment (start 87.65 117.920569) (end 87.652507 117.898317) (width 0.1) (layer "B.Cu") (net 240))
  (segment (start 87.127747 118.147493) (end 87.15 118.15) (width 0.1) (layer "B.Cu") (net 240))
  (segment (start 86.859903 117.677181) (end 86.871816 117.658221) (width 0.1) (layer "B.Cu") (net 240))
  (segment (start 88.071816 118.187651) (end 88.087651 118.171816) (width 0.1) (layer "B.Cu") (net 240))
  (segment (start 86.75 118.15) (end 86.772252 118.147493) (width 0.1) (layer "B.Cu") (net 240))
  (segment (start 87.172252 118.147493) (end 87.193388 118.140097) (width 0.1) (layer "B.Cu") (net 240))
  (segment (start 86.871816 117.658221) (end 86.887651 117.642386) (width 0.1) (layer "B.Cu") (net 240))
  (segment (start 87.35 117.620569) (end 87.372252 117.623077) (width 0.1) (layer "B.Cu") (net 240))
  (segment (start 87.412348 117.642386) (end 87.428183 117.658221) (width 0.1) (layer "B.Cu") (net 240))
  (segment (start 87.641115 118.278641) (end 87.64775 118.259679) (width 0.1) (layer "B.Cu") (net 240))
  (segment (start 87.012348 117.642386) (end 87.028183 117.658221) (width 0.1) (layer "B.Cu") (net 240))
  (segment (start 87.616221 118.309858) (end 87.630427 118.295652) (width 0.1) (layer "B.Cu") (net 240))
  (segment (start 86.906611 117.630473) (end 86.927747 117.623077) (width 0.1) (layer "B.Cu") (net 240))
  (segment (start 86.49 117.895) (end 86.3 118.085) (width 0.1) (layer "B.Cu") (net 240))
  (segment (start 87.228183 118.112349) (end 87.240096 118.093389) (width 0.1) (layer "B.Cu") (net 240))
  (segment (start 86.3 118.55) (end 86.3 118.085) (width 0.1) (layer "B.Cu") (net 240))
  (segment (start 87.240096 118.093389) (end 87.247492 118.072253) (width 0.1) (layer "B.Cu") (net 240))
  (segment (start 87.500789 118.320546) (end 87.519751 118.327181) (width 0.1) (layer "B.Cu") (net 240))
  (segment (start 87.15 118.15) (end 87.172252 118.147493) (width 0.1) (layer "B.Cu") (net 240))
  (segment (start 86.840096 118.093389) (end 86.847492 118.072253) (width 0.1) (layer "B.Cu") (net 240))
  (segment (start 87.287651 117.642386) (end 87.306611 117.630473) (width 0.1) (layer "B.Cu") (net 240))
  (segment (start 86.772252 118.147493) (end 86.793388 118.140097) (width 0.1) (layer "B.Cu") (net 240))
  (segment (start 87.706611 117.830473) (end 87.727747 117.823077) (width 0.1) (layer "B.Cu") (net 240))
  (segment (start 86.847492 118.072253) (end 86.85 118.05) (width 0.1) (layer "B.Cu") (net 240))
  (segment (start 87.212348 118.128184) (end 87.228183 118.112349) (width 0.1) (layer "B.Cu") (net 240))
  (segment (start 87.393388 117.630473) (end 87.412348 117.642386) (width 0.1) (layer "B.Cu") (net 240))
  (segment (start 86.972252 117.623077) (end 86.993388 117.630473) (width 0.1) (layer "B.Cu") (net 240))
  (segment (start 87.828183 117.858221) (end 87.840096 117.877181) (width 0.1) (layer "B.Cu") (net 240))
  (segment (start 87.252507 117.698317) (end 87.259903 117.677181) (width 0.1) (layer "B.Cu") (net 240))
  (segment (start 87.64775 118.259679) (end 87.65 118.239716) (width 0.1) (layer "B.Cu") (net 240))
  (segment (start 88.05 118.25) (end 88.052507 118.227747) (width 0.1) (layer "B.Cu") (net 240))
  (segment (start 86.828183 118.112349) (end 86.840096 118.093389) (width 0.1) (layer "B.Cu") (net 240))
  (segment (start 87.793388 117.830473) (end 87.812348 117.842386) (width 0.1) (layer "B.Cu") (net 240))
  (segment (start 88.028183 118.641779) (end 88.040096 118.622819) (width 0.1) (layer "B.Cu") (net 240))
  (segment (start 87.271816 117.658221) (end 87.287651 117.642386) (width 0.1) (layer "B.Cu") (net 240))
  (segment (start 87.852507 118.601683) (end 87.859903 118.622819) (width 0.1) (layer "B.Cu") (net 240))
  (segment (start 87.75 117.820569) (end 87.772252 117.823077) (width 0.1) (layer "B.Cu") (net 240))
  (segment (start 87.560285 118.329431) (end 87.580248 118.327181) (width 0.1) (layer "B.Cu") (net 240))
  (segment (start 87.327747 117.623077) (end 87.35 117.620569) (width 0.1) (layer "B.Cu") (net 240))
  (segment (start 87.812348 117.842386) (end 87.828183 117.858221) (width 0.1) (layer "B.Cu") (net 240))
  (segment (start 86.993388 117.630473) (end 87.012348 117.642386) (width 0.1) (layer "B.Cu") (net 240))
  (segment (start 88.106611 118.159903) (end 88.127747 118.152507) (width 0.1) (layer "B.Cu") (net 240))
  (segment (start 87.447492 117.698317) (end 87.45 117.720569) (width 0.1) (layer "B.Cu") (net 240))
  (segment (start 88.040096 118.622819) (end 88.047492 118.601683) (width 0.1) (layer "B.Cu") (net 240))
  (segment (start 87.772252 117.823077) (end 87.793388 117.830473) (width 0.1) (layer "B.Cu") (net 240))
  (segment (start 87.071816 118.112349) (end 87.087651 118.128184) (width 0.1) (layer "B.Cu") (net 240))
  (segment (start 87.059903 118.093389) (end 87.071816 118.112349) (width 0.1) (layer "B.Cu") (net 240))
  (segment (start 87.45 118.239716) (end 87.452249 118.259679) (width 0.1) (layer "B.Cu") (net 240))
  (segment (start 87.580248 118.327181) (end 87.59921 118.320546) (width 0.1) (layer "B.Cu") (net 240))
  (segment (start 87.85 117.920569) (end 87.85 118.579431) (width 0.1) (layer "B.Cu") (net 240))
  (segment (start 87.306611 117.630473) (end 87.327747 117.623077) (width 0.1) (layer "B.Cu") (net 240))
  (segment (start 87.840096 117.877181) (end 87.847492 117.898317) (width 0.1) (layer "B.Cu") (net 240))
  (segment (start 86.85 118.05) (end 86.85 117.720569) (width 0.1) (layer "B.Cu") (net 240))
  (segment (start 87.040096 117.677181) (end 87.047492 117.698317) (width 0.1) (layer "B.Cu") (net 240))
  (segment (start 87.452249 118.259679) (end 87.458884 118.278641) (width 0.1) (layer "B.Cu") (net 240))
  (segment (start 87.671816 117.858221) (end 87.687651 117.842386) (width 0.1) (layer "B.Cu") (net 240))
  (segment (start 87.247492 118.072253) (end 87.25 118.05) (width 0.1) (layer "B.Cu") (net 240))
  (segment (start 87.859903 118.622819) (end 87.871816 118.641779) (width 0.1) (layer "B.Cu") (net 240))
  (segment (start 87.458884 118.278641) (end 87.469572 118.295652) (width 0.1) (layer "B.Cu") (net 240))
  (segment (start 87.847492 117.898317) (end 87.85 117.920569) (width 0.1) (layer "B.Cu") (net 240))
  (segment (start 87.85 118.579431) (end 87.852507 118.601683) (width 0.1) (layer "B.Cu") (net 240))
  (segment (start 87.519751 118.327181) (end 87.539715 118.329431) (width 0.1) (layer "B.Cu") (net 240))
  (segment (start 88.052507 118.227747) (end 88.059903 118.206611) (width 0.1) (layer "B.Cu") (net 240))
  (segment (start 87.440096 117.677181) (end 87.447492 117.698317) (width 0.1) (layer "B.Cu") (net 240))
  (segment (start 86.887651 117.642386) (end 86.906611 117.630473) (width 0.1) (layer "B.Cu") (net 240))
  (segment (start 86.7 118.15) (end 86.75 118.15) (width 0.1) (layer "B.Cu") (net 240))
  (segment (start 87.59921 118.320546) (end 87.616221 118.309858) (width 0.1) (layer "B.Cu") (net 240))
  (segment (start 87.993388 118.669527) (end 88.012348 118.657614) (width 0.1) (layer "B.Cu") (net 240))
  (segment (start 87.652507 117.898317) (end 87.659903 117.877181) (width 0.1) (layer "B.Cu") (net 240))
  (segment (start 87.659903 117.877181) (end 87.671816 117.858221) (width 0.1) (layer "B.Cu") (net 240))
  (segment (start 86.852507 117.698317) (end 86.859903 117.677181) (width 0.1) (layer "B.Cu") (net 240))
  (segment (start 87.45 117.720569) (end 87.45 118.239716) (width 0.1) (layer "B.Cu") (net 240))
  (segment (start 88.05 118.579431) (end 88.05 118.25) (width 0.1) (layer "B.Cu") (net 240))
  (segment (start 87.428183 117.658221) (end 87.440096 117.677181) (width 0.1) (layer "B.Cu") (net 240))
  (segment (start 89.5875 118.55) (end 95 118.55) (width 0.1) (layer "B.Cu") (net 240))
  (segment (start 87.087651 118.128184) (end 87.106611 118.140097) (width 0.1) (layer "B.Cu") (net 240))
  (segment (start 87.887651 118.657614) (end 87.906611 118.669527) (width 0.1) (layer "B.Cu") (net 240))
  (segment (start 95.2 120.95) (end 94.8 121.35) (width 0.1) (layer "B.Cu") (net 240))
  (segment (start 88.087651 118.171816) (end 88.106611 118.159903) (width 0.1) (layer "B.Cu") (net 240))
  (segment (start 87.95 118.679431) (end 87.972252 118.676923) (width 0.1) (layer "B.Cu") (net 240))
  (segment (start 86.3 118.55) (end 86.7 118.15) (width 0.1) (layer "B.Cu") (net 240))
  (segment (start 87.727747 117.823077) (end 87.75 117.820569) (width 0.1) (layer "B.Cu") (net 240))
  (segment (start 86.85 117.720569) (end 86.852507 117.698317) (width 0.1) (layer "B.Cu") (net 240))
  (segment (start 87.630427 118.295652) (end 87.641115 118.278641) (width 0.1) (layer "B.Cu") (net 240))
  (segment (start 87.906611 118.669527) (end 87.927747 118.676923) (width 0.1) (layer "B.Cu") (net 240))
  (segment (start 89.1875 118.15) (end 89.5875 118.55) (width 0.1) (layer "B.Cu") (net 240))
  (segment (start 87.25 118.05) (end 87.25 117.720569) (width 0.1) (layer "B.Cu") (net 240))
  (segment (start 87.193388 118.140097) (end 87.212348 118.128184) (width 0.1) (layer "B.Cu") (net 240))
  (segment (start 86.793388 118.140097) (end 86.812348 118.128184) (width 0.1) (layer "B.Cu") (net 240))
  (segment (start 95.2 118.75) (end 95.2 120.95) (width 0.1) (layer "B.Cu") (net 240))
  (segment (start 86.49 117.195) (end 86.49 117.895) (width 0.1) (layer "B.Cu") (net 240))
  (segment (start 87.028183 117.658221) (end 87.040096 117.677181) (width 0.1) (layer "B.Cu") (net 240))
  (segment (start 88.012348 118.657614) (end 88.028183 118.641779) (width 0.1) (layer "B.Cu") (net 240))
  (segment (start 87.05 118.05) (end 87.052507 118.072253) (width 0.1) (layer "B.Cu") (net 240))
  (segment (start 87.483778 118.309858) (end 87.500789 118.320546) (width 0.1) (layer "B.Cu") (net 240))
  (segment (start 87.047492 117.698317) (end 87.05 117.720569) (width 0.1) (layer "B.Cu") (net 240))
  (segment (start 87.927747 118.676923) (end 87.95 118.679431) (width 0.1) (layer "B.Cu") (net 240))
  (segment (start 87.372252 117.623077) (end 87.393388 117.630473) (width 0.1) (layer "B.Cu") (net 240))
  (segment (start 88.047492 118.601683) (end 88.05 118.579431) (width 0.1) (layer "B.Cu") (net 240))
  (segment (start 88.15 118.15) (end 89.1875 118.15) (width 0.1) (layer "B.Cu") (net 240))
  (segment (start 87.05 117.720569) (end 87.05 118.05) (width 0.1) (layer "B.Cu") (net 240))
  (segment (start 87.687651 117.842386) (end 87.706611 117.830473) (width 0.1) (layer "B.Cu") (net 240))
  (segment (start 87.259903 117.677181) (end 87.271816 117.658221) (width 0.1) (layer "B.Cu") (net 240))
  (segment (start 95 118.55) (end 95.2 118.75) (width 0.1) (layer "B.Cu") (net 240))
  (segment (start 87.871816 118.641779) (end 87.887651 118.657614) (width 0.1) (layer "B.Cu") (net 240))
  (segment (start 87.65 118.239716) (end 87.65 117.920569) (width 0.1) (layer "B.Cu") (net 240))
  (segment (start 87.25 117.720569) (end 87.252507 117.698317) (width 0.1) (layer "B.Cu") (net 240))
  (segment (start 87.106611 118.140097) (end 87.127747 118.147493) (width 0.1) (layer "B.Cu") (net 240))
  (segment (start 86.927747 117.623077) (end 86.95 117.620569) (width 0.1) (layer "B.Cu") (net 240))
  (segment (start 88.127747 118.152507) (end 88.15 118.15) (width 0.1) (layer "B.Cu") (net 240))
  (segment (start 86.95 117.620569) (end 86.972252 117.623077) (width 0.1) (layer "B.Cu") (net 240))
  (segment (start 87.972252 118.676923) (end 87.993388 118.669527) (width 0.1) (layer "B.Cu") (net 240))
  (segment (start 86.812348 118.128184) (end 86.828183 118.112349) (width 0.1) (layer "B.Cu") (net 240))
  (segment (start 87.539715 118.329431) (end 87.560285 118.329431) (width 0.1) (layer "B.Cu") (net 240))
  (segment (start 87.052507 118.072253) (end 87.059903 118.093389) (width 0.1) (layer "B.Cu") (net 240))
  (segment (start 87.469572 118.295652) (end 87.483778 118.309858) (width 0.1) (layer "B.Cu") (net 240))
  (segment (start 88.059903 118.206611) (end 88.071816 118.187651) (width 0.1) (layer "B.Cu") (net 240))
  (segment (start 97.2 120.55) (end 96.8 120.95) (width 0.1) (layer "F.Cu") (net 241))
  (segment (start 85.1 118.95) (end 85.5 118.55) (width 0.1) (layer "F.Cu") (net 241))
  (via blind (at 97.2 120.55) (size 0.5) (drill 0.2) (layers "F.Cu" "In5.Cu") (net 241))
  (via (at 85.5 118.55) (size 0.5) (drill 0.2) (layers "F.Cu" "B.Cu") (net 241))
  (segment (start 86.957138 118.057391) (end 86.968697 118.038996) (width 0.1) (layer "In5.Cu") (net 241))
  (segment (start 86.047531 118.196503) (end 86.069119 118.19407) (width 0.1) (layer "In5.Cu") (net 241))
  (segment (start 86.13494 118.14158) (end 86.142115 118.121074) (width 0.1) (layer "In5.Cu") (net 241))
  (segment (start 86.349336 118.090511) (end 86.354662 118.105733) (width 0.1) (layer "In5.Cu") (net 241))
  (segment (start 86.069119 118.19407) (end 86.089625 118.186895) (width 0.1) (layer "In5.Cu") (net 241))
  (segment (start 86.945098 118.121074) (end 86.949963 118.077897) (width 0.1) (layer "In5.Cu") (net 241))
  (segment (start 86.757138 118.14158) (end 86.768697 118.159975) (width 0.1) (layer "In5.Cu") (net 241))
  (segment (start 86.325714 117.646087) (end 86.337627 117.665047) (width 0.1) (layer "In5.Cu") (net 241))
  (segment (start 86.647531 117.608435) (end 86.669783 117.610943) (width 0.1) (layer "In5.Cu") (net 241))
  (segment (start 93.025 118.55) (end 95.425 120.95) (width 0.1) (layer "In5.Cu") (net 241))
  (segment (start 85.5 118.55) (end 85.5 118.1875) (width 0.1) (layer "In5.Cu") (net 241))
  (segment (start 86.520415 118.130791) (end 86.531819 118.119387) (width 0.1) (layer "In5.Cu") (net 241))
  (segment (start 86.749963 118.121074) (end 86.757138 118.14158) (width 0.1) (layer "In5.Cu") (net 241))
  (segment (start 86.309879 117.630252) (end 86.325714 117.646087) (width 0.1) (layer "In5.Cu") (net 241))
  (segment (start 86.949963 118.077897) (end 86.957138 118.057391) (width 0.1) (layer "In5.Cu") (net 241))
  (segment (start 87.022959 118.004901) (end 87.044548 118.002469) (width 0.1) (layer "In5.Cu") (net 241))
  (segment (start 86.768697 118.159975) (end 86.784058 118.175336) (width 0.1) (layer "In5.Cu") (net 241))
  (segment (start 86.142115 118.121074) (end 86.144548 118.099486) (width 0.1) (layer "In5.Cu") (net 241))
  (segment (start 86.3883 118.139371) (end 86.403522 118.144697) (width 0.1) (layer "In5.Cu") (net 241))
  (segment (start 86.269783 117.610943) (end 86.290919 117.618339) (width 0.1) (layer "In5.Cu") (net 241))
  (segment (start 86.802453 118.186895) (end 86.822959 118.19407) (width 0.1) (layer "In5.Cu") (net 241))
  (segment (start 85.685031 118.002469) (end 85.847531 118.002469) (width 0.1) (layer "In5.Cu") (net 241))
  (segment (start 86.147531 117.708435) (end 86.150038 117.686183) (width 0.1) (layer "In5.Cu") (net 241))
  (segment (start 86.403522 118.144697) (end 86.419548 118.146503) (width 0.1) (layer "In5.Cu") (net 241))
  (segment (start 86.547531 117.708435) (end 86.550038 117.686183) (width 0.1) (layer "In5.Cu") (net 241))
  (segment (start 86.747531 118.099486) (end 86.749963 118.121074) (width 0.1) (layer "In5.Cu") (net 241))
  (segment (start 86.604142 117.618339) (end 86.625278 117.610943) (width 0.1) (layer "In5.Cu") (net 241))
  (segment (start 86.690919 117.618339) (end 86.709879 117.630252) (width 0.1) (layer "In5.Cu") (net 241))
  (segment (start 86.169347 117.646087) (end 86.185182 117.630252) (width 0.1) (layer "In5.Cu") (net 241))
  (segment (start 86.247531 117.608435) (end 86.269783 117.610943) (width 0.1) (layer "In5.Cu") (net 241))
  (segment (start 86.475514 118.146503) (end 86.491539 118.144697) (width 0.1) (layer "In5.Cu") (net 241))
  (segment (start 96.8 120.95) (end 97.2 120.55) (width 0.1) (layer "In5.Cu") (net 241))
  (segment (start 86.550038 117.686183) (end 86.557434 117.665047) (width 0.1) (layer "In5.Cu") (net 241))
  (segment (start 86.347531 118.074486) (end 86.349336 118.090511) (width 0.1) (layer "In5.Cu") (net 241))
  (segment (start 86.557434 117.665047) (end 86.569347 117.646087) (width 0.1) (layer "In5.Cu") (net 241))
  (segment (start 85.93494 118.057391) (end 85.942115 118.077897) (width 0.1) (layer "In5.Cu") (net 241))
  (segment (start 86.290919 117.618339) (end 86.309879 117.630252) (width 0.1) (layer "In5.Cu") (net 241))
  (segment (start 86.363242 118.119387) (end 86.374646 118.130791) (width 0.1) (layer "In5.Cu") (net 241))
  (segment (start 86.822959 118.19407) (end 86.844548 118.196503) (width 0.1) (layer "In5.Cu") (net 241))
  (segment (start 86.225278 117.610943) (end 86.247531 117.608435) (width 0.1) (layer "In5.Cu") (net 241))
  (segment (start 85.981075 118.175336) (end 85.99947 118.186895) (width 0.1) (layer "In5.Cu") (net 241))
  (segment (start 85.99947 118.186895) (end 86.019976 118.19407) (width 0.1) (layer "In5.Cu") (net 241))
  (segment (start 86.937923 118.14158) (end 86.945098 118.121074) (width 0.1) (layer "In5.Cu") (net 241))
  (segment (start 86.374646 118.130791) (end 86.3883 118.139371) (width 0.1) (layer "In5.Cu") (net 241))
  (segment (start 86.204142 117.618339) (end 86.225278 117.610943) (width 0.1) (layer "In5.Cu") (net 241))
  (segment (start 85.923381 118.038996) (end 85.93494 118.057391) (width 0.1) (layer "In5.Cu") (net 241))
  (segment (start 86.185182 117.630252) (end 86.204142 117.618339) (width 0.1) (layer "In5.Cu") (net 241))
  (segment (start 86.737627 117.665047) (end 86.745023 117.686183) (width 0.1) (layer "In5.Cu") (net 241))
  (segment (start 86.10802 118.175336) (end 86.123381 118.159975) (width 0.1) (layer "In5.Cu") (net 241))
  (segment (start 86.144548 118.099486) (end 86.144548 118.002469) (width 0.1) (layer "In5.Cu") (net 241))
  (segment (start 86.745023 117.686183) (end 86.747531 117.708435) (width 0.1) (layer "In5.Cu") (net 241))
  (segment (start 86.019976 118.19407) (end 86.041565 118.196503) (width 0.1) (layer "In5.Cu") (net 241))
  (segment (start 86.926364 118.159975) (end 86.937923 118.14158) (width 0.1) (layer "In5.Cu") (net 241))
  (segment (start 86.968697 118.038996) (end 86.984058 118.023635) (width 0.1) (layer "In5.Cu") (net 241))
  (segment (start 86.569347 117.646087) (end 86.585182 117.630252) (width 0.1) (layer "In5.Cu") (net 241))
  (segment (start 86.585182 117.630252) (end 86.604142 117.618339) (width 0.1) (layer "In5.Cu") (net 241))
  (segment (start 86.540399 118.105733) (end 86.545725 118.090511) (width 0.1) (layer "In5.Cu") (net 241))
  (segment (start 86.089625 118.186895) (end 86.10802 118.175336) (width 0.1) (layer "In5.Cu") (net 241))
  (segment (start 86.150038 117.686183) (end 86.157434 117.665047) (width 0.1) (layer "In5.Cu") (net 241))
  (segment (start 85.965714 118.159975) (end 85.981075 118.175336) (width 0.1) (layer "In5.Cu") (net 241))
  (segment (start 86.345023 117.686183) (end 86.347531 117.708435) (width 0.1) (layer "In5.Cu") (net 241))
  (segment (start 86.872102 118.19407) (end 86.892608 118.186895) (width 0.1) (layer "In5.Cu") (net 241))
  (segment (start 86.419548 118.146503) (end 86.475514 118.146503) (width 0.1) (layer "In5.Cu") (net 241))
  (segment (start 86.911003 118.175336) (end 86.926364 118.159975) (width 0.1) (layer "In5.Cu") (net 241))
  (segment (start 86.491539 118.144697) (end 86.506761 118.139371) (width 0.1) (layer "In5.Cu") (net 241))
  (segment (start 85.90802 118.023635) (end 85.923381 118.038996) (width 0.1) (layer "In5.Cu") (net 241))
  (segment (start 85.889625 118.012076) (end 85.90802 118.023635) (width 0.1) (layer "In5.Cu") (net 241))
  (segment (start 86.625278 117.610943) (end 86.647531 117.608435) (width 0.1) (layer "In5.Cu") (net 241))
  (segment (start 86.669783 117.610943) (end 86.690919 117.618339) (width 0.1) (layer "In5.Cu") (net 241))
  (segment (start 86.725714 117.646087) (end 86.737627 117.665047) (width 0.1) (layer "In5.Cu") (net 241))
  (segment (start 86.850514 118.196503) (end 86.872102 118.19407) (width 0.1) (layer "In5.Cu") (net 241))
  (segment (start 85.954155 118.14158) (end 85.965714 118.159975) (width 0.1) (layer "In5.Cu") (net 241))
  (segment (start 87.452469 118.002469) (end 88 118.55) (width 0.1) (layer "In5.Cu") (net 241))
  (segment (start 88 118.55) (end 93.025 118.55) (width 0.1) (layer "In5.Cu") (net 241))
  (segment (start 87.044548 118.002469) (end 87.452469 118.002469) (width 0.1) (layer "In5.Cu") (net 241))
  (segment (start 95.425 120.95) (end 96.8 120.95) (width 0.1) (layer "In5.Cu") (net 241))
  (segment (start 86.709879 117.630252) (end 86.725714 117.646087) (width 0.1) (layer "In5.Cu") (net 241))
  (segment (start 86.547531 118.074486) (end 86.547531 117.708435) (width 0.1) (layer "In5.Cu") (net 241))
  (segment (start 85.869119 118.004901) (end 85.889625 118.012076) (width 0.1) (layer "In5.Cu") (net 241))
  (segment (start 86.784058 118.175336) (end 86.802453 118.186895) (width 0.1) (layer "In5.Cu") (net 241))
  (segment (start 86.545725 118.090511) (end 86.547531 118.074486) (width 0.1) (layer "In5.Cu") (net 241))
  (segment (start 85.5 118.1875) (end 85.685031 118.002469) (width 0.1) (layer "In5.Cu") (net 241))
  (segment (start 86.531819 118.119387) (end 86.540399 118.105733) (width 0.1) (layer "In5.Cu") (net 241))
  (segment (start 86.747531 117.708435) (end 86.747531 118.099486) (width 0.1) (layer "In5.Cu") (net 241))
  (segment (start 86.347531 117.708435) (end 86.347531 118.074486) (width 0.1) (layer "In5.Cu") (net 241))
  (segment (start 86.144548 118.002469) (end 86.147531 118.002469) (width 0.1) (layer "In5.Cu") (net 241))
  (segment (start 86.337627 117.665047) (end 86.345023 117.686183) (width 0.1) (layer "In5.Cu") (net 241))
  (segment (start 86.354662 118.105733) (end 86.363242 118.119387) (width 0.1) (layer "In5.Cu") (net 241))
  (segment (start 85.94698 118.121074) (end 85.954155 118.14158) (width 0.1) (layer "In5.Cu") (net 241))
  (segment (start 85.847531 118.002469) (end 85.869119 118.004901) (width 0.1) (layer "In5.Cu") (net 241))
  (segment (start 86.157434 117.665047) (end 86.169347 117.646087) (width 0.1) (layer "In5.Cu") (net 241))
  (segment (start 85.942115 118.077897) (end 85.94698 118.121074) (width 0.1) (layer "In5.Cu") (net 241))
  (segment (start 86.147531 118.002469) (end 86.147531 117.708435) (width 0.1) (layer "In5.Cu") (net 241))
  (segment (start 86.844548 118.196503) (end 86.850514 118.196503) (width 0.1) (layer "In5.Cu") (net 241))
  (segment (start 86.892608 118.186895) (end 86.911003 118.175336) (width 0.1) (layer "In5.Cu") (net 241))
  (segment (start 87.002453 118.012076) (end 87.022959 118.004901) (width 0.1) (layer "In5.Cu") (net 241))
  (segment (start 86.506761 118.139371) (end 86.520415 118.130791) (width 0.1) (layer "In5.Cu") (net 241))
  (segment (start 86.984058 118.023635) (end 87.002453 118.012076) (width 0.1) (layer "In5.Cu") (net 241))
  (segment (start 86.123381 118.159975) (end 86.13494 118.14158) (width 0.1) (layer "In5.Cu") (net 241))
  (segment (start 86.041565 118.196503) (end 86.047531 118.196503) (width 0.1) (layer "In5.Cu") (net 241))
  (segment (start 85.5 118.55) (end 85.5 117.2) (width 0.1) (layer "B.Cu") (net 241))
  (segment (start 81.1 118.15) (end 80.7 118.55) (width 0.1) (layer "F.Cu") (net 242))
  (segment (start 95.6 120.55) (end 96 120.95) (width 0.1) (layer "F.Cu") (net 242))
  (via (at 80.7 118.55) (size 0.5) (drill 0.2) (layers "F.Cu" "B.Cu") (net 242))
  (via blind (at 95.6 120.55) (size 0.5) (drill 0.2) (layers "F.Cu" "In2.Cu") (net 242))
  (segment (start 94.325 119.35) (end 93 119.35) (width 0.1) (layer "In2.Cu") (net 242))
  (segment (start 93 119.35) (end 92.6 118.95) (width 0.1) (layer "In2.Cu") (net 242))
  (segment (start 81.1 118.95) (end 80.7 118.55) (width 0.1) (layer "In2.Cu") (net 242))
  (segment (start 95.525 120.55) (end 94.325 119.35) (width 0.1) (layer "In2.Cu") (net 242))
  (segment (start 92.6 118.95) (end 81.1 118.95) (width 0.1) (layer "In2.Cu") (net 242))
  (segment (start 95.6 120.55) (end 95.525 120.55) (width 0.1) (layer "In2.Cu") (net 242))
  (segment (start 80.7 118.55) (end 79.85 118.55) (width 0.1) (layer "B.Cu") (net 242))
  (segment (start 81.1 117.35) (end 81.5 117.75) (width 0.1) (layer "F.Cu") (net 243))
  (segment (start 96.8 119.35) (end 96.4 118.95) (width 0.1) (layer "F.Cu") (net 243))
  (via blind (at 96.4 118.95) (size 0.5) (drill 0.2) (layers "F.Cu" "In2.Cu") (net 243))
  (via (at 81.5 117.75) (size 0.5) (drill 0.2) (layers "F.Cu" "B.Cu") (net 243))
  (segment (start 87.6 117.55) (end 87.9 117.85) (width 0.1) (layer "In2.Cu") (net 243))
  (segment (start 82.110537 117.581183) (end 82.1171 117.570739) (width 0.1) (layer "In2.Cu") (net 243))
  (segment (start 82.05 117.660166) (end 82.062257 117.658784) (width 0.1) (layer "In2.Cu") (net 243))
  (segment (start 81.7 117.55) (end 81.85 117.55) (width 0.1) (layer "In2.Cu") (net 243))
  (segment (start 81.903701 117.592825) (end 81.906464 117.61734) (width 0.1) (layer "In2.Cu") (net 243))
  (segment (start 82.093065 117.639426) (end 82.099628 117.628982) (width 0.1) (layer "In2.Cu") (net 243))
  (segment (start 81.936266 117.654711) (end 81.947908 117.658784) (width 0.1) (layer "In2.Cu") (net 243))
  (segment (start 82.099628 117.628982) (end 82.103701 117.61734) (width 0.1) (layer "In2.Cu") (net 243))
  (segment (start 81.910537 117.628982) (end 81.9171 117.639426) (width 0.1) (layer "In2.Cu") (net 243))
  (segment (start 81.873899 117.555454) (end 81.884343 117.562017) (width 0.1) (layer "In2.Cu") (net 243))
  (segment (start 81.925822 117.648148) (end 81.936266 117.654711) (width 0.1) (layer "In2.Cu") (net 243))
  (segment (start 81.5 117.75) (end 81.7 117.55) (width 0.1) (layer "In2.Cu") (net 243))
  (segment (start 81.906464 117.61734) (end 81.910537 117.628982) (width 0.1) (layer "In2.Cu") (net 243))
  (segment (start 96.4 118.85) (end 96.4 118.95) (width 0.1) (layer "In2.Cu") (net 243))
  (segment (start 82.073899 117.654711) (end 82.084343 117.648148) (width 0.1) (layer "In2.Cu") (net 243))
  (segment (start 82.147908 117.551381) (end 82.160166 117.55) (width 0.1) (layer "In2.Cu") (net 243))
  (segment (start 82.125822 117.562017) (end 82.136266 117.555454) (width 0.1) (layer "In2.Cu") (net 243))
  (segment (start 81.9171 117.639426) (end 81.925822 117.648148) (width 0.1) (layer "In2.Cu") (net 243))
  (segment (start 81.85 117.55) (end 81.862257 117.551381) (width 0.1) (layer "In2.Cu") (net 243))
  (segment (start 81.899628 117.581183) (end 81.903701 117.592825) (width 0.1) (layer "In2.Cu") (net 243))
  (segment (start 82.160166 117.55) (end 87.6 117.55) (width 0.1) (layer "In2.Cu") (net 243))
  (segment (start 81.960166 117.660166) (end 82.05 117.660166) (width 0.1) (layer "In2.Cu") (net 243))
  (segment (start 82.1171 117.570739) (end 82.125822 117.562017) (width 0.1) (layer "In2.Cu") (net 243))
  (segment (start 81.947908 117.658784) (end 81.960166 117.660166) (width 0.1) (layer "In2.Cu") (net 243))
  (segment (start 82.084343 117.648148) (end 82.093065 117.639426) (width 0.1) (layer "In2.Cu") (net 243))
  (segment (start 81.893065 117.570739) (end 81.899628 117.581183) (width 0.1) (layer "In2.Cu") (net 243))
  (segment (start 95.4 117.85) (end 96.4 118.85) (width 0.1) (layer "In2.Cu") (net 243))
  (segment (start 82.136266 117.555454) (end 82.147908 117.551381) (width 0.1) (layer "In2.Cu") (net 243))
  (segment (start 82.106464 117.592825) (end 82.110537 117.581183) (width 0.1) (layer "In2.Cu") (net 243))
  (segment (start 87.9 117.85) (end 95.4 117.85) (width 0.1) (layer "In2.Cu") (net 243))
  (segment (start 82.103701 117.61734) (end 82.106464 117.592825) (width 0.1) (layer "In2.Cu") (net 243))
  (segment (start 82.062257 117.658784) (end 82.073899 117.654711) (width 0.1) (layer "In2.Cu") (net 243))
  (segment (start 81.884343 117.562017) (end 81.893065 117.570739) (width 0.1) (layer "In2.Cu") (net 243))
  (segment (start 81.862257 117.551381) (end 81.873899 117.555454) (width 0.1) (layer "In2.Cu") (net 243))
  (segment (start 81.1 118.15) (end 81.5 117.75) (width 0.1) (layer "B.Cu") (net 243))
  (segment (start 80.4 118.05) (end 79.85 118.05) (width 0.1) (layer "B.Cu") (net 243))
  (segment (start 80.5 118.15) (end 80.4 118.05) (width 0.1) (layer "B.Cu") (net 243))
  (segment (start 80.5 118.15) (end 81.1 118.15) (width 0.1) (layer "B.Cu") (net 243))
  (segment (start 82.5 117.95) (end 81.9 117.35) (width 0.1) (layer "F.Cu") (net 244))
  (segment (start 96.8 120.15) (end 96.4 119.75) (width 0.1) (layer "F.Cu") (net 244))
  (segment (start 82.5 118) (end 82.5 117.95) (width 0.1) (layer "F.Cu") (net 244))
  (via (at 82.5 118) (size 0.5) (drill 0.2) (layers "F.Cu" "B.Cu") (net 244))
  (via blind (at 96.4 119.75) (size 0.5) (drill 0.2) (layers "F.Cu" "In2.Cu") (net 244))
  (segment (start 82.95 117.912678) (end 82.968099 117.910638) (width 0.1) (layer "In2.Cu") (net 244))
  (segment (start 83.023283 117.86663) (end 83.029299 117.849438) (width 0.1) (layer "In2.Cu") (net 244))
  (segment (start 82.894578 117.910638) (end 82.912678 117.912678) (width 0.1) (layer "In2.Cu") (net 244))
  (segment (start 82.800714 117.767745) (end 82.813593 117.780624) (width 0.1) (layer "In2.Cu") (net 244))
  (segment (start 82.833378 117.849438) (end 82.839394 117.86663) (width 0.1) (layer "In2.Cu") (net 244))
  (segment (start 83.112678 117.75) (end 87.5 117.75) (width 0.1) (layer "In2.Cu") (net 244))
  (segment (start 82.823283 117.796047) (end 82.829299 117.813239) (width 0.1) (layer "In2.Cu") (net 244))
  (segment (start 82.813593 117.780624) (end 82.823283 117.796047) (width 0.1) (layer "In2.Cu") (net 244))
  (segment (start 82.877386 117.904622) (end 82.894578 117.910638) (width 0.1) (layer "In2.Cu") (net 244))
  (segment (start 83.077386 117.758055) (end 83.094578 117.752039) (width 0.1) (layer "In2.Cu") (net 244))
  (segment (start 87.8 118.05) (end 95.3 118.05) (width 0.1) (layer "In2.Cu") (net 244))
  (segment (start 96 119.35) (end 96.4 119.75) (width 0.1) (layer "In2.Cu") (net 244))
  (segment (start 83.049084 117.780624) (end 83.061963 117.767745) (width 0.1) (layer "In2.Cu") (net 244))
  (segment (start 82.829299 117.813239) (end 82.833378 117.849438) (width 0.1) (layer "In2.Cu") (net 244))
  (segment (start 82.849084 117.882053) (end 82.861963 117.894932) (width 0.1) (layer "In2.Cu") (net 244))
  (segment (start 82.861963 117.894932) (end 82.877386 117.904622) (width 0.1) (layer "In2.Cu") (net 244))
  (segment (start 82.912678 117.912678) (end 82.95 117.912678) (width 0.1) (layer "In2.Cu") (net 244))
  (segment (start 83.000714 117.894932) (end 83.013593 117.882053) (width 0.1) (layer "In2.Cu") (net 244))
  (segment (start 95.3 118.05) (end 96 118.75) (width 0.1) (layer "In2.Cu") (net 244))
  (segment (start 82.968099 117.910638) (end 82.985291 117.904622) (width 0.1) (layer "In2.Cu") (net 244))
  (segment (start 83.039394 117.796047) (end 83.049084 117.780624) (width 0.1) (layer "In2.Cu") (net 244))
  (segment (start 83.033378 117.813239) (end 83.039394 117.796047) (width 0.1) (layer "In2.Cu") (net 244))
  (segment (start 83.013593 117.882053) (end 83.023283 117.86663) (width 0.1) (layer "In2.Cu") (net 244))
  (segment (start 96 118.75) (end 96 119.35) (width 0.1) (layer "In2.Cu") (net 244))
  (segment (start 83.094578 117.752039) (end 83.112678 117.75) (width 0.1) (layer "In2.Cu") (net 244))
  (segment (start 82.839394 117.86663) (end 82.849084 117.882053) (width 0.1) (layer "In2.Cu") (net 244))
  (segment (start 87.5 117.75) (end 87.8 118.05) (width 0.1) (layer "In2.Cu") (net 244))
  (segment (start 82.5 118) (end 82.75 117.75) (width 0.1) (layer "In2.Cu") (net 244))
  (segment (start 82.75 117.75) (end 82.768099 117.752039) (width 0.1) (layer "In2.Cu") (net 244))
  (segment (start 83.029299 117.849438) (end 83.033378 117.813239) (width 0.1) (layer "In2.Cu") (net 244))
  (segment (start 82.985291 117.904622) (end 83.000714 117.894932) (width 0.1) (layer "In2.Cu") (net 244))
  (segment (start 82.785291 117.758055) (end 82.800714 117.767745) (width 0.1) (layer "In2.Cu") (net 244))
  (segment (start 82.768099 117.752039) (end 82.785291 117.758055) (width 0.1) (layer "In2.Cu") (net 244))
  (segment (start 83.061963 117.767745) (end 83.077386 117.758055) (width 0.1) (layer "In2.Cu") (net 244))
  (segment (start 82.7 118) (end 82.5 118) (width 0.1) (layer "B.Cu") (net 244))
  (segment (start 82.99 117.2) (end 82.99 117.71) (width 0.1) (layer "B.Cu") (net 244))
  (segment (start 82.99 117.71) (end 82.7 118) (width 0.1) (layer "B.Cu") (net 244))
  (segment (start 96 119.35) (end 95.6 118.95) (width 0.1) (layer "F.Cu") (net 245))
  (segment (start 81.1 118.95) (end 81.5 118.55) (width 0.1) (layer "F.Cu") (net 245))
  (via blind (at 95.6 118.95) (size 0.5) (drill 0.2) (layers "F.Cu" "In2.Cu") (net 245))
  (via (at 81.5 118.55) (size 0.5) (drill 0.2) (layers "F.Cu" "B.Cu") (net 245))
  (segment (start 81.933542 118.557253) (end 81.918063 118.551837) (width 0.1) (layer "In2.Cu") (net 245))
  (segment (start 82.575 118.55) (end 82.575 118.623232) (width 0.1) (layer "In2.Cu") (net 245))
  (segment (start 82.833704 118.548163) (end 82.818225 118.542747) (width 0.1) (layer "In2.Cu") (net 245))
  (segment (start 82.375 118.623232) (end 82.375 118.476768) (width 0.1) (layer "In2.Cu") (net 245))
  (segment (start 81.973163 118.606937) (end 81.967747 118.591458) (width 0.1) (layer "In2.Cu") (net 245))
  (segment (start 82.175 118.623232) (end 82.173163 118.639528) (width 0.1) (layer "In2.Cu") (net 245))
  (segment (start 82.901837 118.548163) (end 82.833704 118.548163) (width 0.1) (layer "In2.Cu") (net 245))
  (segment (start 82.175 118.476768) (end 82.175 118.623232) (width 0.1) (layer "In2.Cu") (net 245))
  (segment (start 82.382252 118.655007) (end 82.376836 118.639528) (width 0.1) (layer "In2.Cu") (net 245))
  (segment (start 82.80434 118.534023) (end 82.792744 118.522427) (width 0.1) (layer "In2.Cu") (net 245))
  (segment (start 82.301768 118.403536) (end 82.248232 118.403536) (width 0.1) (layer "In2.Cu") (net 245))
  (segment (start 82.774931 118.460472) (end 82.769515 118.444993) (width 0.1) (layer "In2.Cu") (net 245))
  (segment (start 82.167747 118.655007) (end 82.159023 118.668892) (width 0.1) (layer "In2.Cu") (net 245))
  (segment (start 81.947427 118.565977) (end 81.933542 118.557253) (width 0.1) (layer "In2.Cu") (net 245))
  (segment (start 82.547427 118.680488) (end 82.533542 118.689212) (width 0.1) (layer "In2.Cu") (net 245))
  (segment (start 81.747988 118.55) (end 81.5 118.55) (width 0.1) (layer "In2.Cu") (net 245))
  (segment (start 82.78402 118.508542) (end 82.778604 118.493063) (width 0.1) (layer "In2.Cu") (net 245))
  (segment (start 82.633704 118.405372) (end 82.618225 118.410788) (width 0.1) (layer "In2.Cu") (net 245))
  (segment (start 82.778604 118.493063) (end 82.774931 118.460472) (width 0.1) (layer "In2.Cu") (net 245))
  (segment (start 82.402572 118.680488) (end 82.390976 118.668892) (width 0.1) (layer "In2.Cu") (net 245))
  (segment (start 82.133542 118.689212) (end 82.118063 118.694628) (width 0.1) (layer "In2.Cu") (net 245))
  (segment (start 82.367747 118.444993) (end 82.359023 118.431108) (width 0.1) (layer "In2.Cu") (net 245))
  (segment (start 82.749195 118.419512) (end 82.73531 118.410788) (width 0.1) (layer "In2.Cu") (net 245))
  (segment (start 82.559023 118.668892) (end 82.547427 118.680488) (width 0.1) (layer "In2.Cu") (net 245))
  (segment (start 82.390976 118.668892) (end 82.382252 118.655007) (width 0.1) (layer "In2.Cu") (net 245))
  (segment (start 82.031936 118.694628) (end 82.016457 118.689212) (width 0.1) (layer "In2.Cu") (net 245))
  (segment (start 82.190976 118.431108) (end 82.182252 118.444993) (width 0.1) (layer "In2.Cu") (net 245))
  (segment (start 82.576768 118.55) (end 82.575 118.55) (width 0.1) (layer "In2.Cu") (net 245))
  (segment (start 82.518063 118.694628) (end 82.501768 118.696464) (width 0.1) (layer "In2.Cu") (net 245))
  (segment (start 82.567747 118.655007) (end 82.559023 118.668892) (width 0.1) (layer "In2.Cu") (net 245))
  (segment (start 82.431936 118.694628) (end 82.416457 118.689212) (width 0.1) (layer "In2.Cu") (net 245))
  (segment (start 82.60434 118.419512) (end 82.592744 118.431108) (width 0.1) (layer "In2.Cu") (net 245))
  (segment (start 81.918063 118.551837) (end 81.901768 118.55) (width 0.1) (layer "In2.Cu") (net 245))
  (segment (start 82.333542 118.410788) (end 82.318063 118.405372) (width 0.1) (layer "In2.Cu") (net 245))
  (segment (start 82.359023 118.431108) (end 82.347427 118.419512) (width 0.1) (layer "In2.Cu") (net 245))
  (segment (start 82.376836 118.639528) (end 82.375 118.623232) (width 0.1) (layer "In2.Cu") (net 245))
  (segment (start 82.373163 118.460472) (end 82.367747 118.444993) (width 0.1) (layer "In2.Cu") (net 245))
  (segment (start 95.6 118.95) (end 95.6 118.85) (width 0.1) (layer "In2.Cu") (net 245))
  (segment (start 95 118.25) (end 87.7 118.25) (width 0.1) (layer "In2.Cu") (net 245))
  (segment (start 81.976836 118.639528) (end 81.973163 118.606937) (width 0.1) (layer "In2.Cu") (net 245))
  (segment (start 82.818225 118.542747) (end 82.80434 118.534023) (width 0.1) (layer "In2.Cu") (net 245))
  (segment (start 82.173163 118.639528) (end 82.167747 118.655007) (width 0.1) (layer "In2.Cu") (net 245))
  (segment (start 82.65 118.403536) (end 82.633704 118.405372) (width 0.1) (layer "In2.Cu") (net 245))
  (segment (start 82.573163 118.639528) (end 82.567747 118.655007) (width 0.1) (layer "In2.Cu") (net 245))
  (segment (start 82.048232 118.696464) (end 82.031936 118.694628) (width 0.1) (layer "In2.Cu") (net 245))
  (segment (start 82.182252 118.444993) (end 82.176836 118.460472) (width 0.1) (layer "In2.Cu") (net 245))
  (segment (start 82.576768 118.476768) (end 82.576768 118.55) (width 0.1) (layer "In2.Cu") (net 245))
  (segment (start 81.901768 118.55) (end 81.747988 118.55) (width 0.1) (layer "In2.Cu") (net 245))
  (segment (start 82.347427 118.419512) (end 82.333542 118.410788) (width 0.1) (layer "In2.Cu") (net 245))
  (segment (start 82.202572 118.419512) (end 82.190976 118.431108) (width 0.1) (layer "In2.Cu") (net 245))
  (segment (start 82.592744 118.431108) (end 82.58402 118.444993) (width 0.1) (layer "In2.Cu") (net 245))
  (segment (start 82.159023 118.668892) (end 82.147427 118.680488) (width 0.1) (layer "In2.Cu") (net 245))
  (segment (start 82.769515 118.444993) (end 82.760791 118.431108) (width 0.1) (layer "In2.Cu") (net 245))
  (segment (start 81.990976 118.668892) (end 81.982252 118.655007) (width 0.1) (layer "In2.Cu") (net 245))
  (segment (start 82.231936 118.405372) (end 82.216457 118.410788) (width 0.1) (layer "In2.Cu") (net 245))
  (segment (start 82.58402 118.444993) (end 82.578604 118.460472) (width 0.1) (layer "In2.Cu") (net 245))
  (segment (start 81.967747 118.591458) (end 81.959023 118.577573) (width 0.1) (layer "In2.Cu") (net 245))
  (segment (start 82.719831 118.405372) (end 82.703536 118.403536) (width 0.1) (layer "In2.Cu") (net 245))
  (segment (start 82.147427 118.680488) (end 82.133542 118.689212) (width 0.1) (layer "In2.Cu") (net 245))
  (segment (start 82.248232 118.403536) (end 82.231936 118.405372) (width 0.1) (layer "In2.Cu") (net 245))
  (segment (start 82.703536 118.403536) (end 82.65 118.403536) (width 0.1) (layer "In2.Cu") (net 245))
  (segment (start 87.7 118.25) (end 87.4 117.95) (width 0.1) (layer "In2.Cu") (net 245))
  (segment (start 95.6 118.85) (end 95 118.25) (width 0.1) (layer "In2.Cu") (net 245))
  (segment (start 82.375 118.476768) (end 82.373163 118.460472) (width 0.1) (layer "In2.Cu") (net 245))
  (segment (start 83.5 117.95) (end 82.901837 118.548163) (width 0.1) (layer "In2.Cu") (net 245))
  (segment (start 82.118063 118.694628) (end 82.101768 118.696464) (width 0.1) (layer "In2.Cu") (net 245))
  (segment (start 82.448232 118.696464) (end 82.431936 118.694628) (width 0.1) (layer "In2.Cu") (net 245))
  (segment (start 82.760791 118.431108) (end 82.749195 118.419512) (width 0.1) (layer "In2.Cu") (net 245))
  (segment (start 82.792744 118.522427) (end 82.78402 118.508542) (width 0.1) (layer "In2.Cu") (net 245))
  (segment (start 82.416457 118.689212) (end 82.402572 118.680488) (width 0.1) (layer "In2.Cu") (net 245))
  (segment (start 82.73531 118.410788) (end 82.719831 118.405372) (width 0.1) (layer "In2.Cu") (net 245))
  (segment (start 82.101768 118.696464) (end 82.048232 118.696464) (width 0.1) (layer "In2.Cu") (net 245))
  (segment (start 81.982252 118.655007) (end 81.976836 118.639528) (width 0.1) (layer "In2.Cu") (net 245))
  (segment (start 82.216457 118.410788) (end 82.202572 118.419512) (width 0.1) (layer "In2.Cu") (net 245))
  (segment (start 82.176836 118.460472) (end 82.175 118.476768) (width 0.1) (layer "In2.Cu") (net 245))
  (segment (start 82.578604 118.460472) (end 82.576768 118.476768) (width 0.1) (layer "In2.Cu") (net 245))
  (segment (start 82.533542 118.689212) (end 82.518063 118.694628) (width 0.1) (layer "In2.Cu") (net 245))
  (segment (start 82.016457 118.689212) (end 82.002572 118.680488) (width 0.1) (layer "In2.Cu") (net 245))
  (segment (start 82.618225 118.410788) (end 82.60434 118.419512) (width 0.1) (layer "In2.Cu") (net 245))
  (segment (start 82.575 118.623232) (end 82.573163 118.639528) (width 0.1) (layer "In2.Cu") (net 245))
  (segment (start 82.318063 118.405372) (end 82.301768 118.403536) (width 0.1) (layer "In2.Cu") (net 245))
  (segment (start 87.4 117.95) (end 83.5 117.95) (width 0.1) (layer "In2.Cu") (net 245))
  (segment (start 81.959023 118.577573) (end 81.947427 118.565977) (width 0.1) (layer "In2.Cu") (net 245))
  (segment (start 82.002572 118.680488) (end 81.990976 118.668892) (width 0.1) (layer "In2.Cu") (net 245))
  (segment (start 82.501768 118.696464) (end 82.448232 118.696464) (width 0.1) (layer "In2.Cu") (net 245))
  (segment (start 81.005 119.045) (end 81.5 118.55) (width 0.1) (layer "B.Cu") (net 245))
  (segment (start 79.84 119.045) (end 81.005 119.045) (width 0.1) (layer "B.Cu") (net 245))
  (segment (start 84.659439 120.004407) (end 84.639264 119.994691) (width 0.1) (layer "F.Cu") (net 246))
  (segment (start 84.273277 120.573175) (end 84.259315 120.590682) (width 0.1) (layer "F.Cu") (net 246))
  (segment (start 84.692057 120.340906) (end 84.692057 120.35875) (width 0.1) (layer "F.Cu") (net 246))
  (segment (start 84.238723 120.318717) (end 84.229007 120.338892) (width 0.1) (layer "F.Cu") (net 246))
  (segment (start 84.334592 120.27255) (end 84.312199 120.27255) (width 0.1) (layer "F.Cu") (net 246))
  (segment (start 85.1 119.75) (end 84.825 120.025) (width 0.1) (layer "F.Cu") (net 246))
  (segment (start 84.688086 120.376147) (end 84.680344 120.392225) (width 0.1) (layer "F.Cu") (net 246))
  (segment (start 84.287976 120.531168) (end 84.282993 120.553) (width 0.1) (layer "F.Cu") (net 246))
  (segment (start 84.229007 120.404948) (end 84.238723 120.425123) (width 0.1) (layer "F.Cu") (net 246))
  (segment (start 84.553033 120.004407) (end 84.535526 120.018369) (width 0.1) (layer "F.Cu") (net 246))
  (segment (start 84.669217 120.293481) (end 84.680344 120.307431) (width 0.1) (layer "F.Cu") (net 246))
  (segment (start 84.270192 120.287249) (end 84.252685 120.30121) (width 0.1) (layer "F.Cu") (net 246))
  (segment (start 84.238723 120.425123) (end 84.252685 120.442631) (width 0.1) (layer "F.Cu") (net 246))
  (segment (start 84.224024 120.360724) (end 84.224024 120.383117) (width 0.1) (layer "F.Cu") (net 246))
  (segment (start 84.282993 120.553) (end 84.273277 120.573175) (width 0.1) (layer "F.Cu") (net 246))
  (segment (start 84.640493 120.434902) (end 84.626541 120.446029) (width 0.1) (layer "F.Cu") (net 246))
  (segment (start 84.639264 119.994691) (end 84.617433 119.989708) (width 0.1) (layer "F.Cu") (net 246))
  (segment (start 84.743092 120.05366) (end 84.721261 120.048677) (width 0.1) (layer "F.Cu") (net 246))
  (segment (start 84.721261 120.048677) (end 84.701086 120.038961) (width 0.1) (layer "F.Cu") (net 246))
  (segment (start 84.610463 120.453771) (end 84.593066 120.457742) (width 0.1) (layer "F.Cu") (net 246))
  (segment (start 84.521564 120.035876) (end 84.511848 120.056051) (width 0.1) (layer "F.Cu") (net 246))
  (segment (start 84.535526 120.018369) (end 84.521564 120.035876) (width 0.1) (layer "F.Cu") (net 246))
  (segment (start 84.535526 120.15979) (end 84.669217 120.293481) (width 0.1) (layer "F.Cu") (net 246))
  (segment (start 84.541747 120.446029) (end 84.527797 120.434902) (width 0.1) (layer "F.Cu") (net 246))
  (segment (start 84.683578 120.025) (end 84.676947 120.018369) (width 0.1) (layer "F.Cu") (net 246))
  (segment (start 84.701086 120.038961) (end 84.683578 120.025) (width 0.1) (layer "F.Cu") (net 246))
  (segment (start 84.290368 120.277533) (end 84.270192 120.287249) (width 0.1) (layer "F.Cu") (net 246))
  (segment (start 84.229007 120.338892) (end 84.224024 120.360724) (width 0.1) (layer "F.Cu") (net 246))
  (segment (start 84.287976 120.508775) (end 84.287976 120.531168) (width 0.1) (layer "F.Cu") (net 246))
  (segment (start 84.680344 120.392225) (end 84.669217 120.406177) (width 0.1) (layer "F.Cu") (net 246))
  (segment (start 84.282993 120.486944) (end 84.287976 120.508775) (width 0.1) (layer "F.Cu") (net 246))
  (segment (start 83.15 121.7) (end 83.15 122.65) (width 0.1) (layer "F.Cu") (net 246))
  (segment (start 84.669217 120.406177) (end 84.640493 120.434902) (width 0.1) (layer "F.Cu") (net 246))
  (segment (start 84.511848 120.122107) (end 84.521564 120.142282) (width 0.1) (layer "F.Cu") (net 246))
  (segment (start 84.626541 120.446029) (end 84.610463 120.453771) (width 0.1) (layer "F.Cu") (net 246))
  (segment (start 84.521564 120.142282) (end 84.535526 120.15979) (width 0.1) (layer "F.Cu") (net 246))
  (segment (start 84.312199 120.27255) (end 84.290368 120.277533) (width 0.1) (layer "F.Cu") (net 246))
  (segment (start 84.573208 119.994691) (end 84.553033 120.004407) (width 0.1) (layer "F.Cu") (net 246))
  (segment (start 84.688086 120.323509) (end 84.692057 120.340906) (width 0.1) (layer "F.Cu") (net 246))
  (segment (start 84.356424 120.277533) (end 84.334592 120.27255) (width 0.1) (layer "F.Cu") (net 246))
  (segment (start 84.557825 120.453771) (end 84.541747 120.446029) (width 0.1) (layer "F.Cu") (net 246))
  (segment (start 84.273277 120.466769) (end 84.282993 120.486944) (width 0.1) (layer "F.Cu") (net 246))
  (segment (start 84.692057 120.35875) (end 84.688086 120.376147) (width 0.1) (layer "F.Cu") (net 246))
  (segment (start 84.252685 120.30121) (end 84.238723 120.318717) (width 0.1) (layer "F.Cu") (net 246))
  (segment (start 84.807492 120.038961) (end 84.787317 120.048677) (width 0.1) (layer "F.Cu") (net 246))
  (segment (start 84.593066 120.457742) (end 84.575222 120.457742) (width 0.1) (layer "F.Cu") (net 246))
  (segment (start 84.575222 120.457742) (end 84.557825 120.453771) (width 0.1) (layer "F.Cu") (net 246))
  (segment (start 84.511848 120.056051) (end 84.506865 120.077883) (width 0.1) (layer "F.Cu") (net 246))
  (segment (start 84.527797 120.434902) (end 84.394106 120.30121) (width 0.1) (layer "F.Cu") (net 246))
  (segment (start 84.787317 120.048677) (end 84.765485 120.05366) (width 0.1) (layer "F.Cu") (net 246))
  (segment (start 84.394106 120.30121) (end 84.376599 120.287249) (width 0.1) (layer "F.Cu") (net 246))
  (segment (start 94.4 122.55) (end 94 122.95) (width 0.1) (layer "F.Cu") (net 246))
  (segment (start 84.259315 120.449261) (end 84.273277 120.466769) (width 0.1) (layer "F.Cu") (net 246))
  (segment (start 84.506865 120.100276) (end 84.511848 120.122107) (width 0.1) (layer "F.Cu") (net 246))
  (segment (start 84.825 120.025) (end 84.807492 120.038961) (width 0.1) (layer "F.Cu") (net 246))
  (segment (start 84.252685 120.442631) (end 84.259315 120.449261) (width 0.1) (layer "F.Cu") (net 246))
  (segment (start 84.617433 119.989708) (end 84.59504 119.989708) (width 0.1) (layer "F.Cu") (net 246))
  (segment (start 84.765485 120.05366) (end 84.743092 120.05366) (width 0.1) (layer "F.Cu") (net 246))
  (segment (start 84.506865 120.077883) (end 84.506865 120.100276) (width 0.1) (layer "F.Cu") (net 246))
  (segment (start 84.376599 120.287249) (end 84.356424 120.277533) (width 0.1) (layer "F.Cu") (net 246))
  (segment (start 84.259315 120.590682) (end 83.15 121.7) (width 0.1) (layer "F.Cu") (net 246))
  (segment (start 84.680344 120.307431) (end 84.688086 120.323509) (width 0.1) (layer "F.Cu") (net 246))
  (segment (start 84.676947 120.018369) (end 84.659439 120.004407) (width 0.1) (layer "F.Cu") (net 246))
  (segment (start 84.224024 120.383117) (end 84.229007 120.404948) (width 0.1) (layer "F.Cu") (net 246))
  (segment (start 84.59504 119.989708) (end 84.573208 119.994691) (width 0.1) (layer "F.Cu") (net 246))
  (via blind (at 94 122.95) (size 0.5) (drill 0.2) (layers "F.Cu" "In2.Cu") (net 246))
  (via (at 83.15 122.65) (size 0.5) (drill 0.2) (layers "F.Cu" "B.Cu") (net 246))
  (segment (start 92.75 122.55) (end 93.1 122.9) (width 0.1) (layer "In2.Cu") (net 246))
  (segment (start 87.7725 122.3) (end 87.25 122.3) (width 0.1) (layer "In2.Cu") (net 246))
  (segment (start 83.45 122.95) (end 83.15 122.65) (width 0.1) (layer "In2.Cu") (net 246))
  (segment (start 88.0225 122.55) (end 88.95 122.55) (width 0.1) (layer "In2.Cu") (net 246))
  (segment (start 86.6 122.95) (end 83.45 122.95) (width 0.1) (layer "In2.Cu") (net 246))
  (segment (start 91.1 122.75) (end 91.3 122.55) (width 0.1) (layer "In2.Cu") (net 246))
  (segment (start 88.0225 122.55) (end 87.7725 122.3) (width 0.1) (layer "In2.Cu") (net 246))
  (segment (start 94 122.95) (end 94 122.9) (width 0.1) (layer "In2.Cu") (net 246))
  (segment (start 94 122.9) (end 93.1 122.9) (width 0.1) (layer "In2.Cu") (net 246))
  (segment (start 88.95 122.55) (end 89.15 122.75) (width 0.1) (layer "In2.Cu") (net 246))
  (segment (start 92.75 122.55) (end 91.3 122.55) (width 0.1) (layer "In2.Cu") (net 246))
  (segment (start 87.25 122.3) (end 86.6 122.95) (width 0.1) (layer "In2.Cu") (net 246))
  (segment (start 89.15 122.75) (end 91.1 122.75) (width 0.1) (layer "In2.Cu") (net 246))
  (segment (start 82.99 122.81) (end 83.15 122.65) (width 0.1) (layer "B.Cu") (net 246))
  (segment (start 82.99 123.695) (end 82.99 122.81) (width 0.1) (layer "B.Cu") (net 246))
  (segment (start 82.3 119.35) (end 81.9 118.95) (width 0.1) (layer "F.Cu") (net 247))
  (segment (start 96.4 121.35) (end 96.8 121.75) (width 0.1) (layer "F.Cu") (net 247))
  (via (at 82.3 119.35) (size 0.5) (drill 0.2) (layers "F.Cu" "B.Cu") (net 247))
  (via (at 96.4 121.35) (size 0.5) (drill 0.2) (layers "F.Cu" "B.Cu") (net 247))
  (segment (start 82.690096 119.006611) (end 82.697492 119.027747) (width 0.1) (layer "In5.Cu") (net 247))
  (segment (start 82.9 119.05) (end 82.902507 119.027747) (width 0.1) (layer "In5.Cu") (net 247))
  (segment (start 82.709903 119.111091) (end 82.721816 119.130051) (width 0.1) (layer "In5.Cu") (net 247))
  (segment (start 82.45 118.95) (end 82.6 118.95) (width 0.1) (layer "In5.Cu") (net 247))
  (segment (start 82.721816 119.130051) (end 82.737651 119.145886) (width 0.1) (layer "In5.Cu") (net 247))
  (segment (start 82.890096 119.111091) (end 82.897492 119.089955) (width 0.1) (layer "In5.Cu") (net 247))
  (segment (start 83 118.95) (end 93.075 118.95) (width 0.1) (layer "In5.Cu") (net 247))
  (segment (start 82.7 119.067703) (end 82.702507 119.089955) (width 0.1) (layer "In5.Cu") (net 247))
  (segment (start 82.3 119.1) (end 82.45 118.95) (width 0.1) (layer "In5.Cu") (net 247))
  (segment (start 82.777747 119.165195) (end 82.8 119.167703) (width 0.1) (layer "In5.Cu") (net 247))
  (segment (start 82.697492 119.027747) (end 82.7 119.05) (width 0.1) (layer "In5.Cu") (net 247))
  (segment (start 82.8 119.167703) (end 82.822252 119.165195) (width 0.1) (layer "In5.Cu") (net 247))
  (segment (start 82.622252 118.952507) (end 82.643388 118.959903) (width 0.1) (layer "In5.Cu") (net 247))
  (segment (start 93.075 118.95) (end 95.475 121.35) (width 0.1) (layer "In5.Cu") (net 247))
  (segment (start 82.956611 118.959903) (end 82.977747 118.952507) (width 0.1) (layer "In5.Cu") (net 247))
  (segment (start 82.9 119.067703) (end 82.9 119.05) (width 0.1) (layer "In5.Cu") (net 247))
  (segment (start 82.702507 119.089955) (end 82.709903 119.111091) (width 0.1) (layer "In5.Cu") (net 247))
  (segment (start 82.937651 118.971816) (end 82.956611 118.959903) (width 0.1) (layer "In5.Cu") (net 247))
  (segment (start 82.3 119.35) (end 82.3 119.1) (width 0.1) (layer "In5.Cu") (net 247))
  (segment (start 82.977747 118.952507) (end 83 118.95) (width 0.1) (layer "In5.Cu") (net 247))
  (segment (start 82.921816 118.987651) (end 82.937651 118.971816) (width 0.1) (layer "In5.Cu") (net 247))
  (segment (start 82.902507 119.027747) (end 82.909903 119.006611) (width 0.1) (layer "In5.Cu") (net 247))
  (segment (start 82.678183 118.987651) (end 82.690096 119.006611) (width 0.1) (layer "In5.Cu") (net 247))
  (segment (start 82.897492 119.089955) (end 82.9 119.067703) (width 0.1) (layer "In5.Cu") (net 247))
  (segment (start 82.822252 119.165195) (end 82.843388 119.157799) (width 0.1) (layer "In5.Cu") (net 247))
  (segment (start 82.843388 119.157799) (end 82.862348 119.145886) (width 0.1) (layer "In5.Cu") (net 247))
  (segment (start 95.475 121.35) (end 96.4 121.35) (width 0.1) (layer "In5.Cu") (net 247))
  (segment (start 82.878183 119.130051) (end 82.890096 119.111091) (width 0.1) (layer "In5.Cu") (net 247))
  (segment (start 82.737651 119.145886) (end 82.756611 119.157799) (width 0.1) (layer "In5.Cu") (net 247))
  (segment (start 82.756611 119.157799) (end 82.777747 119.165195) (width 0.1) (layer "In5.Cu") (net 247))
  (segment (start 82.662348 118.971816) (end 82.678183 118.987651) (width 0.1) (layer "In5.Cu") (net 247))
  (segment (start 82.7 119.05) (end 82.7 119.067703) (width 0.1) (layer "In5.Cu") (net 247))
  (segment (start 82.862348 119.145886) (end 82.878183 119.130051) (width 0.1) (layer "In5.Cu") (net 247))
  (segment (start 82.909903 119.006611) (end 82.921816 118.987651) (width 0.1) (layer "In5.Cu") (net 247))
  (segment (start 82.6 118.95) (end 82.622252 118.952507) (width 0.1) (layer "In5.Cu") (net 247))
  (segment (start 82.643388 118.959903) (end 82.662348 118.971816) (width 0.1) (layer "In5.Cu") (net 247))
  (segment (start 81.04 119.545) (end 79.84 119.545) (width 0.1) (layer "B.Cu") (net 247))
  (segment (start 81.235 119.35) (end 82.3 119.35) (width 0.1) (layer "B.Cu") (net 247))
  (segment (start 81.235 119.35) (end 81.04 119.545) (width 0.1) (layer "B.Cu") (net 247))
  (segment (start 82.252507 120.377109) (end 82.259903 120.398245) (width 0.1) (layer "F.Cu") (net 248))
  (segment (start 82.240096 119.806611) (end 82.247492 119.827747) (width 0.1) (layer "F.Cu") (net 248))
  (segment (start 82.271816 120.417205) (end 82.287651 120.43304) (width 0.1) (layer "F.Cu") (net 248))
  (segment (start 82.428183 120.417205) (end 82.440096 120.398245) (width 0.1) (layer "F.Cu") (net 248))
  (segment (start 82.447492 120.377109) (end 82.45 120.354857) (width 0.1) (layer "F.Cu") (net 248))
  (segment (start 82.55 119.75) (end 82.785006 119.75) (width 0.1) (layer "F.Cu") (net 248))
  (segment (start 82.15 119.75) (end 82.172252 119.752507) (width 0.1) (layer "F.Cu") (net 248))
  (segment (start 82.172252 119.752507) (end 82.193388 119.759903) (width 0.1) (layer "F.Cu") (net 248))
  (segment (start 95.2 120.15) (end 94.8 120.55) (width 0.1) (layer "F.Cu") (net 248))
  (segment (start 82.212348 119.771816) (end 82.228183 119.787651) (width 0.1) (layer "F.Cu") (net 248))
  (segment (start 82.25 120.354857) (end 82.252507 120.377109) (width 0.1) (layer "F.Cu") (net 248))
  (segment (start 82.35 120.454857) (end 82.372252 120.452349) (width 0.1) (layer "F.Cu") (net 248))
  (segment (start 82.487651 119.771816) (end 82.506611 119.759903) (width 0.1) (layer "F.Cu") (net 248))
  (segment (start 82.25 119.85) (end 82.25 120.354857) (width 0.1) (layer "F.Cu") (net 248))
  (segment (start 82.393388 120.444953) (end 82.412348 120.43304) (width 0.1) (layer "F.Cu") (net 248))
  (segment (start 82.785006 119.75) (end 82.790006 119.745) (width 0.1) (layer "F.Cu") (net 248))
  (segment (start 82.471816 119.787651) (end 82.487651 119.771816) (width 0.1) (layer "F.Cu") (net 248))
  (segment (start 82.327747 120.452349) (end 82.35 120.454857) (width 0.1) (layer "F.Cu") (net 248))
  (segment (start 82.259903 120.398245) (end 82.271816 120.417205) (width 0.1) (layer "F.Cu") (net 248))
  (segment (start 82.247492 119.827747) (end 82.25 119.85) (width 0.1) (layer "F.Cu") (net 248))
  (segment (start 82.228183 119.787651) (end 82.240096 119.806611) (width 0.1) (layer "F.Cu") (net 248))
  (segment (start 81.9 119.75) (end 82.15 119.75) (width 0.1) (layer "F.Cu") (net 248))
  (segment (start 82.452507 119.827747) (end 82.459903 119.806611) (width 0.1) (layer "F.Cu") (net 248))
  (segment (start 82.412348 120.43304) (end 82.428183 120.417205) (width 0.1) (layer "F.Cu") (net 248))
  (segment (start 82.45 120.354857) (end 82.45 119.85) (width 0.1) (layer "F.Cu") (net 248))
  (segment (start 82.287651 120.43304) (end 82.306611 120.444953) (width 0.1) (layer "F.Cu") (net 248))
  (segment (start 82.372252 120.452349) (end 82.393388 120.444953) (width 0.1) (layer "F.Cu") (net 248))
  (segment (start 82.440096 120.398245) (end 82.447492 120.377109) (width 0.1) (layer "F.Cu") (net 248))
  (segment (start 82.306611 120.444953) (end 82.327747 120.452349) (width 0.1) (layer "F.Cu") (net 248))
  (segment (start 82.459903 119.806611) (end 82.471816 119.787651) (width 0.1) (layer "F.Cu") (net 248))
  (segment (start 82.506611 119.759903) (end 82.527747 119.752507) (width 0.1) (layer "F.Cu") (net 248))
  (segment (start 82.45 119.85) (end 82.452507 119.827747) (width 0.1) (layer "F.Cu") (net 248))
  (segment (start 82.193388 119.759903) (end 82.212348 119.771816) (width 0.1) (layer "F.Cu") (net 248))
  (segment (start 82.527747 119.752507) (end 82.55 119.75) (width 0.1) (layer "F.Cu") (net 248))
  (via blind (at 94.8 120.55) (size 0.5) (drill 0.2) (layers "F.Cu" "In2.Cu") (net 248))
  (via (at 82.790006 119.745) (size 0.5) (drill 0.2) (layers "F.Cu" "B.Cu") (net 248))
  (segment (start 83.668388 119.533398) (end 83.647252 119.540794) (width 0.1) (layer "In2.Cu") (net 248))
  (segment (start 94.4 120.15) (end 93 120.15) (width 0.1) (layer "In2.Cu") (net 248))
  (segment (start 83.534903 119.48669) (end 83.527507 119.465554) (width 0.1) (layer "In2.Cu") (net 248))
  (segment (start 83.45335 119.156699) (end 83.39665 119.156699) (width 0.1) (layer "In2.Cu") (net 248))
  (segment (start 83.517904 119.197261) (end 83.509368 119.183675) (width 0.1) (layer "In2.Cu") (net 248))
  (segment (start 83.647252 119.540794) (end 83.625 119.543301) (width 0.1) (layer "In2.Cu") (net 248))
  (segment (start 83.122576 119.375144) (end 83.115428 119.354716) (width 0.1) (layer "In2.Cu") (net 248))
  (segment (start 83.523203 119.212405) (end 83.517904 119.197261) (width 0.1) (layer "In2.Cu") (net 248))
  (segment (start 83.127423 119.418158) (end 83.122576 119.375144) (width 0.1) (layer "In2.Cu") (net 248))
  (segment (start 83.332095 119.197261) (end 83.326796 119.212405) (width 0.1) (layer "In2.Cu") (net 248))
  (segment (start 83.315428 119.438586) (end 83.303914 119.456912) (width 0.1) (layer "In2.Cu") (net 248))
  (segment (start 83.768912 119.163794) (end 83.755326 119.17233) (width 0.1) (layer "In2.Cu") (net 248))
  (segment (start 83.687348 119.521485) (end 83.668388 119.533398) (width 0.1) (layer "In2.Cu") (net 248))
  (segment (start 84.6 119.95) (end 84.2 119.55) (width 0.1) (layer "In2.Cu") (net 248))
  (segment (start 83.070284 119.309572) (end 83.049856 119.302424) (width 0.1) (layer "In2.Cu") (net 248))
  (segment (start 83.546816 119.50565) (end 83.534903 119.48669) (width 0.1) (layer "In2.Cu") (net 248))
  (segment (start 87.6 119.9) (end 87.55 119.95) (width 0.1) (layer "In2.Cu") (net 248))
  (segment (start 92.75 119.9) (end 87.6 119.9) (width 0.1) (layer "In2.Cu") (net 248))
  (segment (start 83.049856 119.302424) (end 83.02835 119.3) (width 0.1) (layer "In2.Cu") (net 248))
  (segment (start 83.325 119.228349) (end 83.325 119.396651) (width 0.1) (layer "In2.Cu") (net 248))
  (segment (start 83.715096 119.48669) (end 83.703183 119.50565) (width 0.1) (layer "In2.Cu") (net 248))
  (segment (start 83.943981 119.273023) (end 83.935445 119.259437) (width 0.1) (layer "In2.Cu") (net 248))
  (segment (start 83.930146 119.244293) (end 83.926553 119.212405) (width 0.1) (layer "In2.Cu") (net 248))
  (segment (start 87.55 119.95) (end 84.6 119.95) (width 0.1) (layer "In2.Cu") (net 248))
  (segment (start 83.146085 119.456912) (end 83.134571 119.438586) (width 0.1) (layer "In2.Cu") (net 248))
  (segment (start 93 120.15) (end 92.75 119.9) (width 0.1) (layer "In2.Cu") (net 248))
  (segment (start 83.134571 119.438586) (end 83.127423 119.418158) (width 0.1) (layer "In2.Cu") (net 248))
  (segment (start 83.249856 119.490878) (end 83.22835 119.493301) (width 0.1) (layer "In2.Cu") (net 248))
  (segment (start 83.562651 119.521485) (end 83.546816 119.50565) (width 0.1) (layer "In2.Cu") (net 248))
  (segment (start 83.270284 119.48373) (end 83.249856 119.490878) (width 0.1) (layer "In2.Cu") (net 248))
  (segment (start 83.22165 119.493301) (end 83.200143 119.490878) (width 0.1) (layer "In2.Cu") (net 248))
  (segment (start 83.380706 119.158495) (end 83.365562 119.163794) (width 0.1) (layer "In2.Cu") (net 248))
  (segment (start 83.984056 119.298203) (end 83.968912 119.292904) (width 0.1) (layer "In2.Cu") (net 248))
  (segment (start 83.887787 119.163794) (end 83.872643 119.158495) (width 0.1) (layer "In2.Cu") (net 248))
  (segment (start 83.525 119.443301) (end 83.525 119.228349) (width 0.1) (layer "In2.Cu") (net 248))
  (segment (start 83.703183 119.50565) (end 83.687348 119.521485) (width 0.1) (layer "In2.Cu") (net 248))
  (segment (start 83.722492 119.465554) (end 83.715096 119.48669) (width 0.1) (layer "In2.Cu") (net 248))
  (segment (start 83.509368 119.183675) (end 83.498023 119.17233) (width 0.1) (layer "In2.Cu") (net 248))
  (segment (start 83.725 119.3) (end 83.725 119.443301) (width 0.1) (layer "In2.Cu") (net 248))
  (segment (start 83.22835 119.493301) (end 83.22165 119.493301) (width 0.1) (layer "In2.Cu") (net 248))
  (segment (start 83.525 119.228349) (end 83.523203 119.212405) (width 0.1) (layer "In2.Cu") (net 248))
  (segment (start 83.115428 119.354716) (end 83.103914 119.33639) (width 0.1) (layer "In2.Cu") (net 248))
  (segment (start 83.161389 119.472216) (end 83.146085 119.456912) (width 0.1) (layer "In2.Cu") (net 248))
  (segment (start 83.72835 119.22835) (end 83.72835 119.3) (width 0.1) (layer "In2.Cu") (net 248))
  (segment (start 83.755326 119.17233) (end 83.743981 119.183675) (width 0.1) (layer "In2.Cu") (net 248))
  (segment (start 83.469293 119.158495) (end 83.45335 119.156699) (width 0.1) (layer "In2.Cu") (net 248))
  (segment (start 83.784056 119.158495) (end 83.768912 119.163794) (width 0.1) (layer "In2.Cu") (net 248))
  (segment (start 83.365562 119.163794) (end 83.351976 119.17233) (width 0.1) (layer "In2.Cu") (net 248))
  (segment (start 83.322576 119.418158) (end 83.315428 119.438586) (width 0.1) (layer "In2.Cu") (net 248))
  (segment (start 83.955326 119.284368) (end 83.943981 119.273023) (width 0.1) (layer "In2.Cu") (net 248))
  (segment (start 94.8 120.55) (end 94.4 120.15) (width 0.1) (layer "In2.Cu") (net 248))
  (segment (start 83.103914 119.33639) (end 83.08861 119.321086) (width 0.1) (layer "In2.Cu") (net 248))
  (segment (start 83.872643 119.158495) (end 83.8567 119.156699) (width 0.1) (layer "In2.Cu") (net 248))
  (segment (start 83.901373 119.17233) (end 83.887787 119.163794) (width 0.1) (layer "In2.Cu") (net 248))
  (segment (start 83.72835 119.3) (end 83.725 119.3) (width 0.1) (layer "In2.Cu") (net 248))
  (segment (start 83.926553 119.212405) (end 83.921254 119.197261) (width 0.1) (layer "In2.Cu") (net 248))
  (segment (start 83.200143 119.490878) (end 83.179715 119.48373) (width 0.1) (layer "In2.Cu") (net 248))
  (segment (start 83.08861 119.321086) (end 83.070284 119.309572) (width 0.1) (layer "In2.Cu") (net 248))
  (segment (start 84.2 119.4) (end 84.1 119.3) (width 0.1) (layer "In2.Cu") (net 248))
  (segment (start 83.179715 119.48373) (end 83.161389 119.472216) (width 0.1) (layer "In2.Cu") (net 248))
  (segment (start 82.790006 119.409994) (end 82.790006 119.745) (width 0.1) (layer "In2.Cu") (net 248))
  (segment (start 84 119.3) (end 83.984056 119.298203) (width 0.1) (layer "In2.Cu") (net 248))
  (segment (start 84.1 119.3) (end 84 119.3) (width 0.1) (layer "In2.Cu") (net 248))
  (segment (start 83.28861 119.472216) (end 83.270284 119.48373) (width 0.1) (layer "In2.Cu") (net 248))
  (segment (start 83.39665 119.156699) (end 83.380706 119.158495) (width 0.1) (layer "In2.Cu") (net 248))
  (segment (start 83.921254 119.197261) (end 83.912718 119.183675) (width 0.1) (layer "In2.Cu") (net 248))
  (segment (start 83.325 119.396651) (end 83.322576 119.418158) (width 0.1) (layer "In2.Cu") (net 248))
  (segment (start 83.735445 119.197261) (end 83.730146 119.212405) (width 0.1) (layer "In2.Cu") (net 248))
  (segment (start 83.351976 119.17233) (end 83.340631 119.183675) (width 0.1) (layer "In2.Cu") (net 248))
  (segment (start 84.2 119.55) (end 84.2 119.4) (width 0.1) (layer "In2.Cu") (net 248))
  (segment (start 83.602747 119.540794) (end 83.581611 119.533398) (width 0.1) (layer "In2.Cu") (net 248))
  (segment (start 82.9 119.3) (end 82.790006 119.409994) (width 0.1) (layer "In2.Cu") (net 248))
  (segment (start 83.8 119.156699) (end 83.784056 119.158495) (width 0.1) (layer "In2.Cu") (net 248))
  (segment (start 83.484437 119.163794) (end 83.469293 119.158495) (width 0.1) (layer "In2.Cu") (net 248))
  (segment (start 83.912718 119.183675) (end 83.901373 119.17233) (width 0.1) (layer "In2.Cu") (net 248))
  (segment (start 83.02835 119.3) (end 82.9 119.3) (width 0.1) (layer "In2.Cu") (net 248))
  (segment (start 83.340631 119.183675) (end 83.332095 119.197261) (width 0.1) (layer "In2.Cu") (net 248))
  (segment (start 83.968912 119.292904) (end 83.955326 119.284368) (width 0.1) (layer "In2.Cu") (net 248))
  (segment (start 83.935445 119.259437) (end 83.930146 119.244293) (width 0.1) (layer "In2.Cu") (net 248))
  (segment (start 83.8567 119.156699) (end 83.8 119.156699) (width 0.1) (layer "In2.Cu") (net 248))
  (segment (start 83.326796 119.212405) (end 83.325 119.228349) (width 0.1) (layer "In2.Cu") (net 248))
  (segment (start 83.725 119.443301) (end 83.722492 119.465554) (width 0.1) (layer "In2.Cu") (net 248))
  (segment (start 83.498023 119.17233) (end 83.484437 119.163794) (width 0.1) (layer "In2.Cu") (net 248))
  (segment (start 83.303914 119.456912) (end 83.28861 119.472216) (width 0.1) (layer "In2.Cu") (net 248))
  (segment (start 83.743981 119.183675) (end 83.735445 119.197261) (width 0.1) (layer "In2.Cu") (net 248))
  (segment (start 83.625 119.543301) (end 83.602747 119.540794) (width 0.1) (layer "In2.Cu") (net 248))
  (segment (start 83.581611 119.533398) (end 83.562651 119.521485) (width 0.1) (layer "In2.Cu") (net 248))
  (segment (start 83.730146 119.212405) (end 83.72835 119.22835) (width 0.1) (layer "In2.Cu") (net 248))
  (segment (start 83.527507 119.465554) (end 83.525 119.443301) (width 0.1) (layer "In2.Cu") (net 248))
  (segment (start 82.785006 119.75) (end 82.790006 119.745) (width 0.1) (layer "B.Cu") (net 248))
  (segment (start 81.285 119.75) (end 82.785006 119.75) (width 0.1) (layer "B.Cu") (net 248))
  (segment (start 80.99 120.045) (end 79.84 120.045) (width 0.1) (layer "B.Cu") (net 248))
  (segment (start 81.285 119.75) (end 80.99 120.045) (width 0.1) (layer "B.Cu") (net 248))
  (segment (start 81.1 119.75) (end 81.5 120.15) (width 0.1) (layer "F.Cu") (net 249))
  (segment (start 96 121.75) (end 95.6 121.35) (width 0.1) (layer "F.Cu") (net 249))
  (via (at 81.5 120.15) (size 0.5) (drill 0.2) (layers "F.Cu" "B.Cu") (net 249))
  (via blind (at 95.6 121.35) (size 0.5) (drill 0.2) (layers "F.Cu" "In2.Cu") (net 249))
  (segment (start 82.8 120.45) (end 87.95 120.45) (width 0.1) (layer "In2.Cu") (net 249))
  (segment (start 82.137651 120.850481) (end 82.156611 120.862394) (width 0.1) (layer "In2.Cu") (net 249))
  (segment (start 82.043388 120.459903) (end 82.062348 120.471816) (width 0.1) (layer "In2.Cu") (net 249))
  (segment (start 82.3 120.772298) (end 82.3 120.55) (width 0.1) (layer "In2.Cu") (net 249))
  (segment (start 82.278183 120.834646) (end 82.290096 120.815686) (width 0.1) (layer "In2.Cu") (net 249))
  (segment (start 82.5 120.55) (end 82.5 120.63651) (width 0.1) (layer "In2.Cu") (net 249))
  (segment (start 82.7 120.63651) (end 82.7 120.55) (width 0.1) (layer "In2.Cu") (net 249))
  (segment (start 82.302507 120.527747) (end 82.309903 120.506611) (width 0.1) (layer "In2.Cu") (net 249))
  (segment (start 95.2 120.95) (end 95.6 121.35) (width 0.1) (layer "In2.Cu") (net 249))
  (segment (start 82.577747 120.734002) (end 82.6 120.73651) (width 0.1) (layer "In2.Cu") (net 249))
  (segment (start 82.090096 120.506611) (end 82.097492 120.527747) (width 0.1) (layer "In2.Cu") (net 249))
  (segment (start 82.521816 120.698858) (end 82.537651 120.714693) (width 0.1) (layer "In2.Cu") (net 249))
  (segment (start 82.709903 120.506611) (end 82.721816 120.487651) (width 0.1) (layer "In2.Cu") (net 249))
  (segment (start 81.8 120.45) (end 82 120.45) (width 0.1) (layer "In2.Cu") (net 249))
  (segment (start 82.643388 120.726606) (end 82.662348 120.714693) (width 0.1) (layer "In2.Cu") (net 249))
  (segment (start 82.490096 120.506611) (end 82.497492 120.527747) (width 0.1) (layer "In2.Cu") (net 249))
  (segment (start 82.702507 120.527747) (end 82.709903 120.506611) (width 0.1) (layer "In2.Cu") (net 249))
  (segment (start 82.377747 120.452507) (end 82.4 120.45) (width 0.1) (layer "In2.Cu") (net 249))
  (segment (start 82.022252 120.452507) (end 82.043388 120.459903) (width 0.1) (layer "In2.Cu") (net 249))
  (segment (start 82.777747 120.452507) (end 82.8 120.45) (width 0.1) (layer "In2.Cu") (net 249))
  (segment (start 82.422252 120.452507) (end 82.443388 120.459903) (width 0.1) (layer "In2.Cu") (net 249))
  (segment (start 82.697492 120.658762) (end 82.7 120.63651) (width 0.1) (layer "In2.Cu") (net 249))
  (segment (start 82.062348 120.471816) (end 82.078183 120.487651) (width 0.1) (layer "In2.Cu") (net 249))
  (segment (start 82.356611 120.459903) (end 82.377747 120.452507) (width 0.1) (layer "In2.Cu") (net 249))
  (segment (start 82.337651 120.471816) (end 82.356611 120.459903) (width 0.1) (layer "In2.Cu") (net 249))
  (segment (start 82.4 120.45) (end 82.422252 120.452507) (width 0.1) (layer "In2.Cu") (net 249))
  (segment (start 82 120.45) (end 82.022252 120.452507) (width 0.1) (layer "In2.Cu") (net 249))
  (segment (start 82.721816 120.487651) (end 82.737651 120.471816) (width 0.1) (layer "In2.Cu") (net 249))
  (segment (start 82.502507 120.658762) (end 82.509903 120.679898) (width 0.1) (layer "In2.Cu") (net 249))
  (segment (start 82.2 120.872298) (end 82.222252 120.86979) (width 0.1) (layer "In2.Cu") (net 249))
  (segment (start 82.462348 120.471816) (end 82.478183 120.487651) (width 0.1) (layer "In2.Cu") (net 249))
  (segment (start 82.7 120.55) (end 82.702507 120.527747) (width 0.1) (layer "In2.Cu") (net 249))
  (segment (start 82.556611 120.726606) (end 82.577747 120.734002) (width 0.1) (layer "In2.Cu") (net 249))
  (segment (start 82.737651 120.471816) (end 82.756611 120.459903) (width 0.1) (layer "In2.Cu") (net 249))
  (segment (start 82.102507 120.79455) (end 82.109903 120.815686) (width 0.1) (layer "In2.Cu") (net 249))
  (segment (start 82.443388 120.459903) (end 82.462348 120.471816) (width 0.1) (layer "In2.Cu") (net 249))
  (segment (start 82.243388 120.862394) (end 82.262348 120.850481) (width 0.1) (layer "In2.Cu") (net 249))
  (segment (start 82.290096 120.815686) (end 82.297492 120.79455) (width 0.1) (layer "In2.Cu") (net 249))
  (segment (start 82.156611 120.862394) (end 82.177747 120.86979) (width 0.1) (layer "In2.Cu") (net 249))
  (segment (start 82.509903 120.679898) (end 82.521816 120.698858) (width 0.1) (layer "In2.Cu") (net 249))
  (segment (start 82.690096 120.679898) (end 82.697492 120.658762) (width 0.1) (layer "In2.Cu") (net 249))
  (segment (start 82.177747 120.86979) (end 82.2 120.872298) (width 0.1) (layer "In2.Cu") (net 249))
  (segment (start 82.662348 120.714693) (end 82.678183 120.698858) (width 0.1) (layer "In2.Cu") (net 249))
  (segment (start 82.478183 120.487651) (end 82.490096 120.506611) (width 0.1) (layer "In2.Cu") (net 249))
  (segment (start 88.45 120.95) (end 95.2 120.95) (width 0.1) (layer "In2.Cu") (net 249))
  (segment (start 82.497492 120.527747) (end 82.5 120.55) (width 0.1) (layer "In2.Cu") (net 249))
  (segment (start 82.222252 120.86979) (end 82.243388 120.862394) (width 0.1) (layer "In2.Cu") (net 249))
  (segment (start 82.309903 120.506611) (end 82.321816 120.487651) (width 0.1) (layer "In2.Cu") (net 249))
  (segment (start 82.6 120.73651) (end 82.622252 120.734002) (width 0.1) (layer "In2.Cu") (net 249))
  (segment (start 82.297492 120.79455) (end 82.3 120.772298) (width 0.1) (layer "In2.Cu") (net 249))
  (segment (start 82.262348 120.850481) (end 82.278183 120.834646) (width 0.1) (layer "In2.Cu") (net 249))
  (segment (start 82.1 120.772298) (end 82.102507 120.79455) (width 0.1) (layer "In2.Cu") (net 249))
  (segment (start 82.622252 120.734002) (end 82.643388 120.726606) (width 0.1) (layer "In2.Cu") (net 249))
  (segment (start 82.109903 120.815686) (end 82.121816 120.834646) (width 0.1) (layer "In2.Cu") (net 249))
  (segment (start 82.678183 120.698858) (end 82.690096 120.679898) (width 0.1) (layer "In2.Cu") (net 249))
  (segment (start 82.5 120.63651) (end 82.502507 120.658762) (width 0.1) (layer "In2.Cu") (net 249))
  (segment (start 82.3 120.55) (end 82.302507 120.527747) (width 0.1) (layer "In2.Cu") (net 249))
  (segment (start 81.5 120.15) (end 81.8 120.45) (width 0.1) (layer "In2.Cu") (net 249))
  (segment (start 82.756611 120.459903) (end 82.777747 120.452507) (width 0.1) (layer "In2.Cu") (net 249))
  (segment (start 82.097492 120.527747) (end 82.1 120.55) (width 0.1) (layer "In2.Cu") (net 249))
  (segment (start 82.537651 120.714693) (end 82.556611 120.726606) (width 0.1) (layer "In2.Cu") (net 249))
  (segment (start 82.078183 120.487651) (end 82.090096 120.506611) (width 0.1) (layer "In2.Cu") (net 249))
  (segment (start 82.1 120.55) (end 82.1 120.772298) (width 0.1) (layer "In2.Cu") (net 249))
  (segment (start 82.121816 120.834646) (end 82.137651 120.850481) (width 0.1) (layer "In2.Cu") (net 249))
  (segment (start 87.95 120.45) (end 88.45 120.95) (width 0.1) (layer "In2.Cu") (net 249))
  (segment (start 82.321816 120.487651) (end 82.337651 120.471816) (width 0.1) (layer "In2.Cu") (net 249))
  (segment (start 79.84 120.545) (end 81.105 120.545) (width 0.1) (layer "B.Cu") (net 249))
  (segment (start 81.105 120.545) (end 81.5 120.15) (width 0.1) (layer "B.Cu") (net 249))
  (segment (start 94.4 120.95) (end 94 121.35) (width 0.15) (layer "F.Cu") (net 250))
  (segment (start 81.8898 121.35) (end 82.6 121.35) (width 0.1) (layer "F.Cu") (net 250))
  (via (at 82.6 121.35) (size 0.5) (drill 0.2) (layers "F.Cu" "B.Cu") (net 250))
  (via (at 94 121.35) (size 0.5) (drill 0.2) (layers "F.Cu" "B.Cu") (net 250))
  (segment (start 83.952507 121.324438) (end 83.959903 121.345574) (width 0.1) (layer "In2.Cu") (net 250))
  (segment (start 83.528183 120.735466) (end 83.540096 120.754426) (width 0.1) (layer "In2.Cu") (net 250))
  (segment (start 83.752507 120.775562) (end 83.759903 120.754426) (width 0.1) (layer "In2.Cu") (net 250))
  (segment (start 83.552507 121.374438) (end 83.559903 121.395574) (width 0.1) (layer "In2.Cu") (net 250))
  (segment (start 83.771816 120.735466) (end 83.787651 120.719631) (width 0.1) (layer "In2.Cu") (net 250))
  (segment (start 93.8 121.15) (end 94 121.35) (width 0.1) (layer "In2.Cu") (net 250))
  (segment (start 83.787651 120.719631) (end 83.806611 120.707718) (width 0.1) (layer "In2.Cu") (net 250))
  (segment (start 83.171816 121.564534) (end 83.187651 121.580369) (width 0.1) (layer "In2.Cu") (net 250))
  (segment (start 83.072252 121.052507) (end 83.093388 121.059903) (width 0.1) (layer "In2.Cu") (net 250))
  (segment (start 83.971816 121.364534) (end 83.987651 121.380369) (width 0.1) (layer "In2.Cu") (net 250))
  (segment (start 83.493388 120.707718) (end 83.512348 120.719631) (width 0.1) (layer "In2.Cu") (net 250))
  (segment (start 83.940096 120.754426) (end 83.947492 120.775562) (width 0.1) (layer "In2.Cu") (net 250))
  (segment (start 83.872252 120.700322) (end 83.893388 120.707718) (width 0.1) (layer "In2.Cu") (net 250))
  (segment (start 84.187651 121.071816) (end 84.206611 121.059903) (width 0.1) (layer "In2.Cu") (net 250))
  (segment (start 83.15 121.502186) (end 83.152507 121.524438) (width 0.1) (layer "In2.Cu") (net 250))
  (segment (start 83.093388 121.059903) (end 83.112348 121.071816) (width 0.1) (layer "In2.Cu") (net 250))
  (segment (start 84.15 121.15) (end 84.152507 121.127747) (width 0.1) (layer "In2.Cu") (net 250))
  (segment (start 84.140096 121.345574) (end 84.147492 121.324438) (width 0.1) (layer "In2.Cu") (net 250))
  (segment (start 83.140096 121.106611) (end 83.147492 121.127747) (width 0.1) (layer "In2.Cu") (net 250))
  (segment (start 84.152507 121.127747) (end 84.159903 121.106611) (width 0.1) (layer "In2.Cu") (net 250))
  (segment (start 83.187651 121.580369) (end 83.206611 121.592282) (width 0.1) (layer "In2.Cu") (net 250))
  (segment (start 84.05 121.402186) (end 84.072252 121.399678) (width 0.1) (layer "In2.Cu") (net 250))
  (segment (start 83.128183 121.087651) (end 83.140096 121.106611) (width 0.1) (layer "In2.Cu") (net 250))
  (segment (start 83.55 120.797814) (end 83.55 121.352186) (width 0.1) (layer "In2.Cu") (net 250))
  (segment (start 83.95 120.797814) (end 83.95 121.302186) (width 0.1) (layer "In2.Cu") (net 250))
  (segment (start 83.740096 121.395574) (end 83.747492 121.374438) (width 0.1) (layer "In2.Cu") (net 250))
  (segment (start 83.35 120.797814) (end 83.352507 120.775562) (width 0.1) (layer "In2.Cu") (net 250))
  (segment (start 83.427747 120.700322) (end 83.45 120.697814) (width 0.1) (layer "In2.Cu") (net 250))
  (segment (start 83.152507 121.524438) (end 83.159903 121.545574) (width 0.1) (layer "In2.Cu") (net 250))
  (segment (start 83.559903 121.395574) (end 83.571816 121.414534) (width 0.1) (layer "In2.Cu") (net 250))
  (segment (start 83.912348 120.719631) (end 83.928183 120.735466) (width 0.1) (layer "In2.Cu") (net 250))
  (segment (start 83.371816 120.735466) (end 83.387651 120.719631) (width 0.1) (layer "In2.Cu") (net 250))
  (segment (start 83.340096 121.545574) (end 83.347492 121.524438) (width 0.1) (layer "In2.Cu") (net 250))
  (segment (start 83.928183 120.735466) (end 83.940096 120.754426) (width 0.1) (layer "In2.Cu") (net 250))
  (segment (start 83.987651 121.380369) (end 84.006611 121.392282) (width 0.1) (layer "In2.Cu") (net 250))
  (segment (start 84.147492 121.324438) (end 84.15 121.302186) (width 0.1) (layer "In2.Cu") (net 250))
  (segment (start 83.627747 121.449678) (end 83.65 121.452186) (width 0.1) (layer "In2.Cu") (net 250))
  (segment (start 83.947492 120.775562) (end 83.95 120.797814) (width 0.1) (layer "In2.Cu") (net 250))
  (segment (start 83.159903 121.545574) (end 83.171816 121.564534) (width 0.1) (layer "In2.Cu") (net 250))
  (segment (start 83.227747 121.599678) (end 83.25 121.602186) (width 0.1) (layer "In2.Cu") (net 250))
  (segment (start 83.406611 120.707718) (end 83.427747 120.700322) (width 0.1) (layer "In2.Cu") (net 250))
  (segment (start 83.512348 120.719631) (end 83.528183 120.735466) (width 0.1) (layer "In2.Cu") (net 250))
  (segment (start 84.227747 121.052507) (end 84.25 121.05) (width 0.1) (layer "In2.Cu") (net 250))
  (segment (start 84.006611 121.392282) (end 84.027747 121.399678) (width 0.1) (layer "In2.Cu") (net 250))
  (segment (start 85.7 121.35) (end 85.95 121.6) (width 0.1) (layer "In2.Cu") (net 250))
  (segment (start 83.693388 121.442282) (end 83.712348 121.430369) (width 0.1) (layer "In2.Cu") (net 250))
  (segment (start 84.159903 121.106611) (end 84.171816 121.087651) (width 0.1) (layer "In2.Cu") (net 250))
  (segment (start 85.95 121.6) (end 87.95 121.6) (width 0.1) (layer "In2.Cu") (net 250))
  (segment (start 84.15 121.302186) (end 84.15 121.15) (width 0.1) (layer "In2.Cu") (net 250))
  (segment (start 88.4 121.15) (end 93.8 121.15) (width 0.1) (layer "In2.Cu") (net 250))
  (segment (start 83.15 121.15) (end 83.15 121.502186) (width 0.1) (layer "In2.Cu") (net 250))
  (segment (start 83.05 121.05) (end 83.072252 121.052507) (width 0.1) (layer "In2.Cu") (net 250))
  (segment (start 83.540096 120.754426) (end 83.547492 120.775562) (width 0.1) (layer "In2.Cu") (net 250))
  (segment (start 84.206611 121.059903) (end 84.227747 121.052507) (width 0.1) (layer "In2.Cu") (net 250))
  (segment (start 83.35 121.502186) (end 83.35 120.797814) (width 0.1) (layer "In2.Cu") (net 250))
  (segment (start 83.806611 120.707718) (end 83.827747 120.700322) (width 0.1) (layer "In2.Cu") (net 250))
  (segment (start 83.547492 120.775562) (end 83.55 120.797814) (width 0.1) (layer "In2.Cu") (net 250))
  (segment (start 82.9 121.05) (end 83.05 121.05) (width 0.1) (layer "In2.Cu") (net 250))
  (segment (start 83.147492 121.127747) (end 83.15 121.15) (width 0.1) (layer "In2.Cu") (net 250))
  (segment (start 84.093388 121.392282) (end 84.112348 121.380369) (width 0.1) (layer "In2.Cu") (net 250))
  (segment (start 83.328183 121.564534) (end 83.340096 121.545574) (width 0.1) (layer "In2.Cu") (net 250))
  (segment (start 83.272252 121.599678) (end 83.293388 121.592282) (width 0.1) (layer "In2.Cu") (net 250))
  (segment (start 83.472252 120.700322) (end 83.493388 120.707718) (width 0.1) (layer "In2.Cu") (net 250))
  (segment (start 83.352507 120.775562) (end 83.359903 120.754426) (width 0.1) (layer "In2.Cu") (net 250))
  (segment (start 83.95 121.302186) (end 83.952507 121.324438) (width 0.1) (layer "In2.Cu") (net 250))
  (segment (start 83.827747 120.700322) (end 83.85 120.697814) (width 0.1) (layer "In2.Cu") (net 250))
  (segment (start 84.072252 121.399678) (end 84.093388 121.392282) (width 0.1) (layer "In2.Cu") (net 250))
  (segment (start 83.347492 121.524438) (end 83.35 121.502186) (width 0.1) (layer "In2.Cu") (net 250))
  (segment (start 84.45 121.05) (end 84.75 121.35) (width 0.1) (layer "In2.Cu") (net 250))
  (segment (start 83.587651 121.430369) (end 83.606611 121.442282) (width 0.1) (layer "In2.Cu") (net 250))
  (segment (start 84.25 121.05) (end 84.45 121.05) (width 0.1) (layer "In2.Cu") (net 250))
  (segment (start 83.112348 121.071816) (end 83.128183 121.087651) (width 0.1) (layer "In2.Cu") (net 250))
  (segment (start 83.959903 121.345574) (end 83.971816 121.364534) (width 0.1) (layer "In2.Cu") (net 250))
  (segment (start 83.728183 121.414534) (end 83.740096 121.395574) (width 0.1) (layer "In2.Cu") (net 250))
  (segment (start 83.75 121.352186) (end 83.75 120.797814) (width 0.1) (layer "In2.Cu") (net 250))
  (segment (start 83.312348 121.580369) (end 83.328183 121.564534) (width 0.1) (layer "In2.Cu") (net 250))
  (segment (start 83.747492 121.374438) (end 83.75 121.352186) (width 0.1) (layer "In2.Cu") (net 250))
  (segment (start 84.112348 121.380369) (end 84.128183 121.364534) (width 0.1) (layer "In2.Cu") (net 250))
  (segment (start 83.606611 121.442282) (end 83.627747 121.449678) (width 0.1) (layer "In2.Cu") (net 250))
  (segment (start 83.387651 120.719631) (end 83.406611 120.707718) (width 0.1) (layer "In2.Cu") (net 250))
  (segment (start 87.95 121.6) (end 88.4 121.15) (width 0.1) (layer "In2.Cu") (net 250))
  (segment (start 83.893388 120.707718) (end 83.912348 120.719631) (width 0.1) (layer "In2.Cu") (net 250))
  (segment (start 83.45 120.697814) (end 83.472252 120.700322) (width 0.1) (layer "In2.Cu") (net 250))
  (segment (start 84.128183 121.364534) (end 84.140096 121.345574) (width 0.1) (layer "In2.Cu") (net 250))
  (segment (start 83.759903 120.754426) (end 83.771816 120.735466) (width 0.1) (layer "In2.Cu") (net 250))
  (segment (start 83.672252 121.449678) (end 83.693388 121.442282) (width 0.1) (layer "In2.Cu") (net 250))
  (segment (start 83.571816 121.414534) (end 83.587651 121.430369) (width 0.1) (layer "In2.Cu") (net 250))
  (segment (start 83.712348 121.430369) (end 83.728183 121.414534) (width 0.1) (layer "In2.Cu") (net 250))
  (segment (start 84.171816 121.087651) (end 84.187651 121.071816) (width 0.1) (layer "In2.Cu") (net 250))
  (segment (start 82.6 121.35) (end 82.9 121.05) (width 0.1) (layer "In2.Cu") (net 250))
  (segment (start 83.206611 121.592282) (end 83.227747 121.599678) (width 0.1) (layer "In2.Cu") (net 250))
  (segment (start 83.55 121.352186) (end 83.552507 121.374438) (width 0.1) (layer "In2.Cu") (net 250))
  (segment (start 83.75 120.797814) (end 83.752507 120.775562) (width 0.1) (layer "In2.Cu") (net 250))
  (segment (start 84.027747 121.399678) (end 84.05 121.402186) (width 0.1) (layer "In2.Cu") (net 250))
  (segment (start 84.75 121.35) (end 85.7 121.35) (width 0.1) (layer "In2.Cu") (net 250))
  (segment (start 83.85 120.697814) (end 83.872252 120.700322) (width 0.1) (layer "In2.Cu") (net 250))
  (segment (start 83.65 121.452186) (end 83.672252 121.449678) (width 0.1) (layer "In2.Cu") (net 250))
  (segment (start 83.293388 121.592282) (end 83.312348 121.580369) (width 0.1) (layer "In2.Cu") (net 250))
  (segment (start 83.25 121.602186) (end 83.272252 121.599678) (width 0.1) (layer "In2.Cu") (net 250))
  (segment (start 83.359903 120.754426) (end 83.371816 120.735466) (width 0.1) (layer "In2.Cu") (net 250))
  (segment (start 81.15 121.35) (end 82.6 121.35) (width 0.1) (layer "B.Cu") (net 250))
  (segment (start 80.845 121.045) (end 79.79 121.045) (width 0.1) (layer "B.Cu") (net 250))
  (segment (start 81.15 121.35) (end 80.845 121.045) (width 0.1) (layer "B.Cu") (net 250))
  (segment (start 84.293416 122.156587) (end 84.306547 122.146116) (width 0.1) (layer "F.Cu") (net 251))
  (segment (start 84.662317 121.773677) (end 84.682492 121.763961) (width 0.1) (layer "F.Cu") (net 251))
  (segment (start 84.31109 121.785354) (end 84.297128 121.767846) (width 0.1) (layer "F.Cu") (net 251))
  (segment (start 84.55866 122.043428) (end 84.551374 122.028295) (width 0.1) (layer "F.Cu") (net 251))
  (segment (start 84.551374 122.028295) (end 84.540902 122.015166) (width 0.1) (layer "F.Cu") (net 251))
  (segment (start 84.306547 122.146116) (end 84.321678 122.13883) (width 0.1) (layer "F.Cu") (net 251))
  (segment (start 84.321678 122.13883) (end 84.338051 122.135093) (width 0.1) (layer "F.Cu") (net 251))
  (segment (start 84.31109 121.643933) (end 84.328598 121.629972) (width 0.1) (layer "F.Cu") (net 251))
  (segment (start 84.412613 122.167058) (end 84.427744 122.174345) (width 0.1) (layer "F.Cu") (net 251))
  (segment (start 84.640485 121.77866) (end 84.662317 121.773677) (width 0.1) (layer "F.Cu") (net 251))
  (segment (start 84.328598 121.629972) (end 84.348773 121.620256) (width 0.1) (layer "F.Cu") (net 251))
  (segment (start 84.562398 122.076595) (end 84.562397 122.059801) (width 0.1) (layer "F.Cu") (net 251))
  (segment (start 84.354847 122.135092) (end 84.37122 122.138829) (width 0.1) (layer "F.Cu") (net 251))
  (segment (start 84.596261 121.773677) (end 84.618092 121.77866) (width 0.1) (layer "F.Cu") (net 251))
  (segment (start 84.7 121.75) (end 85.1 121.35) (width 0.1) (layer "F.Cu") (net 251))
  (segment (start 95.2 125.75) (end 94.8 125.35) (width 0.1) (layer "F.Cu") (net 251))
  (segment (start 84.386351 122.146117) (end 84.412613 122.167058) (width 0.1) (layer "F.Cu") (net 251))
  (segment (start 84.282429 121.703447) (end 84.287412 121.681615) (width 0.1) (layer "F.Cu") (net 251))
  (segment (start 84.435004 121.629972) (end 84.452511 121.643933) (width 0.1) (layer "F.Cu") (net 251))
  (segment (start 84.576086 121.763961) (end 84.596261 121.773677) (width 0.1) (layer "F.Cu") (net 251))
  (segment (start 84.505548 122.156587) (end 84.540902 122.121232) (width 0.1) (layer "F.Cu") (net 251))
  (segment (start 84.370604 121.615273) (end 84.392997 121.615273) (width 0.1) (layer "F.Cu") (net 251))
  (segment (start 84.392997 121.615273) (end 84.414829 121.620256) (width 0.1) (layer "F.Cu") (net 251))
  (segment (start 84.551373 122.108101) (end 84.558661 122.092968) (width 0.1) (layer "F.Cu") (net 251))
  (segment (start 84.618092 121.77866) (end 84.640485 121.77866) (width 0.1) (layer "F.Cu") (net 251))
  (segment (start 84.37122 122.138829) (end 84.386351 122.146117) (width 0.1) (layer "F.Cu") (net 251))
  (segment (start 84.452511 121.643933) (end 84.558578 121.75) (width 0.1) (layer "F.Cu") (net 251))
  (segment (start 84.414829 121.620256) (end 84.435004 121.629972) (width 0.1) (layer "F.Cu") (net 251))
  (segment (start 84.282429 121.72584) (end 84.282429 121.703447) (width 0.1) (layer "F.Cu") (net 251))
  (segment (start 84.492417 122.167059) (end 84.505548 122.156587) (width 0.1) (layer "F.Cu") (net 251))
  (segment (start 84.460911 122.178083) (end 84.477286 122.174345) (width 0.1) (layer "F.Cu") (net 251))
  (segment (start 84.540902 122.121232) (end 84.551373 122.108101) (width 0.1) (layer "F.Cu") (net 251))
  (segment (start 84.348773 121.620256) (end 84.370604 121.615273) (width 0.1) (layer "F.Cu") (net 251))
  (segment (start 84.477286 122.174345) (end 84.492417 122.167059) (width 0.1) (layer "F.Cu") (net 251))
  (segment (start 84.287412 121.747671) (end 84.282429 121.72584) (width 0.1) (layer "F.Cu") (net 251))
  (segment (start 84.540902 122.015166) (end 84.31109 121.785354) (width 0.1) (layer "F.Cu") (net 251))
  (segment (start 84.427744 122.174345) (end 84.444117 122.178083) (width 0.1) (layer "F.Cu") (net 251))
  (segment (start 84.297128 121.66144) (end 84.31109 121.643933) (width 0.1) (layer "F.Cu") (net 251))
  (segment (start 84.297128 121.767846) (end 84.287412 121.747671) (width 0.1) (layer "F.Cu") (net 251))
  (segment (start 84.562397 122.059801) (end 84.55866 122.043428) (width 0.1) (layer "F.Cu") (net 251))
  (segment (start 84.338051 122.135093) (end 84.354847 122.135092) (width 0.1) (layer "F.Cu") (net 251))
  (segment (start 84 122.55) (end 84 122.450003) (width 0.1) (layer "F.Cu") (net 251))
  (segment (start 84 122.450003) (end 84.293416 122.156587) (width 0.1) (layer "F.Cu") (net 251))
  (segment (start 84.558578 121.75) (end 84.576086 121.763961) (width 0.1) (layer "F.Cu") (net 251))
  (segment (start 84.682492 121.763961) (end 84.7 121.75) (width 0.1) (layer "F.Cu") (net 251))
  (segment (start 84.558661 122.092968) (end 84.562398 122.076595) (width 0.1) (layer "F.Cu") (net 251))
  (segment (start 84.444117 122.178083) (end 84.460911 122.178083) (width 0.1) (layer "F.Cu") (net 251))
  (segment (start 84.287412 121.681615) (end 84.297128 121.66144) (width 0.1) (layer "F.Cu") (net 251))
  (via (at 87.5 124.95) (size 0.5) (drill 0.2) (layers "F.Cu" "B.Cu") (net 251))
  (via blind (at 94.8 125.35) (size 0.5) (drill 0.2) (layers "F.Cu" "In2.Cu") (net 251))
  (via (at 84 122.55) (size 0.5) (drill 0.2) (layers "F.Cu" "B.Cu") (net 251))
  (segment (start 94.8 125.05) (end 94.8 125.35) (width 0.1) (layer "In2.Cu") (net 251))
  (segment (start 87.5 124.95) (end 88.3 124.95) (width 0.1) (layer "In2.Cu") (net 251))
  (segment (start 88.8 124.45) (end 94.2 124.45) (width 0.1) (layer "In2.Cu") (net 251))
  (segment (start 94.2 124.45) (end 94.8 125.05) (width 0.1) (layer "In2.Cu") (net 251))
  (segment (start 88.3 124.95) (end 88.8 124.45) (width 0.1) (layer "In2.Cu") (net 251))
  (segment (start 84.55 124.65) (end 84.572252 124.647493) (width 0.1) (layer "B.Cu") (net 251))
  (segment (start 84.593388 124.640097) (end 84.612348 124.628184) (width 0.1) (layer "B.Cu") (net 251))
  (segment (start 84 122.55) (end 84 124.15) (width 0.1) (layer "B.Cu") (net 251))
  (segment (start 84.859903 124.593389) (end 84.871816 124.612349) (width 0.1) (layer "B.Cu") (net 251))
  (segment (start 84.659903 124.460723) (end 84.671816 124.441763) (width 0.1) (layer "B.Cu") (net 251))
  (segment (start 84.927747 124.647493) (end 84.95 124.65) (width 0.1) (layer "B.Cu") (net 251))
  (segment (start 84.840096 124.460723) (end 84.847492 124.481859) (width 0.1) (layer "B.Cu") (net 251))
  (segment (start 84.871816 124.612349) (end 84.887651 124.628184) (width 0.1) (layer "B.Cu") (net 251))
  (segment (start 87.2 124.65) (end 87.5 124.95) (width 0.1) (layer "B.Cu") (net 251))
  (segment (start 84.706611 124.414015) (end 84.727747 124.406619) (width 0.1) (layer "B.Cu") (net 251))
  (segment (start 84.687651 124.425928) (end 84.706611 124.414015) (width 0.1) (layer "B.Cu") (net 251))
  (segment (start 84.727747 124.406619) (end 84.75 124.404111) (width 0.1) (layer "B.Cu") (net 251))
  (segment (start 84.812348 124.425928) (end 84.828183 124.441763) (width 0.1) (layer "B.Cu") (net 251))
  (segment (start 84.95 124.65) (end 87.2 124.65) (width 0.1) (layer "B.Cu") (net 251))
  (segment (start 84.5 124.65) (end 84.55 124.65) (width 0.1) (layer "B.Cu") (net 251))
  (segment (start 84.612348 124.628184) (end 84.628183 124.612349) (width 0.1) (layer "B.Cu") (net 251))
  (segment (start 84.828183 124.441763) (end 84.840096 124.460723) (width 0.1) (layer "B.Cu") (net 251))
  (segment (start 84.906611 124.640097) (end 84.927747 124.647493) (width 0.1) (layer "B.Cu") (net 251))
  (segment (start 84.572252 124.647493) (end 84.593388 124.640097) (width 0.1) (layer "B.Cu") (net 251))
  (segment (start 84.628183 124.612349) (end 84.640096 124.593389) (width 0.1) (layer "B.Cu") (net 251))
  (segment (start 84.671816 124.441763) (end 84.687651 124.425928) (width 0.1) (layer "B.Cu") (net 251))
  (segment (start 84.85 124.55) (end 84.852507 124.572253) (width 0.1) (layer "B.Cu") (net 251))
  (segment (start 84.772252 124.406619) (end 84.793388 124.414015) (width 0.1) (layer "B.Cu") (net 251))
  (segment (start 84.887651 124.628184) (end 84.906611 124.640097) (width 0.1) (layer "B.Cu") (net 251))
  (segment (start 84.852507 124.572253) (end 84.859903 124.593389) (width 0.1) (layer "B.Cu") (net 251))
  (segment (start 84.65 124.504111) (end 84.652507 124.481859) (width 0.1) (layer "B.Cu") (net 251))
  (segment (start 84.647492 124.572253) (end 84.65 124.55) (width 0.1) (layer "B.Cu") (net 251))
  (segment (start 84.85 124.504111) (end 84.85 124.55) (width 0.1) (layer "B.Cu") (net 251))
  (segment (start 84.65 124.55) (end 84.65 124.504111) (width 0.1) (layer "B.Cu") (net 251))
  (segment (start 84.652507 124.481859) (end 84.659903 124.460723) (width 0.1) (layer "B.Cu") (net 251))
  (segment (start 84.75 124.404111) (end 84.772252 124.406619) (width 0.1) (layer "B.Cu") (net 251))
  (segment (start 84.847492 124.481859) (end 84.85 124.504111) (width 0.1) (layer "B.Cu") (net 251))
  (segment (start 84.793388 124.414015) (end 84.812348 124.425928) (width 0.1) (layer "B.Cu") (net 251))
  (segment (start 84.640096 124.593389) (end 84.647492 124.572253) (width 0.1) (layer "B.Cu") (net 251))
  (segment (start 84 124.15) (end 84.5 124.65) (width 0.1) (layer "B.Cu") (net 251))
  (segment (start 84.83604 120.567507) (end 84.826323 120.587683) (width 0.1) (layer "F.Cu") (net 252))
  (segment (start 84.520666 120.672696) (end 84.500512 120.672696) (width 0.1) (layer "F.Cu") (net 252))
  (segment (start 84.411497 120.805997) (end 84.420242 120.824155) (width 0.1) (layer "F.Cu") (net 252))
  (segment (start 85.1 120.55) (end 84.85 120.55) (width 0.1) (layer "F.Cu") (net 252))
  (segment (start 84.682762 121.103869) (end 84.687745 121.1257) (width 0.1) (layer "F.Cu") (net 252))
  (segment (start 84.16253 121.13851) (end 84.171274 121.156668) (width 0.1) (layer "F.Cu") (net 252))
  (segment (start 84.21767 120.955538) (end 84.198022 120.960023) (width 0.1) (layer "F.Cu") (net 252))
  (segment (start 84.555346 121.231285) (end 84.53517 121.22157) (width 0.1) (layer "F.Cu") (net 252))
  (segment (start 84.673045 121.083695) (end 84.682762 121.103869) (width 0.1) (layer "F.Cu") (net 252))
  (segment (start 84.432807 120.839912) (end 84.659083 121.066187) (width 0.1) (layer "F.Cu") (net 252))
  (segment (start 84.599569 121.236269) (end 84.577177 121.236268) (width 0.1) (layer "F.Cu") (net 252))
  (segment (start 84.432807 120.712633) (end 84.420242 120.728389) (width 0.1) (layer "F.Cu") (net 252))
  (segment (start 84.540314 120.677181) (end 84.520666 120.672696) (width 0.1) (layer "F.Cu") (net 252))
  (segment (start 84.82134 120.631908) (end 84.826323 120.653739) (width 0.1) (layer "F.Cu") (net 252))
  (segment (start 84.941924 120.783346) (end 84.955886 120.800854) (width 0.1) (layer "F.Cu") (net 252))
  (segment (start 84.659084 121.207607) (end 84.641576 121.22157) (width 0.1) (layer "F.Cu") (net 252))
  (segment (start 84.955886 120.800854) (end 84.965603 120.821028) (width 0.1) (layer "F.Cu") (net 252))
  (segment (start 84.462706 120.685925) (end 84.44695 120.698491) (width 0.1) (layer "F.Cu") (net 252))
  (segment (start 84.818012 120.938729) (end 84.800504 120.924767) (width 0.1) (layer "F.Cu") (net 252))
  (segment (start 84.673045 121.190101) (end 84.659084 121.207607) (width 0.1) (layer "F.Cu") (net 252))
  (segment (start 84.882411 120.953428) (end 84.860017 120.953429) (width 0.1) (layer "F.Cu") (net 252))
  (segment (start 83.9 121.5) (end 83.9 121.85) (width 0.1) (layer "F.Cu") (net 252))
  (segment (start 84.621402 121.231285) (end 84.599569 121.236269) (width 0.1) (layer "F.Cu") (net 252))
  (segment (start 84.179864 120.968767) (end 84.164108 120.981333) (width 0.1) (layer "F.Cu") (net 252))
  (segment (start 84.641576 121.22157) (end 84.621402 121.231285) (width 0.1) (layer "F.Cu") (net 252))
  (segment (start 95.2 122.55) (end 94.8 122.15) (width 0.15) (layer "F.Cu") (net 252))
  (segment (start 84.420242 120.728389) (end 84.411497 120.746547) (width 0.1) (layer "F.Cu") (net 252))
  (segment (start 84.480864 120.677181) (end 84.462706 120.685925) (width 0.1) (layer "F.Cu") (net 252))
  (segment (start 84.687744 121.148094) (end 84.682762 121.169925) (width 0.1) (layer "F.Cu") (net 252))
  (segment (start 84.149965 120.995475) (end 84.1374 121.011231) (width 0.1) (layer "F.Cu") (net 252))
  (segment (start 84.85 120.691422) (end 84.941924 120.783346) (width 0.1) (layer "F.Cu") (net 252))
  (segment (start 84.659083 121.066187) (end 84.673045 121.083695) (width 0.1) (layer "F.Cu") (net 252))
  (segment (start 84.44695 120.698491) (end 84.432807 120.712633) (width 0.1) (layer "F.Cu") (net 252))
  (segment (start 84.198022 120.960023) (end 84.179864 120.968767) (width 0.1) (layer "F.Cu") (net 252))
  (segment (start 84.171274 121.156668) (end 84.175759 121.176316) (width 0.1) (layer "F.Cu") (net 252))
  (segment (start 84.407013 120.766195) (end 84.407013 120.786349) (width 0.1) (layer "F.Cu") (net 252))
  (segment (start 84.500512 120.672696) (end 84.480864 120.677181) (width 0.1) (layer "F.Cu") (net 252))
  (segment (start 84.682762 121.169925) (end 84.673045 121.190101) (width 0.1) (layer "F.Cu") (net 252))
  (segment (start 84.970585 120.842861) (end 84.970586 120.865253) (width 0.1) (layer "F.Cu") (net 252))
  (segment (start 84.965603 120.821028) (end 84.970585 120.842861) (width 0.1) (layer "F.Cu") (net 252))
  (segment (start 84.941924 120.924768) (end 84.924418 120.938729) (width 0.1) (layer "F.Cu") (net 252))
  (segment (start 84.558472 120.685925) (end 84.540314 120.677181) (width 0.1) (layer "F.Cu") (net 252))
  (segment (start 84.420242 120.824155) (end 84.432807 120.839912) (width 0.1) (layer "F.Cu") (net 252))
  (segment (start 84.128655 121.029389) (end 84.124171 121.049037) (width 0.1) (layer "F.Cu") (net 252))
  (segment (start 84.821341 120.609514) (end 84.82134 120.631908) (width 0.1) (layer "F.Cu") (net 252))
  (segment (start 84.128655 121.088839) (end 84.1374 121.106997) (width 0.1) (layer "F.Cu") (net 252))
  (segment (start 84.826323 120.587683) (end 84.821341 120.609514) (width 0.1) (layer "F.Cu") (net 252))
  (segment (start 84.687745 121.1257) (end 84.687744 121.148094) (width 0.1) (layer "F.Cu") (net 252))
  (segment (start 84.149965 121.250033) (end 83.9 121.5) (width 0.1) (layer "F.Cu") (net 252))
  (segment (start 84.291387 120.981333) (end 84.27563 120.968767) (width 0.1) (layer "F.Cu") (net 252))
  (segment (start 84.826323 120.653739) (end 84.83604 120.673913) (width 0.1) (layer "F.Cu") (net 252))
  (segment (start 84.904242 120.948446) (end 84.882411 120.953428) (width 0.1) (layer "F.Cu") (net 252))
  (segment (start 84.27563 120.968767) (end 84.257472 120.960023) (width 0.1) (layer "F.Cu") (net 252))
  (segment (start 84.838186 120.948446) (end 84.818012 120.938729) (width 0.1) (layer "F.Cu") (net 252))
  (segment (start 84.85 120.55) (end 84.83604 120.567507) (width 0.1) (layer "F.Cu") (net 252))
  (segment (start 84.860017 120.953429) (end 84.838186 120.948446) (width 0.1) (layer "F.Cu") (net 252))
  (segment (start 84.257472 120.960023) (end 84.237824 120.955538) (width 0.1) (layer "F.Cu") (net 252))
  (segment (start 84.164108 120.981333) (end 84.149965 120.995475) (width 0.1) (layer "F.Cu") (net 252))
  (segment (start 84.407013 120.786349) (end 84.411497 120.805997) (width 0.1) (layer "F.Cu") (net 252))
  (segment (start 84.965603 120.887084) (end 84.955886 120.90726) (width 0.1) (layer "F.Cu") (net 252))
  (segment (start 84.16253 121.234276) (end 84.149965 121.250033) (width 0.1) (layer "F.Cu") (net 252))
  (segment (start 84.574229 120.698491) (end 84.558472 120.685925) (width 0.1) (layer "F.Cu") (net 252))
  (segment (start 84.175759 121.19647) (end 84.171274 121.216118) (width 0.1) (layer "F.Cu") (net 252))
  (segment (start 84.53517 121.22157) (end 84.517662 121.207608) (width 0.1) (layer "F.Cu") (net 252))
  (segment (start 84.124171 121.049037) (end 84.124171 121.069191) (width 0.1) (layer "F.Cu") (net 252))
  (segment (start 84.955886 120.90726) (end 84.941924 120.924768) (width 0.1) (layer "F.Cu") (net 252))
  (segment (start 84.1374 121.011231) (end 84.128655 121.029389) (width 0.1) (layer "F.Cu") (net 252))
  (segment (start 84.800504 120.924767) (end 84.574229 120.698491) (width 0.1) (layer "F.Cu") (net 252))
  (segment (start 84.411497 120.746547) (end 84.407013 120.766195) (width 0.1) (layer "F.Cu") (net 252))
  (segment (start 84.924418 120.938729) (end 84.904242 120.948446) (width 0.1) (layer "F.Cu") (net 252))
  (segment (start 84.517662 121.207608) (end 84.291387 120.981333) (width 0.1) (layer "F.Cu") (net 252))
  (segment (start 84.237824 120.955538) (end 84.21767 120.955538) (width 0.1) (layer "F.Cu") (net 252))
  (segment (start 84.124171 121.069191) (end 84.128655 121.088839) (width 0.1) (layer "F.Cu") (net 252))
  (segment (start 84.970586 120.865253) (end 84.965603 120.887084) (width 0.1) (layer "F.Cu") (net 252))
  (segment (start 84.175759 121.176316) (end 84.175759 121.19647) (width 0.1) (layer "F.Cu") (net 252))
  (segment (start 84.83604 120.673913) (end 84.85 120.691422) (width 0.1) (layer "F.Cu") (net 252))
  (segment (start 84.171274 121.216118) (end 84.16253 121.234276) (width 0.1) (layer "F.Cu") (net 252))
  (segment (start 84.1374 121.106997) (end 84.16253 121.13851) (width 0.1) (layer "F.Cu") (net 252))
  (segment (start 84.577177 121.236268) (end 84.555346 121.231285) (width 0.1) (layer "F.Cu") (net 252))
  (via (at 83.9 121.85) (size 0.5) (drill 0.2) (layers "F.Cu" "B.Cu") (net 252))
  (via (at 94.8 122.15) (size 0.5) (drill 0.2) (layers "F.Cu" "B.Cu") (net 252))
  (segment (start 84.412348 122.128184) (end 84.428183 122.112349) (width 0.1) (layer "In2.Cu") (net 252))
  (segment (start 94.4 121.75) (end 94.8 122.15) (width 0.1) (layer "In2.Cu") (net 252))
  (segment (start 93.75 121.75) (end 94.4 121.75) (width 0.1) (layer "In2.Cu") (net 252))
  (segment (start 84.506611 121.586044) (end 84.527747 121.578648) (width 0.1) (layer "In2.Cu") (net 252))
  (segment (start 84.65 122.05) (end 84.652507 122.072253) (width 0.1) (layer "In2.Cu") (net 252))
  (segment (start 84.393388 122.140097) (end 84.412348 122.128184) (width 0.1) (layer "In2.Cu") (net 252))
  (segment (start 84.487651 121.597957) (end 84.506611 121.586044) (width 0.1) (layer "In2.Cu") (net 252))
  (segment (start 84.612348 121.597957) (end 84.628183 121.613792) (width 0.1) (layer "In2.Cu") (net 252))
  (segment (start 84.659903 122.093389) (end 84.671816 122.112349) (width 0.1) (layer "In2.Cu") (net 252))
  (segment (start 84.628183 121.613792) (end 84.640096 121.632752) (width 0.1) (layer "In2.Cu") (net 252))
  (segment (start 84.727747 122.147493) (end 84.75 122.15) (width 0.1) (layer "In2.Cu") (net 252))
  (segment (start 84.671816 122.112349) (end 84.687651 122.128184) (width 0.1) (layer "In2.Cu") (net 252))
  (segment (start 84.640096 121.632752) (end 84.647492 121.653888) (width 0.1) (layer "In2.Cu") (net 252))
  (segment (start 84.45 122.05) (end 84.45 121.67614) (width 0.1) (layer "In2.Cu") (net 252))
  (segment (start 84.55 121.57614) (end 84.572252 121.578648) (width 0.1) (layer "In2.Cu") (net 252))
  (segment (start 93.35 121.35) (end 93.75 121.75) (width 0.1) (layer "In2.Cu") (net 252))
  (segment (start 88.05 121.85) (end 88.55 121.35) (width 0.1) (layer "In2.Cu") (net 252))
  (segment (start 84.440096 122.093389) (end 84.447492 122.072253) (width 0.1) (layer "In2.Cu") (net 252))
  (segment (start 84.372252 122.147493) (end 84.393388 122.140097) (width 0.1) (layer "In2.Cu") (net 252))
  (segment (start 84.45 121.67614) (end 84.452507 121.653888) (width 0.1) (layer "In2.Cu") (net 252))
  (segment (start 86.05 121.85) (end 88.05 121.85) (width 0.1) (layer "In2.Cu") (net 252))
  (segment (start 84.428183 122.112349) (end 84.440096 122.093389) (width 0.1) (layer "In2.Cu") (net 252))
  (segment (start 84.452507 121.653888) (end 84.459903 121.632752) (width 0.1) (layer "In2.Cu") (net 252))
  (segment (start 88.55 121.35) (end 93.35 121.35) (width 0.1) (layer "In2.Cu") (net 252))
  (segment (start 85.75 122.15) (end 86.05 121.85) (width 0.1) (layer "In2.Cu") (net 252))
  (segment (start 84.652507 122.072253) (end 84.659903 122.093389) (width 0.1) (layer "In2.Cu") (net 252))
  (segment (start 84.2 122.15) (end 84.35 122.15) (width 0.1) (layer "In2.Cu") (net 252))
  (segment (start 84.471816 121.613792) (end 84.487651 121.597957) (width 0.1) (layer "In2.Cu") (net 252))
  (segment (start 84.527747 121.578648) (end 84.55 121.57614) (width 0.1) (layer "In2.Cu") (net 252))
  (segment (start 84.75 122.15) (end 85.75 122.15) (width 0.1) (layer "In2.Cu") (net 252))
  (segment (start 84.447492 122.072253) (end 84.45 122.05) (width 0.1) (layer "In2.Cu") (net 252))
  (segment (start 84.65 121.67614) (end 84.65 122.05) (width 0.1) (layer "In2.Cu") (net 252))
  (segment (start 84.687651 122.128184) (end 84.706611 122.140097) (width 0.1) (layer "In2.Cu") (net 252))
  (segment (start 84.647492 121.653888) (end 84.65 121.67614) (width 0.1) (layer "In2.Cu") (net 252))
  (segment (start 84.706611 122.140097) (end 84.727747 122.147493) (width 0.1) (layer "In2.Cu") (net 252))
  (segment (start 83.9 121.85) (end 84.2 122.15) (width 0.1) (layer "In2.Cu") (net 252))
  (segment (start 84.35 122.15) (end 84.372252 122.147493) (width 0.1) (layer "In2.Cu") (net 252))
  (segment (start 84.593388 121.586044) (end 84.612348 121.597957) (width 0.1) (layer "In2.Cu") (net 252))
  (segment (start 84.459903 121.632752) (end 84.471816 121.613792) (width 0.1) (layer "In2.Cu") (net 252))
  (segment (start 84.572252 121.578648) (end 84.593388 121.586044) (width 0.1) (layer "In2.Cu") (net 252))
  (segment (start 83.6 123.1) (end 83.6 122.15) (width 0.1) (layer "B.Cu") (net 252))
  (segment (start 83.6 122.15) (end 83.9 121.85) (width 0.1) (layer "B.Cu") (net 252))
  (segment (start 83.49 123.21) (end 83.6 123.1) (width 0.1) (layer "B.Cu") (net 252))
  (segment (start 83.49 123.695) (end 83.49 123.21) (width 0.1) (layer "B.Cu") (net 252))
  (segment (start 94.395 127.335) (end 93.995 127.735) (width 0.1) (layer "F.Cu") (net 253))
  (segment (start 85.9 118.95) (end 85.5 119.35) (width 0.1) (layer "F.Cu") (net 253))
  (via (at 93.995 127.735) (size 0.5) (drill 0.2) (layers "F.Cu" "B.Cu") (net 253))
  (via (at 85.5 119.35) (size 0.5) (drill 0.2) (layers "F.Cu" "B.Cu") (net 253))
  (segment (start 87.883251 121.031059) (end 87.903426 121.040775) (width 0.1) (layer "In5.Cu") (net 253))
  (segment (start 88.533776 121.087023) (end 88.556169 121.087023) (width 0.1) (layer "In5.Cu") (net 253))
  (segment (start 87.7 120.2) (end 88.05 120.55) (width 0.1) (layer "In5.Cu") (net 253))
  (segment (start 87.865744 120.875676) (end 87.851782 120.893184) (width 0.1) (layer "In5.Cu") (net 253))
  (segment (start 87.851782 120.893184) (end 87.842066 120.913359) (width 0.1) (layer "In5.Cu") (net 253))
  (segment (start 88.272499 121.313901) (end 88.290007 121.29994) (width 0.1) (layer "In5.Cu") (net 253))
  (segment (start 87.947651 121.045758) (end 87.969482 121.040775) (width 0.1) (layer "In5.Cu") (net 253))
  (segment (start 88.474262 121.115684) (end 88.49177 121.101722) (width 0.1) (layer "In5.Cu") (net 253))
  (segment (start 87.925258 121.045758) (end 87.947651 121.045758) (width 0.1) (layer "In5.Cu") (net 253))
  (segment (start 88.119925 121.218032) (end 88.119925 121.240425) (width 0.1) (layer "In5.Cu") (net 253))
  (segment (start 87.851782 120.99959) (end 87.865744 121.017098) (width 0.1) (layer "In5.Cu") (net 253))
  (segment (start 93.95 124.5) (end 94.4 124.95) (width 0.1) (layer "In5.Cu") (net 253))
  (segment (start 88.49177 121.101722) (end 88.511945 121.092006) (width 0.1) (layer "In5.Cu") (net 253))
  (segment (start 88.124908 121.196201) (end 88.119925 121.218032) (width 0.1) (layer "In5.Cu") (net 253))
  (segment (start 88.07866 120.631907) (end 88.073677 120.653738) (width 0.1) (layer "In5.Cu") (net 253))
  (segment (start 88.511945 121.092006) (end 88.533776 121.087023) (width 0.1) (layer "In5.Cu") (net 253))
  (segment (start 94.4 124.95) (end 94.4 127.33) (width 0.1) (layer "In5.Cu") (net 253))
  (segment (start 88.273327 120.804181) (end 88.295159 120.809164) (width 0.1) (layer "In5.Cu") (net 253))
  (segment (start 87.969482 121.040775) (end 87.989657 121.031059) (width 0.1) (layer "In5.Cu") (net 253))
  (segment (start 88.007165 121.017098) (end 88.19142 120.832842) (width 0.1) (layer "In5.Cu") (net 253))
  (segment (start 88.332842 120.832842) (end 88.346803 120.850349) (width 0.1) (layer "In5.Cu") (net 253))
  (segment (start 88.250934 120.804181) (end 88.273327 120.804181) (width 0.1) (layer "In5.Cu") (net 253))
  (segment (start 88.615684 121.115684) (end 92 124.5) (width 0.1) (layer "In5.Cu") (net 253))
  (segment (start 88.073677 120.653738) (end 88.063961 120.673913) (width 0.1) (layer "In5.Cu") (net 253))
  (segment (start 88.346803 120.956755) (end 88.332842 120.974263) (width 0.1) (layer "In5.Cu") (net 253))
  (segment (start 87.837083 120.93519) (end 87.837083 120.957583) (width 0.1) (layer "In5.Cu") (net 253))
  (segment (start 88.252324 121.323617) (end 88.272499 121.313901) (width 0.1) (layer "In5.Cu") (net 253))
  (segment (start 88.598176 121.101722) (end 88.615684 121.115684) (width 0.1) (layer "In5.Cu") (net 253))
  (segment (start 88.361502 120.914749) (end 88.356519 120.93658) (width 0.1) (layer "In5.Cu") (net 253))
  (segment (start 88.134624 121.282432) (end 88.148586 121.29994) (width 0.1) (layer "In5.Cu") (net 253))
  (segment (start 88.290007 121.29994) (end 88.474262 121.115684) (width 0.1) (layer "In5.Cu") (net 253))
  (segment (start 88.208928 120.81888) (end 88.229103 120.809164) (width 0.1) (layer "In5.Cu") (net 253))
  (segment (start 88.063961 120.567507) (end 88.073677 120.587682) (width 0.1) (layer "In5.Cu") (net 253))
  (segment (start 88.578001 121.092006) (end 88.598176 121.101722) (width 0.1) (layer "In5.Cu") (net 253))
  (segment (start 88.166093 121.313901) (end 88.186268 121.323617) (width 0.1) (layer "In5.Cu") (net 253))
  (segment (start 88.556169 121.087023) (end 88.578001 121.092006) (width 0.1) (layer "In5.Cu") (net 253))
  (segment (start 88.315334 120.81888) (end 88.332842 120.832842) (width 0.1) (layer "In5.Cu") (net 253))
  (segment (start 88.361502 120.892356) (end 88.361502 120.914749) (width 0.1) (layer "In5.Cu") (net 253))
  (segment (start 87.865744 121.017098) (end 87.883251 121.031059) (width 0.1) (layer "In5.Cu") (net 253))
  (segment (start 88.356519 120.870524) (end 88.361502 120.892356) (width 0.1) (layer "In5.Cu") (net 253))
  (segment (start 88.119925 121.240425) (end 88.124908 121.262257) (width 0.1) (layer "In5.Cu") (net 253))
  (segment (start 88.346803 120.850349) (end 88.356519 120.870524) (width 0.1) (layer "In5.Cu") (net 253))
  (segment (start 92 124.5) (end 93.95 124.5) (width 0.1) (layer "In5.Cu") (net 253))
  (segment (start 88.07866 120.609514) (end 88.07866 120.631907) (width 0.1) (layer "In5.Cu") (net 253))
  (segment (start 88.332842 120.974263) (end 88.148586 121.158518) (width 0.1) (layer "In5.Cu") (net 253))
  (segment (start 94.4 127.33) (end 93.995 127.735) (width 0.1) (layer "In5.Cu") (net 253))
  (segment (start 88.186268 121.323617) (end 88.2081 121.3286) (width 0.1) (layer "In5.Cu") (net 253))
  (segment (start 86.35 120.2) (end 87.7 120.2) (width 0.1) (layer "In5.Cu") (net 253))
  (segment (start 88.19142 120.832842) (end 88.208928 120.81888) (width 0.1) (layer "In5.Cu") (net 253))
  (segment (start 88.134624 121.176026) (end 88.124908 121.196201) (width 0.1) (layer "In5.Cu") (net 253))
  (segment (start 88.124908 121.262257) (end 88.134624 121.282432) (width 0.1) (layer "In5.Cu") (net 253))
  (segment (start 85.5 119.35) (end 86.35 120.2) (width 0.1) (layer "In5.Cu") (net 253))
  (segment (start 88.2081 121.3286) (end 88.230493 121.3286) (width 0.1) (layer "In5.Cu") (net 253))
  (segment (start 88.063961 120.673913) (end 88.05 120.691421) (width 0.1) (layer "In5.Cu") (net 253))
  (segment (start 88.05 120.55) (end 88.063961 120.567507) (width 0.1) (layer "In5.Cu") (net 253))
  (segment (start 88.295159 120.809164) (end 88.315334 120.81888) (width 0.1) (layer "In5.Cu") (net 253))
  (segment (start 87.903426 121.040775) (end 87.925258 121.045758) (width 0.1) (layer "In5.Cu") (net 253))
  (segment (start 87.842066 120.979415) (end 87.851782 120.99959) (width 0.1) (layer "In5.Cu") (net 253))
  (segment (start 88.356519 120.93658) (end 88.346803 120.956755) (width 0.1) (layer "In5.Cu") (net 253))
  (segment (start 87.989657 121.031059) (end 88.007165 121.017098) (width 0.1) (layer "In5.Cu") (net 253))
  (segment (start 88.073677 120.587682) (end 88.07866 120.609514) (width 0.1) (layer "In5.Cu") (net 253))
  (segment (start 87.842066 120.913359) (end 87.837083 120.93519) (width 0.1) (layer "In5.Cu") (net 253))
  (segment (start 88.229103 120.809164) (end 88.250934 120.804181) (width 0.1) (layer "In5.Cu") (net 253))
  (segment (start 88.148586 121.29994) (end 88.166093 121.313901) (width 0.1) (layer "In5.Cu") (net 253))
  (segment (start 88.05 120.691421) (end 87.865744 120.875676) (width 0.1) (layer "In5.Cu") (net 253))
  (segment (start 88.148586 121.158518) (end 88.134624 121.176026) (width 0.1) (layer "In5.Cu") (net 253))
  (segment (start 88.230493 121.3286) (end 88.252324 121.323617) (width 0.1) (layer "In5.Cu") (net 253))
  (segment (start 87.837083 120.957583) (end 87.842066 120.979415) (width 0.1) (layer "In5.Cu") (net 253))
  (segment (start 84.99 118.84) (end 85.5 119.35) (width 0.1) (layer "B.Cu") (net 253))
  (segment (start 84.99 118.84) (end 84.99 117.195) (width 0.1) (layer "B.Cu") (net 253))
  (segment (start 92.8 122.55) (end 92.4 122.15) (width 0.15) (layer "F.Cu") (net 254))
  (segment (start 85.1 122.15) (end 85.5 122.55) (width 0.1) (layer "F.Cu") (net 254))
  (via blind (at 92.4 122.15) (size 0.5) (drill 0.2) (layers "F.Cu" "In2.Cu") (net 254))
  (via (at 85.5 122.55) (size 0.5) (drill 0.2) (layers "F.Cu" "B.Cu") (net 254))
  (segment (start 90.15 122.297741) (end 90.15 121.802259) (width 0.1) (layer "In2.Cu") (net 254))
  (segment (start 89.547492 121.780007) (end 89.55 121.802259) (width 0.1) (layer "In2.Cu") (net 254))
  (segment (start 89.728183 122.360089) (end 89.740096 122.341129) (width 0.1) (layer "In2.Cu") (net 254))
  (segment (start 90.128183 122.360089) (end 90.140096 122.341129) (width 0.1) (layer "In2.Cu") (net 254))
  (segment (start 90.728183 121.739911) (end 90.740096 121.758871) (width 0.1) (layer "In2.Cu") (net 254))
  (segment (start 89.347492 122.319993) (end 89.35 122.297741) (width 0.1) (layer "In2.Cu") (net 254))
  (segment (start 88.85 122.347741) (end 88.872252 122.345233) (width 0.1) (layer "In2.Cu") (net 254))
  (segment (start 89.928183 121.739911) (end 89.940096 121.758871) (width 0.1) (layer "In2.Cu") (net 254))
  (segment (start 90.387651 122.375924) (end 90.406611 122.387837) (width 0.1) (layer "In2.Cu") (net 254))
  (segment (start 89.359903 121.758871) (end 89.371816 121.739911) (width 0.1) (layer "In2.Cu") (net 254))
  (segment (start 89.328183 122.360089) (end 89.340096 122.341129) (width 0.1) (layer "In2.Cu") (net 254))
  (segment (start 89.15 121.802259) (end 89.15 122.297741) (width 0.1) (layer "In2.Cu") (net 254))
  (segment (start 91.187651 122.028184) (end 91.206611 122.040097) (width 0.1) (layer "In2.Cu") (net 254))
  (segment (start 90.693388 121.712163) (end 90.712348 121.724076) (width 0.1) (layer "In2.Cu") (net 254))
  (segment (start 88.912348 122.325924) (end 88.928183 122.310089) (width 0.1) (layer "In2.Cu") (net 254))
  (segment (start 89.85 121.702259) (end 89.872252 121.704767) (width 0.1) (layer "In2.Cu") (net 254))
  (segment (start 88.24774 122.05) (end 88.25 122.05) (width 0.1) (layer "In2.Cu") (net 254))
  (segment (start 88.293388 122.059903) (end 88.312348 122.071816) (width 0.1) (layer "In2.Cu") (net 254))
  (segment (start 87.892898 122.059791) (end 87.911644 122.07157) (width 0.1) (layer "In2.Cu") (net 254))
  (segment (start 88.75 122.247741) (end 88.752507 122.269993) (width 0.1) (layer "In2.Cu") (net 254))
  (segment (start 91.027747 121.704767) (end 91.05 121.702259) (width 0.1) (layer "In2.Cu") (net 254))
  (segment (start 91.006611 121.712163) (end 91.027747 121.704767) (width 0.1) (layer "In2.Cu") (net 254))
  (segment (start 89.627747 122.395233) (end 89.65 122.397741) (width 0.1) (layer "In2.Cu") (net 254))
  (segment (start 88.95 122.247741) (end 88.95 121.802259) (width 0.1) (layer "In2.Cu") (net 254))
  (segment (start 89.312348 122.375924) (end 89.328183 122.360089) (width 0.1) (layer "In2.Cu") (net 254))
  (segment (start 91.206611 122.040097) (end 91.227747 122.047493) (width 0.1) (layer "In2.Cu") (net 254))
  (segment (start 89.35 122.297741) (end 89.35 121.802259) (width 0.1) (layer "In2.Cu") (net 254))
  (segment (start 89.272252 122.395233) (end 89.293388 122.387837) (width 0.1) (layer "In2.Cu") (net 254))
  (segment (start 91.093388 121.712163) (end 91.112348 121.724076) (width 0.1) (layer "In2.Cu") (net 254))
  (segment (start 90.806611 122.387837) (end 90.827747 122.395233) (width 0.1) (layer "In2.Cu") (net 254))
  (segment (start 89.971816 122.360089) (end 89.987651 122.375924) (width 0.1) (layer "In2.Cu") (net 254))
  (segment (start 89.806611 121.712163) (end 89.827747 121.704767) (width 0.1) (layer "In2.Cu") (net 254))
  (segment (start 90.771816 122.360089) (end 90.787651 122.375924) (width 0.1) (layer "In2.Cu") (net 254))
  (segment (start 90.15 121.802259) (end 90.152507 121.780007) (width 0.1) (layer "In2.Cu") (net 254))
  (segment (start 90.227747 121.704767) (end 90.25 121.702259) (width 0.1) (layer "In2.Cu") (net 254))
  (segment (start 89.55 121.802259) (end 89.55 122.297741) (width 0.1) (layer "In2.Cu") (net 254))
  (segment (start 88.928183 122.310089) (end 88.940096 122.291129) (width 0.1) (layer "In2.Cu") (net 254))
  (segment (start 88.547492 122.269993) (end 88.55 122.247741) (width 0.1) (layer "In2.Cu") (net 254))
  (segment (start 90.147492 122.319993) (end 90.15 122.297741) (width 0.1) (layer "In2.Cu") (net 254))
  (segment (start 90.627747 121.704767) (end 90.65 121.702259) (width 0.1) (layer "In2.Cu") (net 254))
  (segment (start 89.027747 121.704767) (end 89.05 121.702259) (width 0.1) (layer "In2.Cu") (net 254))
  (segment (start 88.406611 122.337837) (end 88.427747 122.345233) (width 0.1) (layer "In2.Cu") (net 254))
  (segment (start 88.971816 121.739911) (end 88.987651 121.724076) (width 0.1) (layer "In2.Cu") (net 254))
  (segment (start 89.827747 121.704767) (end 89.85 121.702259) (width 0.1) (layer "In2.Cu") (net 254))
  (segment (start 88.025739 122.245262) (end 88.04774 122.247741) (width 0.1) (layer "In2.Cu") (net 254))
  (segment (start 88.693388 121.712163) (end 88.712348 121.724076) (width 0.1) (layer "In2.Cu") (net 254))
  (segment (start 89.15 122.297741) (end 89.152507 122.319993) (width 0.1) (layer "In2.Cu") (net 254))
  (segment (start 89.872252 121.704767) (end 89.893388 121.712163) (width 0.1) (layer "In2.Cu") (net 254))
  (segment (start 90.371816 122.360089) (end 90.387651 122.375924) (width 0.1) (layer "In2.Cu") (net 254))
  (segment (start 90.359903 122.341129) (end 90.371816 122.360089) (width 0.1) (layer "In2.Cu") (net 254))
  (segment (start 88.092898 122.237949) (end 88.111644 122.22617) (width 0.1) (layer "In2.Cu") (net 254))
  (segment (start 88.25 122.05) (end 88.272252 122.052507) (width 0.1) (layer "In2.Cu") (net 254))
  (segment (start 90.171816 121.739911) (end 90.187651 121.724076) (width 0.1) (layer "In2.Cu") (net 254))
  (segment (start 89.959903 122.341129) (end 89.971816 122.360089) (width 0.1) (layer "In2.Cu") (net 254))
  (segment (start 89.227747 122.395233) (end 89.25 122.397741) (width 0.1) (layer "In2.Cu") (net 254))
  (segment (start 88.65 121.702259) (end 88.672252 121.704767) (width 0.1) (layer "In2.Cu") (net 254))
  (segment (start 90.427747 122.395233) (end 90.45 122.397741) (width 0.1) (layer "In2.Cu") (net 254))
  (segment (start 89.05 121.702259) (end 89.072252 121.704767) (width 0.1) (layer "In2.Cu") (net 254))
  (segment (start 89.206611 122.387837) (end 89.227747 122.395233) (width 0.1) (layer "In2.Cu") (net 254))
  (segment (start 91.159903 121.993389) (end 91.171816 122.012349) (width 0.1) (layer "In2.Cu") (net 254))
  (segment (start 88.204841 122.059791) (end 88.225739 122.052478) (width 0.1) (layer "In2.Cu") (net 254))
  (segment (start 88.186095 122.07157) (end 88.204841 122.059791) (width 0.1) (layer "In2.Cu") (net 254))
  (segment (start 90.712348 121.724076) (end 90.728183 121.739911) (width 0.1) (layer "In2.Cu") (net 254))
  (segment (start 89.35 121.802259) (end 89.352507 121.780007) (width 0.1) (layer "In2.Cu") (net 254))
  (segment (start 91.25 122.05) (end 92.3 122.05) (width 0.1) (layer "In2.Cu") (net 254))
  (segment (start 89.587651 122.375924) (end 89.606611 122.387837) (width 0.1) (layer "In2.Cu") (net 254))
  (segment (start 90.512348 122.375924) (end 90.528183 122.360089) (width 0.1) (layer "In2.Cu") (net 254))
  (segment (start 88.05 122.247741) (end 88.072 122.245262) (width 0.1) (layer "In2.Cu") (net 254))
  (segment (start 88.55 122.247741) (end 88.55 121.802259) (width 0.1) (layer "In2.Cu") (net 254))
  (segment (start 88.359903 122.291129) (end 88.371816 122.310089) (width 0.1) (layer "In2.Cu") (net 254))
  (segment (start 90.95 122.297741) (end 90.95 121.802259) (width 0.1) (layer "In2.Cu") (net 254))
  (segment (start 89.112348 121.724076) (end 89.128183 121.739911) (width 0.1) (layer "In2.Cu") (net 254))
  (segment (start 89.740096 122.341129) (end 89.747492 122.319993) (width 0.1) (layer "In2.Cu") (net 254))
  (segment (start 88.387651 122.325924) (end 88.406611 122.337837) (width 0.1) (layer "In2.Cu") (net 254))
  (segment (start 90.340096 121.758871) (end 90.347492 121.780007) (width 0.1) (layer "In2.Cu") (net 254))
  (segment (start 90.140096 122.341129) (end 90.147492 122.319993) (width 0.1) (layer "In2.Cu") (net 254))
  (segment (start 89.512348 121.724076) (end 89.528183 121.739911) (width 0.1) (layer "In2.Cu") (net 254))
  (segment (start 88.17044 122.087225) (end 88.186095 122.07157) (width 0.1) (layer "In2.Cu") (net 254))
  (segment (start 89.006611 121.712163) (end 89.027747 121.704767) (width 0.1) (layer "In2.Cu") (net 254))
  (segment (start 90.672252 121.704767) (end 90.693388 121.712163) (width 0.1) (layer "In2.Cu") (net 254))
  (segment (start 89.747492 122.319993) (end 89.75 122.297741) (width 0.1) (layer "In2.Cu") (net 254))
  (segment (start 88.004841 122.237949) (end 88.025739 122.245262) (width 0.1) (layer "In2.Cu") (net 254))
  (segment (start 89.093388 121.712163) (end 89.112348 121.724076) (width 0.1) (layer "In2.Cu") (net 254))
  (segment (start 91.171816 122.012349) (end 91.187651 122.028184) (width 0.1) (layer "In2.Cu") (net 254))
  (segment (start 88.127299 122.210515) (end 88.139078 122.191769) (width 0.1) (layer "In2.Cu") (net 254))
  (segment (start 90.940096 122.341129) (end 90.947492 122.319993) (width 0.1) (layer "In2.Cu") (net 254))
  (segment (start 87.85 122.05) (end 87.872 122.052478) (width 0.1) (layer "In2.Cu") (net 254))
  (segment (start 88.872252 122.345233) (end 88.893388 122.337837) (width 0.1) (layer "In2.Cu") (net 254))
  (segment (start 90.55 121.802259) (end 90.552507 121.780007) (width 0.1) (layer "In2.Cu") (net 254))
  (segment (start 88.606611 121.712163) (end 88.627747 121.704767) (width 0.1) (layer "In2.Cu") (net 254))
  (segment (start 89.128183 121.739911) (end 89.140096 121.758871) (width 0.1) (layer "In2.Cu") (net 254))
  (segment (start 87.951348 122.170871) (end 87.958661 122.191769) (width 0.1) (layer "In2.Cu") (net 254))
  (segment (start 88.559903 121.758871) (end 88.571816 121.739911) (width 0.1) (layer "In2.Cu") (net 254))
  (segment (start 89.528183 121.739911) (end 89.540096 121.758871) (width 0.1) (layer "In2.Cu") (net 254))
  (segment (start 85.75 122.55) (end 85.9 122.4) (width 0.1) (layer "In2.Cu") (net 254))
  (segment (start 89.752507 121.780007) (end 89.759903 121.758871) (width 0.1) (layer "In2.Cu") (net 254))
  (segment (start 89.771816 121.739911) (end 89.787651 121.724076) (width 0.1) (layer "In2.Cu") (net 254))
  (segment (start 88.893388 122.337837) (end 88.912348 122.325924) (width 0.1) (layer "In2.Cu") (net 254))
  (segment (start 88.528183 122.310089) (end 88.540096 122.291129) (width 0.1) (layer "In2.Cu") (net 254))
  (segment (start 88.328183 122.087651) (end 88.340096 122.106611) (width 0.1) (layer "In2.Cu") (net 254))
  (segment (start 91.152507 121.972253) (end 91.159903 121.993389) (width 0.1) (layer "In2.Cu") (net 254))
  (segment (start 90.152507 121.780007) (end 90.159903 121.758871) (width 0.1) (layer "In2.Cu") (net 254))
  (segment (start 89.55 122.297741) (end 89.552507 122.319993) (width 0.1) (layer "In2.Cu") (net 254))
  (segment (start 90.35 122.297741) (end 90.352507 122.319993) (width 0.1) (layer "In2.Cu") (net 254))
  (segment (start 88.347492 122.127747) (end 88.35 122.15) (width 0.1) (layer "In2.Cu") (net 254))
  (segment (start 88.587651 121.724076) (end 88.606611 121.712163) (width 0.1) (layer "In2.Cu") (net 254))
  (segment (start 89.371816 121.739911) (end 89.387651 121.724076) (width 0.1) (layer "In2.Cu") (net 254))
  (segment (start 89.672252 122.395233) (end 89.693388 122.387837) (width 0.1) (layer "In2.Cu") (net 254))
  (segment (start 89.387651 121.724076) (end 89.406611 121.712163) (width 0.1) (layer "In2.Cu") (net 254))
  (segment (start 90.959903 121.758871) (end 90.971816 121.739911) (width 0.1) (layer "In2.Cu") (net 254))
  (segment (start 88.139078 122.191769) (end 88.146391 122.170871) (width 0.1) (layer "In2.Cu") (net 254))
  (segment (start 89.559903 122.341129) (end 89.571816 122.360089) (width 0.1) (layer "In2.Cu") (net 254))
  (segment (start 90.25 121.702259) (end 90.272252 121.704767) (width 0.1) (layer "In2.Cu") (net 254))
  (segment (start 90.872252 122.395233) (end 90.893388 122.387837) (width 0.1) (layer "In2.Cu") (net 254))
  (segment (start 90.587651 121.724076) (end 90.606611 121.712163) (width 0.1) (layer "In2.Cu") (net 254))
  (segment (start 87.927299 122.087225) (end 87.939078 122.105971) (width 0.1) (layer "In2.Cu") (net 254))
  (segment (start 89.171816 122.360089) (end 89.187651 122.375924) (width 0.1) (layer "In2.Cu") (net 254))
  (segment (start 88.940096 122.291129) (end 88.947492 122.269993) (width 0.1) (layer "In2.Cu") (net 254))
  (segment (start 90.006611 122.387837) (end 90.027747 122.395233) (width 0.1) (layer "In2.Cu") (net 254))
  (segment (start 90.752507 122.319993) (end 90.759903 122.341129) (width 0.1) (layer "In2.Cu") (net 254))
  (segment (start 90.093388 122.387837) (end 90.112348 122.375924) (width 0.1) (layer "In2.Cu") (net 254))
  (segment (start 89.95 122.297741) (end 89.952507 122.319993) (width 0.1) (layer "In2.Cu") (net 254))
  (segment (start 90.952507 121.780007) (end 90.959903 121.758871) (width 0.1) (layer "In2.Cu") (net 254))
  (segment (start 89.25 122.397741) (end 89.272252 122.395233) (width 0.1) (layer "In2.Cu") (net 254))
  (segment (start 89.340096 122.341129) (end 89.347492 122.319993) (width 0.1) (layer "In2.Cu") (net 254))
  (segment (start 88.827747 122.345233) (end 88.85 122.347741) (width 0.1) (layer "In2.Cu") (net 254))
  (segment (start 90.75 121.802259) (end 90.75 122.297741) (width 0.1) (layer "In2.Cu") (net 254))
  (segment (start 88.571816 121.739911) (end 88.587651 121.724076) (width 0.1) (layer "In2.Cu") (net 254))
  (segment (start 91.15 121.95) (end 91.152507 121.972253) (width 0.1) (layer "In2.Cu") (net 254))
  (segment (start 90.893388 122.387837) (end 90.912348 122.375924) (width 0.1) (layer "In2.Cu") (net 254))
  (segment (start 90.352507 122.319993) (end 90.359903 122.341129) (width 0.1) (layer "In2.Cu") (net 254))
  (segment (start 90.528183 122.360089) (end 90.540096 122.341129) (width 0.1) (layer "In2.Cu") (net 254))
  (segment (start 85.9 122.3) (end 86.15 122.05) (width 0.1) (layer "In2.Cu") (net 254))
  (segment (start 89.147492 121.780007) (end 89.15 121.802259) (width 0.1) (layer "In2.Cu") (net 254))
  (segment (start 90.55 122.297741) (end 90.55 121.802259) (width 0.1) (layer "In2.Cu") (net 254))
  (segment (start 90.947492 122.319993) (end 90.95 122.297741) (width 0.1) (layer "In2.Cu") (net 254))
  (segment (start 89.712348 122.375924) (end 89.728183 122.360089) (width 0.1) (layer "In2.Cu") (net 254))
  (segment (start 89.552507 122.319993) (end 89.559903 122.341129) (width 0.1) (layer "In2.Cu") (net 254))
  (segment (start 90.85 122.397741) (end 90.872252 122.395233) (width 0.1) (layer "In2.Cu") (net 254))
  (segment (start 90.293388 121.712163) (end 90.312348 121.724076) (width 0.1) (layer "In2.Cu") (net 254))
  (segment (start 91.072252 121.704767) (end 91.093388 121.712163) (width 0.1) (layer "In2.Cu") (net 254))
  (segment (start 88.552507 121.780007) (end 88.559903 121.758871) (width 0.1) (layer "In2.Cu") (net 254))
  (segment (start 90.45 122.397741) (end 90.472252 122.395233) (width 0.1) (layer "In2.Cu") (net 254))
  (segment (start 90.747492 121.780007) (end 90.75 121.802259) (width 0.1) (layer "In2.Cu") (net 254))
  (segment (start 87.911644 122.07157) (end 87.927299 122.087225) (width 0.1) (layer "In2.Cu") (net 254))
  (segment (start 86.15 122.05) (end 87.85 122.05) (width 0.1) (layer "In2.Cu") (net 254))
  (segment (start 90.912348 122.375924) (end 90.928183 122.360089) (width 0.1) (layer "In2.Cu") (net 254))
  (segment (start 90.347492 121.780007) (end 90.35 121.802259) (width 0.1) (layer "In2.Cu") (net 254))
  (segment (start 90.552507 121.780007) (end 90.559903 121.758871) (width 0.1) (layer "In2.Cu") (net 254))
  (segment (start 90.05 122.397741) (end 90.072252 122.395233) (width 0.1) (layer "In2.Cu") (net 254))
  (segment (start 90.406611 122.387837) (end 90.427747 122.395233) (width 0.1) (layer "In2.Cu") (net 254))
  (segment (start 89.952507 122.319993) (end 89.959903 122.341129) (width 0.1) (layer "In2.Cu") (net 254))
  (segment (start 88.672252 121.704767) (end 88.693388 121.712163) (width 0.1) (layer "In2.Cu") (net 254))
  (segment (start 87.986095 122.22617) (end 88.004841 122.237949) (width 0.1) (layer "In2.Cu") (net 254))
  (segment (start 89.140096 121.758871) (end 89.147492 121.780007) (width 0.1) (layer "In2.Cu") (net 254))
  (segment (start 88.787651 122.325924) (end 88.806611 122.337837) (width 0.1) (layer "In2.Cu") (net 254))
  (segment (start 90.65 121.702259) (end 90.672252 121.704767) (width 0.1) (layer "In2.Cu") (net 254))
  (segment (start 90.272252 121.704767) (end 90.293388 121.712163) (width 0.1) (layer "In2.Cu") (net 254))
  (segment (start 90.472252 122.395233) (end 90.493388 122.387837) (width 0.1) (layer "In2.Cu") (net 254))
  (segment (start 88.959903 121.758871) (end 88.971816 121.739911) (width 0.1) (layer "In2.Cu") (net 254))
  (segment (start 88.540096 122.291129) (end 88.547492 122.269993) (width 0.1) (layer "In2.Cu") (net 254))
  (segment (start 88.493388 122.337837) (end 88.512348 122.325924) (width 0.1) (layer "In2.Cu") (net 254))
  (segment (start 88.340096 122.106611) (end 88.347492 122.127747) (width 0.1) (layer "In2.Cu") (net 254))
  (segment (start 89.493388 121.712163) (end 89.512348 121.724076) (width 0.1) (layer "In2.Cu") (net 254))
  (segment (start 90.112348 122.375924) (end 90.128183 122.360089) (width 0.1) (layer "In2.Cu") (net 254))
  (segment (start 88.947492 122.269993) (end 88.95 122.247741) (width 0.1) (layer "In2.Cu") (net 254))
  (segment (start 90.159903 121.758871) (end 90.171816 121.739911) (width 0.1) (layer "In2.Cu") (net 254))
  (segment (start 88.95 121.802259) (end 88.952507 121.780007) (width 0.1) (layer "In2.Cu") (net 254))
  (segment (start 91.227747 122.047493) (end 91.25 122.05) (width 0.1) (layer "In2.Cu") (net 254))
  (segment (start 90.312348 121.724076) (end 90.328183 121.739911) (width 0.1) (layer "In2.Cu") (net 254))
  (segment (start 90.971816 121.739911) (end 90.987651 121.724076) (width 0.1) (layer "In2.Cu") (net 254))
  (segment (start 87.97044 122.210515) (end 87.986095 122.22617) (width 0.1) (layer "In2.Cu") (net 254))
  (segment (start 88.75 121.802259) (end 88.75 122.247741) (width 0.1) (layer "In2.Cu") (net 254))
  (segment (start 89.693388 122.387837) (end 89.712348 122.375924) (width 0.1) (layer "In2.Cu") (net 254))
  (segment (start 92.3 122.05) (end 92.4 122.15) (width 0.1) (layer "In2.Cu") (net 254))
  (segment (start 89.912348 121.724076) (end 89.928183 121.739911) (width 0.1) (layer "In2.Cu") (net 254))
  (segment (start 89.427747 121.704767) (end 89.45 121.702259) (width 0.1) (layer "In2.Cu") (net 254))
  (segment (start 90.187651 121.724076) (end 90.206611 121.712163) (width 0.1) (layer "In2.Cu") (net 254))
  (segment (start 88.45 122.347741) (end 88.472252 122.345233) (width 0.1) (layer "In2.Cu") (net 254))
  (segment (start 89.159903 122.341129) (end 89.171816 122.360089) (width 0.1) (layer "In2.Cu") (net 254))
  (segment (start 88.146391 122.170871) (end 88.151348 122.126869) (width 0.1) (layer "In2.Cu") (net 254))
  (segment (start 88.35 122.247741) (end 88.352507 122.269993) (width 0.1) (layer "In2.Cu") (net 254))
  (segment (start 90.827747 122.395233) (end 90.85 122.397741) (width 0.1) (layer "In2.Cu") (net 254))
  (segment (start 89.352507 121.780007) (end 89.359903 121.758871) (width 0.1) (layer "In2.Cu") (net 254))
  (segment (start 90.493388 122.387837) (end 90.512348 122.375924) (width 0.1) (layer "In2.Cu") (net 254))
  (segment (start 90.95 121.802259) (end 90.952507 121.780007) (width 0.1) (layer "In2.Cu") (net 254))
  (segment (start 89.947492 121.780007) (end 89.95 121.802259) (width 0.1) (layer "In2.Cu") (net 254))
  (segment (start 88.225739 122.052478) (end 88.24774 122.05) (width 0.1) (layer "In2.Cu") (net 254))
  (segment (start 89.152507 122.319993) (end 89.159903 122.341129) (width 0.1) (layer "In2.Cu") (net 254))
  (segment (start 90.759903 122.341129) (end 90.771816 122.360089) (width 0.1) (layer "In2.Cu") (net 254))
  (segment (start 88.806611 122.337837) (end 88.827747 122.345233) (width 0.1) (layer "In2.Cu") (net 254))
  (segment (start 88.752507 122.269993) (end 88.759903 122.291129) (width 0.1) (layer "In2.Cu") (net 254))
  (segment (start 89.75 122.297741) (end 89.75 121.802259) (width 0.1) (layer "In2.Cu") (net 254))
  (segment (start 90.987651 121.724076) (end 91.006611 121.712163) (width 0.1) (layer "In2.Cu") (net 254))
  (segment (start 87.872 122.052478) (end 87.892898 122.059791) (width 0.1) (layer "In2.Cu") (net 254))
  (segment (start 88.712348 121.724076) (end 88.728183 121.739911) (width 0.1) (layer "In2.Cu") (net 254))
  (segment (start 88.427747 122.345233) (end 88.45 122.347741) (width 0.1) (layer "In2.Cu") (net 254))
  (segment (start 88.512348 122.325924) (end 88.528183 122.310089) (width 0.1) (layer "In2.Cu") (net 254))
  (segment (start 91.05 121.702259) (end 91.072252 121.704767) (width 0.1) (layer "In2.Cu") (net 254))
  (segment (start 89.940096 121.758871) (end 89.947492 121.780007) (width 0.1) (layer "In2.Cu") (net 254))
  (segment (start 88.04774 122.247741) (end 88.05 122.247741) (width 0.1) (layer "In2.Cu") (net 254))
  (segment (start 89.293388 122.387837) (end 89.312348 122.375924) (width 0.1) (layer "In2.Cu") (net 254))
  (segment (start 88.371816 122.310089) (end 88.387651 122.325924) (width 0.1) (layer "In2.Cu") (net 254))
  (segment (start 87.958661 122.191769) (end 87.97044 122.210515) (width 0.1) (layer "In2.Cu") (net 254))
  (segment (start 90.328183 121.739911) (end 90.340096 121.758871) (width 0.1) (layer "In2.Cu") (net 254))
  (segment (start 89.65 122.397741) (end 89.672252 122.395233) (width 0.1) (layer "In2.Cu") (net 254))
  (segment (start 90.75 122.297741) (end 90.752507 122.319993) (width 0.1) (layer "In2.Cu") (net 254))
  (segment (start 90.559903 121.758871) (end 90.571816 121.739911) (width 0.1) (layer "In2.Cu") (net 254))
  (segment (start 90.571816 121.739911) (end 90.587651 121.724076) (width 0.1) (layer "In2.Cu") (net 254))
  (segment (start 91.112348 121.724076) (end 91.128183 121.739911) (width 0.1) (layer "In2.Cu") (net 254))
  (segment (start 90.027747 122.395233) (end 90.05 122.397741) (width 0.1) (layer "In2.Cu") (net 254))
  (segment (start 90.540096 122.341129) (end 90.547492 122.319993) (width 0.1) (layer "In2.Cu") (net 254))
  (segment (start 91.15 121.802259) (end 91.15 121.95) (width 0.1) (layer "In2.Cu") (net 254))
  (segment (start 88.627747 121.704767) (end 88.65 121.702259) (width 0.1) (layer "In2.Cu") (net 254))
  (segment (start 90.072252 122.395233) (end 90.093388 122.387837) (width 0.1) (layer "In2.Cu") (net 254))
  (segment (start 91.128183 121.739911) (end 91.140096 121.758871) (width 0.1) (layer "In2.Cu") (net 254))
  (segment (start 88.352507 122.269993) (end 88.359903 122.291129) (width 0.1) (layer "In2.Cu") (net 254))
  (segment (start 90.787651 122.375924) (end 90.806611 122.387837) (width 0.1) (layer "In2.Cu") (net 254))
  (segment (start 89.406611 121.712163) (end 89.427747 121.704767) (width 0.1) (layer "In2.Cu") (net 254))
  (segment (start 88.35 122.15) (end 88.35 122.247741) (width 0.1) (layer "In2.Cu") (net 254))
  (segment (start 89.75 121.802259) (end 89.752507 121.780007) (width 0.1) (layer "In2.Cu") (net 254))
  (segment (start 90.606611 121.712163) (end 90.627747 121.704767) (width 0.1) (layer "In2.Cu") (net 254))
  (segment (start 85.5 122.55) (end 85.75 122.55) (width 0.1) (layer "In2.Cu") (net 254))
  (segment (start 88.728183 121.739911) (end 88.740096 121.758871) (width 0.1) (layer "In2.Cu") (net 254))
  (segment (start 90.928183 122.360089) (end 90.940096 122.341129) (width 0.1) (layer "In2.Cu") (net 254))
  (segment (start 87.939078 122.105971) (end 87.946391 122.126869) (width 0.1) (layer "In2.Cu") (net 254))
  (segment (start 88.312348 122.071816) (end 88.328183 122.087651) (width 0.1) (layer "In2.Cu") (net 254))
  (segment (start 90.206611 121.712163) (end 90.227747 121.704767) (width 0.1) (layer "In2.Cu") (net 254))
  (segment (start 89.606611 122.387837) (end 89.627747 122.395233) (width 0.1) (layer "In2.Cu") (net 254))
  (segment (start 90.547492 122.319993) (end 90.55 122.297741) (width 0.1) (layer "In2.Cu") (net 254))
  (segment (start 91.147492 121.780007) (end 91.15 121.802259) (width 0.1) (layer "In2.Cu") (net 254))
  (segment (start 89.787651 121.724076) (end 89.806611 121.712163) (width 0.1) (layer "In2.Cu") (net 254))
  (segment (start 87.946391 122.126869) (end 87.951348 122.170871) (width 0.1) (layer "In2.Cu") (net 254))
  (segment (start 88.771816 122.310089) (end 88.787651 122.325924) (width 0.1) (layer "In2.Cu") (net 254))
  (segment (start 89.987651 122.375924) (end 90.006611 122.387837) (width 0.1) (layer "In2.Cu") (net 254))
  (segment (start 88.151348 122.126869) (end 88.158661 122.105971) (width 0.1) (layer "In2.Cu") (net 254))
  (segment (start 89.072252 121.704767) (end 89.093388 121.712163) (width 0.1) (layer "In2.Cu") (net 254))
  (segment (start 85.9 122.4) (end 85.9 122.3) (width 0.1) (layer "In2.Cu") (net 254))
  (segment (start 91.140096 121.758871) (end 91.147492 121.780007) (width 0.1) (layer "In2.Cu") (net 254))
  (segment (start 88.55 121.802259) (end 88.552507 121.780007) (width 0.1) (layer "In2.Cu") (net 254))
  (segment (start 90.35 121.802259) (end 90.35 122.297741) (width 0.1) (layer "In2.Cu") (net 254))
  (segment (start 88.072 122.245262) (end 88.092898 122.237949) (width 0.1) (layer "In2.Cu") (net 254))
  (segment (start 89.45 121.702259) (end 89.472252 121.704767) (width 0.1) (layer "In2.Cu") (net 254))
  (segment (start 88.952507 121.780007) (end 88.959903 121.758871) (width 0.1) (layer "In2.Cu") (net 254))
  (segment (start 88.158661 122.105971) (end 88.17044 122.087225) (width 0.1) (layer "In2.Cu") (net 254))
  (segment (start 89.571816 122.360089) (end 89.587651 122.375924) (width 0.1) (layer "In2.Cu") (net 254))
  (segment (start 89.893388 121.712163) (end 89.912348 121.724076) (width 0.1) (layer "In2.Cu") (net 254))
  (segment (start 89.472252 121.704767) (end 89.493388 121.712163) (width 0.1) (layer "In2.Cu") (net 254))
  (segment (start 88.472252 122.345233) (end 88.493388 122.337837) (width 0.1) (layer "In2.Cu") (net 254))
  (segment (start 88.111644 122.22617) (end 88.127299 122.210515) (width 0.1) (layer "In2.Cu") (net 254))
  (segment (start 88.272252 122.052507) (end 88.293388 122.059903) (width 0.1) (layer "In2.Cu") (net 254))
  (segment (start 89.540096 121.758871) (end 89.547492 121.780007) (width 0.1) (layer "In2.Cu") (net 254))
  (segment (start 89.187651 122.375924) (end 89.206611 122.387837) (width 0.1) (layer "In2.Cu") (net 254))
  (segment (start 89.95 121.802259) (end 89.95 122.297741) (width 0.1) (layer "In2.Cu") (net 254))
  (segment (start 88.987651 121.724076) (end 89.006611 121.712163) (width 0.1) (layer "In2.Cu") (net 254))
  (segment (start 89.759903 121.758871) (end 89.771816 121.739911) (width 0.1) (layer "In2.Cu") (net 254))
  (segment (start 88.747492 121.780007) (end 88.75 121.802259) (width 0.1) (layer "In2.Cu") (net 254))
  (segment (start 90.740096 121.758871) (end 90.747492 121.780007) (width 0.1) (layer "In2.Cu") (net 254))
  (segment (start 88.759903 122.291129) (end 88.771816 122.310089) (width 0.1) (layer "In2.Cu") (net 254))
  (segment (start 88.740096 121.758871) (end 88.747492 121.780007) (width 0.1) (layer "In2.Cu") (net 254))
  (segment (start 84.99 123.695) (end 84.99 123.06) (width 0.1) (layer "B.Cu") (net 254))
  (segment (start 84.99 123.06) (end 85.5 122.55) (width 0.1) (layer "B.Cu") (net 254))
  (segment (start 96 127.35) (end 95.6 126.95) (width 0.15) (layer "F.Cu") (net 255))
  (segment (start 85.9 119.75) (end 86.3 119.35) (width 0.1) (layer "F.Cu") (net 255))
  (via (at 95.6 126.95) (size 0.5) (drill 0.2) (layers "F.Cu" "B.Cu") (net 255))
  (via (at 86.3 119.35) (size 0.5) (drill 0.2) (layers "F.Cu" "B.Cu") (net 255))
  (segment (start 87.981906 120.128659) (end 88.003737 120.123676) (width 0.1) (layer "In5.Cu") (net 255))
  (segment (start 88.734563 120.931016) (end 88.748526 120.948526) (width 0.1) (layer "In5.Cu") (net 255))
  (segment (start 88.572619 120.165339) (end 88.595011 120.165338) (width 0.1) (layer "In5.Cu") (net 255))
  (segment (start 88.003737 120.123676) (end 88.023913 120.113961) (width 0.1) (layer "In5.Cu") (net 255))
  (segment (start 94.4 124.15) (end 95.2 124.95) (width 0.1) (layer "In5.Cu") (net 255))
  (segment (start 88.400344 119.993064) (end 88.395361 120.014895) (width 0.1) (layer "In5.Cu") (net 255))
  (segment (start 88.833628 120.453163) (end 88.855461 120.448181) (width 0.1) (layer "In5.Cu") (net 255))
  (segment (start 88.465682 120.524261) (end 88.451721 120.541768) (width 0.1) (layer "In5.Cu") (net 255))
  (segment (start 88.683186 120.275906) (end 88.678203 120.297737) (width 0.1) (layer "In5.Cu") (net 255))
  (segment (start 88.678203 120.231681) (end 88.683185 120.253512) (width 0.1) (layer "In5.Cu") (net 255))
  (segment (start 88.159164 120.279102) (end 88.15418 120.300933) (width 0.1) (layer "In5.Cu") (net 255))
  (segment (start 88.724848 120.910842) (end 88.734563 120.931016) (width 0.1) (layer "In5.Cu") (net 255))
  (segment (start 88.91986 120.46288) (end 88.937367 120.47684) (width 0.1) (layer "In5.Cu") (net 255))
  (segment (start 88.795947 120.476841) (end 88.813454 120.46288) (width 0.1) (layer "In5.Cu") (net 255))
  (segment (start 88.442006 120.561944) (end 88.437022 120.583775) (width 0.1) (layer "In5.Cu") (net 255))
  (segment (start 88.961045 120.580579) (end 88.951328 120.600753) (width 0.1) (layer "In5.Cu") (net 255))
  (segment (start 88.442006 120.628) (end 88.451721 120.648174) (width 0.1) (layer "In5.Cu") (net 255))
  (segment (start 88.306755 120.396803) (end 88.324262 120.382841) (width 0.1) (layer "In5.Cu") (net 255))
  (segment (start 88.683185 120.253512) (end 88.683186 120.275906) (width 0.1) (layer "In5.Cu") (net 255))
  (segment (start 87.937681 120.123676) (end 87.959514 120.12866) (width 0.1) (layer "In5.Cu") (net 255))
  (segment (start 86.3 119.35) (end 86.825 119.875) (width 0.1) (layer "In5.Cu") (net 255))
  (segment (start 87.675 119.875) (end 87.9 120.1) (width 0.1) (layer "In5.Cu") (net 255))
  (segment (start 88.951328 120.494347) (end 88.961045 120.514523) (width 0.1) (layer "In5.Cu") (net 255))
  (segment (start 88.550786 120.170321) (end 88.572619 120.165339) (width 0.1) (layer "In5.Cu") (net 255))
  (segment (start 87.959514 120.12866) (end 87.981906 120.128659) (width 0.1) (layer "In5.Cu") (net 255))
  (segment (start 88.465684 120.665684) (end 88.483191 120.679645) (width 0.1) (layer "In5.Cu") (net 255))
  (segment (start 88.503365 120.68936) (end 88.525198 120.694344) (width 0.1) (layer "In5.Cu") (net 255))
  (segment (start 88.242356 120.411502) (end 88.264748 120.411501) (width 0.1) (layer "In5.Cu") (net 255))
  (segment (start 88.168879 120.258926) (end 88.159164 120.279102) (width 0.1) (layer "In5.Cu") (net 255))
  (segment (start 88.385644 120.035069) (end 88.371684 120.052578) (width 0.1) (layer "In5.Cu") (net 255))
  (segment (start 88.312169 119.882496) (end 88.334 119.887479) (width 0.1) (layer "In5.Cu") (net 255))
  (segment (start 88.230263 119.911157) (end 88.24777 119.897196) (width 0.1) (layer "In5.Cu") (net 255))
  (segment (start 88.961045 120.514523) (end 88.966027 120.536354) (width 0.1) (layer "In5.Cu") (net 255))
  (segment (start 88.668486 120.211505) (end 88.678203 120.231681) (width 0.1) (layer "In5.Cu") (net 255))
  (segment (start 88.966028 120.558748) (end 88.961045 120.580579) (width 0.1) (layer "In5.Cu") (net 255))
  (segment (start 88.595011 120.165338) (end 88.616842 120.170321) (width 0.1) (layer "In5.Cu") (net 255))
  (segment (start 88.483191 120.679645) (end 88.503365 120.68936) (width 0.1) (layer "In5.Cu") (net 255))
  (segment (start 88.220523 120.406518) (end 88.242356 120.411502) (width 0.1) (layer "In5.Cu") (net 255))
  (segment (start 88.530612 120.180038) (end 88.550786 120.170321) (width 0.1) (layer "In5.Cu") (net 255))
  (segment (start 88.855461 120.448181) (end 88.877853 120.44818) (width 0.1) (layer "In5.Cu") (net 255))
  (segment (start 88.182842 120.382842) (end 88.200349 120.396803) (width 0.1) (layer "In5.Cu") (net 255))
  (segment (start 88.719864 120.866617) (end 88.719865 120.889011) (width 0.1) (layer "In5.Cu") (net 255))
  (segment (start 88.607104 120.665683) (end 88.795947 120.476841) (width 0.1) (layer "In5.Cu") (net 255))
  (segment (start 88.395361 119.948839) (end 88.400343 119.97067) (width 0.1) (layer "In5.Cu") (net 255))
  (segment (start 88.719865 120.889011) (end 88.724848 120.910842) (width 0.1) (layer "In5.Cu") (net 255))
  (segment (start 88.04142 120.099999) (end 88.230263 119.911157) (width 0.1) (layer "In5.Cu") (net 255))
  (segment (start 88.668486 120.317911) (end 88.654526 120.33542) (width 0.1) (layer "In5.Cu") (net 255))
  (segment (start 88.267944 119.887479) (end 88.289777 119.882497) (width 0.1) (layer "In5.Cu") (net 255))
  (segment (start 88.513105 120.193999) (end 88.530612 120.180038) (width 0.1) (layer "In5.Cu") (net 255))
  (segment (start 86.825 119.875) (end 87.675 119.875) (width 0.1) (layer "In5.Cu") (net 255))
  (segment (start 88.286579 120.406518) (end 88.306755 120.396803) (width 0.1) (layer "In5.Cu") (net 255))
  (segment (start 88.334 119.887479) (end 88.354176 119.897196) (width 0.1) (layer "In5.Cu") (net 255))
  (segment (start 88.451721 120.648174) (end 88.465684 120.665684) (width 0.1) (layer "In5.Cu") (net 255))
  (segment (start 88.200349 120.396803) (end 88.220523 120.406518) (width 0.1) (layer "In5.Cu") (net 255))
  (segment (start 95.2 124.95) (end 95.2 126.55) (width 0.1) (layer "In5.Cu") (net 255))
  (segment (start 88.385644 119.928663) (end 88.395361 119.948839) (width 0.1) (layer "In5.Cu") (net 255))
  (segment (start 88.54759 120.694343) (end 88.569421 120.68936) (width 0.1) (layer "In5.Cu") (net 255))
  (segment (start 88.877853 120.44818) (end 88.899684 120.453163) (width 0.1) (layer "In5.Cu") (net 255))
  (segment (start 88.371684 120.052578) (end 88.18284 120.241419) (width 0.1) (layer "In5.Cu") (net 255))
  (segment (start 88.637018 120.180038) (end 88.654525 120.193998) (width 0.1) (layer "In5.Cu") (net 255))
  (segment (start 88.354176 119.897196) (end 88.371683 119.911156) (width 0.1) (layer "In5.Cu") (net 255))
  (segment (start 88.569421 120.68936) (end 88.589597 120.679645) (width 0.1) (layer "In5.Cu") (net 255))
  (segment (start 88.437023 120.606169) (end 88.442006 120.628) (width 0.1) (layer "In5.Cu") (net 255))
  (segment (start 88.023913 120.113961) (end 88.04142 120.099999) (width 0.1) (layer "In5.Cu") (net 255))
  (segment (start 88.154181 120.323327) (end 88.159164 120.345158) (width 0.1) (layer "In5.Cu") (net 255))
  (segment (start 88.748526 120.948526) (end 91.95 124.15) (width 0.1) (layer "In5.Cu") (net 255))
  (segment (start 88.159164 120.345158) (end 88.168879 120.365332) (width 0.1) (layer "In5.Cu") (net 255))
  (segment (start 88.289777 119.882497) (end 88.312169 119.882496) (width 0.1) (layer "In5.Cu") (net 255))
  (segment (start 88.264748 120.411501) (end 88.286579 120.406518) (width 0.1) (layer "In5.Cu") (net 255))
  (segment (start 88.451721 120.541768) (end 88.442006 120.561944) (width 0.1) (layer "In5.Cu") (net 255))
  (segment (start 88.899684 120.453163) (end 88.91986 120.46288) (width 0.1) (layer "In5.Cu") (net 255))
  (segment (start 88.437022 120.583775) (end 88.437023 120.606169) (width 0.1) (layer "In5.Cu") (net 255))
  (segment (start 88.589597 120.679645) (end 88.607104 120.665683) (width 0.1) (layer "In5.Cu") (net 255))
  (segment (start 88.400343 119.97067) (end 88.400344 119.993064) (width 0.1) (layer "In5.Cu") (net 255))
  (segment (start 88.168879 120.365332) (end 88.182842 120.382842) (width 0.1) (layer "In5.Cu") (net 255))
  (segment (start 88.966027 120.536354) (end 88.966028 120.558748) (width 0.1) (layer "In5.Cu") (net 255))
  (segment (start 88.616842 120.170321) (end 88.637018 120.180038) (width 0.1) (layer "In5.Cu") (net 255))
  (segment (start 88.937367 120.47684) (end 88.951328 120.494347) (width 0.1) (layer "In5.Cu") (net 255))
  (segment (start 88.24777 119.897196) (end 88.267944 119.887479) (width 0.1) (layer "In5.Cu") (net 255))
  (segment (start 88.951328 120.600753) (end 88.937368 120.618262) (width 0.1) (layer "In5.Cu") (net 255))
  (segment (start 88.748524 120.807103) (end 88.734563 120.82461) (width 0.1) (layer "In5.Cu") (net 255))
  (segment (start 88.654526 120.33542) (end 88.465682 120.524261) (width 0.1) (layer "In5.Cu") (net 255))
  (segment (start 88.734563 120.82461) (end 88.724848 120.844786) (width 0.1) (layer "In5.Cu") (net 255))
  (segment (start 88.395361 120.014895) (end 88.385644 120.035069) (width 0.1) (layer "In5.Cu") (net 255))
  (segment (start 95.2 126.55) (end 95.6 126.95) (width 0.1) (layer "In5.Cu") (net 255))
  (segment (start 87.9 120.1) (end 87.917507 120.113961) (width 0.1) (layer "In5.Cu") (net 255))
  (segment (start 88.937368 120.618262) (end 88.748524 120.807103) (width 0.1) (layer "In5.Cu") (net 255))
  (segment (start 88.18284 120.241419) (end 88.168879 120.258926) (width 0.1) (layer "In5.Cu") (net 255))
  (segment (start 87.917507 120.113961) (end 87.937681 120.123676) (width 0.1) (layer "In5.Cu") (net 255))
  (segment (start 88.371683 119.911156) (end 88.385644 119.928663) (width 0.1) (layer "In5.Cu") (net 255))
  (segment (start 88.525198 120.694344) (end 88.54759 120.694343) (width 0.1) (layer "In5.Cu") (net 255))
  (segment (start 91.95 124.15) (end 94.4 124.15) (width 0.1) (layer "In5.Cu") (net 255))
  (segment (start 88.813454 120.46288) (end 88.833628 120.453163) (width 0.1) (layer "In5.Cu") (net 255))
  (segment (start 88.724848 120.844786) (end 88.719864 120.866617) (width 0.1) (layer "In5.Cu") (net 255))
  (segment (start 88.324262 120.382841) (end 88.513105 120.193999) (width 0.1) (layer "In5.Cu") (net 255))
  (segment (start 88.654525 120.193998) (end 88.668486 120.211505) (width 0.1) (layer "In5.Cu") (net 255))
  (segment (start 88.678203 120.297737) (end 88.668486 120.317911) (width 0.1) (layer "In5.Cu") (net 255))
  (segment (start 88.15418 120.300933) (end 88.154181 120.323327) (width 0.1) (layer "In5.Cu") (net 255))
  (segment (start 85.9 118.95) (end 86.3 119.35) (width 0.1) (layer "B.Cu") (net 255))
  (segment (start 85.9 118.95) (end 85.9 117.935) (width 0.1) (layer "B.Cu") (net 255))
  (segment (start 85.9 117.935) (end 85.99 117.845) (width 0.1) (layer "B.Cu") (net 255))
  (segment (start 85.99 117.845) (end 85.99 117.245) (width 0.1) (layer "B.Cu") (net 255))
  (segment (start 97.3 124.6) (end 97.3 125.25) (width 0.1) (layer "F.Cu") (net 256))
  (segment (start 97.3 125.25) (end 96.8 125.75) (width 0.1) (layer "F.Cu") (net 256))
  (segment (start 96.7 124) (end 97.3 124.6) (width 0.1) (layer "F.Cu") (net 256))
  (segment (start 85.9 120.55) (end 86.3 120.95) (width 0.1) (layer "F.Cu") (net 256))
  (via (at 86.3 120.95) (size 0.5) (drill 0.2) (layers "F.Cu" "B.Cu") (net 256))
  (via (at 96.7 124) (size 0.5) (drill 0.2) (layers "F.Cu" "B.Cu") (net 256))
  (segment (start 87.495601 123.342354) (end 87.495602 123.364748) (width 0.1) (layer "B.Cu") (net 256))
  (segment (start 86.765165 121.309098) (end 86.778294 121.298626) (width 0.1) (layer "B.Cu") (net 256))
  (segment (start 87.54794 123.245158) (end 87.538223 123.265332) (width 0.1) (layer "B.Cu") (net 256))
  (segment (start 86.871229 121.309096) (end 86.906584 121.344451) (width 0.1) (layer "B.Cu") (net 256))
  (segment (start 86.523677 121.253738) (end 86.513961 121.273913) (width 0.1) (layer "B.Cu") (net 256))
  (segment (start 86.888825 121.52832) (end 86.896113 121.543453) (width 0.1) (layer "B.Cu") (net 256))
  (segment (start 86.909261 123.335705) (end 86.899545 123.35588) (width 0.1) (layer "B.Cu") (net 256))
  (segment (start 86.924342 121.422255) (end 86.917055 121.437386) (width 0.1) (layer "B.Cu") (net 256))
  (segment (start 86.778294 121.298626) (end 86.793425 121.291338) (width 0.1) (layer "B.Cu") (net 256))
  (segment (start 86.623913 121.446803) (end 86.641421 121.432842) (width 0.1) (layer "B.Cu") (net 256))
  (segment (start 86.924342 121.372713) (end 86.92808 121.389088) (width 0.1) (layer "B.Cu") (net 256))
  (segment (start 86.858098 121.298625) (end 86.871229 121.309096) (width 0.1) (layer "B.Cu") (net 256))
  (segment (start 86.559514 121.461502) (end 86.581907 121.461502) (width 0.1) (layer "B.Cu") (net 256))
  (segment (start 87.064644 123.459619) (end 87.382842 123.141421) (width 0.1) (layer "B.Cu") (net 256))
  (segment (start 86.5 121.432842) (end 86.517507 121.446803) (width 0.1) (layer "B.Cu") (net 256))
  (segment (start 87.500585 123.386579) (end 87.5103 123.406753) (width 0.1) (layer "B.Cu") (net 256))
  (segment (start 87.464747 123.112758) (end 87.48658 123.117742) (width 0.1) (layer "B.Cu") (net 256))
  (segment (start 86.52866 121.231907) (end 86.523677 121.253738) (width 0.1) (layer "B.Cu") (net 256))
  (segment (start 86.906584 121.344451) (end 86.917056 121.357582) (width 0.1) (layer "B.Cu") (net 256))
  (segment (start 87.5103 123.300347) (end 87.500585 123.320523) (width 0.1) (layer "B.Cu") (net 256))
  (segment (start 87.1 123) (end 87.113961 123.017507) (width 0.1) (layer "B.Cu") (net 256))
  (segment (start 86.95 122.85) (end 87.1 123) (width 0.1) (layer "B.Cu") (net 256))
  (segment (start 86.982737 123.488279) (end 87.00513 123.488279) (width 0.1) (layer "B.Cu") (net 256))
  (segment (start 86.894562 123.400104) (end 86.899545 123.421936) (width 0.1) (layer "B.Cu") (net 256))
  (segment (start 86.94073 123.47358) (end 86.960905 123.483296) (width 0.1) (layer "B.Cu") (net 256))
  (segment (start 87.113961 123.123913) (end 87.1 123.141421) (width 0.1) (layer "B.Cu") (net 256))
  (segment (start 86.476322 121.395159) (end 86.486038 121.415334) (width 0.1) (layer "B.Cu") (net 256))
  (segment (start 87.538223 123.265332) (end 87.524263 123.282841) (width 0.1) (layer "B.Cu") (net 256))
  (segment (start 87.538223 123.158926) (end 87.54794 123.179102) (width 0.1) (layer "B.Cu") (net 256))
  (segment (start 86.917056 121.357582) (end 86.924342 121.372713) (width 0.1) (layer "B.Cu") (net 256))
  (segment (start 85.99 123.145) (end 86.135 123) (width 0.1) (layer "B.Cu") (net 256))
  (segment (start 86.826594 121.287602) (end 86.842967 121.291339) (width 0.1) (layer "B.Cu") (net 256))
  (segment (start 86.809798 121.287601) (end 86.826594 121.287602) (width 0.1) (layer "B.Cu") (net 256))
  (segment (start 87.48658 123.117742) (end 87.506754 123.127457) (width 0.1) (layer "B.Cu") (net 256))
  (segment (start 86.486038 121.415334) (end 86.5 121.432842) (width 0.1) (layer "B.Cu") (net 256))
  (segment (start 87.420524 123.117742) (end 87.442355 123.112759) (width 0.1) (layer "B.Cu") (net 256))
  (segment (start 86.581907 121.461502) (end 86.603738 121.456519) (width 0.1) (layer "B.Cu") (net 256))
  (segment (start 86.899545 123.421936) (end 86.909261 123.442111) (width 0.1) (layer "B.Cu") (net 256))
  (segment (start 86.906584 121.556583) (end 86.95 121.6) (width 0.1) (layer "B.Cu") (net 256))
  (segment (start 87.113961 123.017507) (end 87.123677 123.037682) (width 0.1) (layer "B.Cu") (net 256))
  (segment (start 86.537682 121.456519) (end 86.559514 121.461502) (width 0.1) (layer "B.Cu") (net 256))
  (segment (start 87.123677 123.103738) (end 87.113961 123.123913) (width 0.1) (layer "B.Cu") (net 256))
  (segment (start 87.524262 123.424261) (end 88.15 124.05) (width 0.1) (layer "B.Cu") (net 256))
  (segment (start 86.917055 121.437386) (end 86.896112 121.463647) (width 0.1) (layer "B.Cu") (net 256))
  (segment (start 87.500585 123.320523) (end 87.495601 123.342354) (width 0.1) (layer "B.Cu") (net 256))
  (segment (start 87.1 123.141421) (end 86.923223 123.318197) (width 0.1) (layer "B.Cu") (net 256))
  (segment (start 87.524263 123.282841) (end 87.5103 123.300347) (width 0.1) (layer "B.Cu") (net 256))
  (segment (start 86.517507 121.446803) (end 86.537682 121.456519) (width 0.1) (layer "B.Cu") (net 256))
  (segment (start 86.793425 121.291338) (end 86.809798 121.287601) (width 0.1) (layer "B.Cu") (net 256))
  (segment (start 86.7 122.85) (end 86.7 122.25) (width 0.1) (layer "B.Cu") (net 256))
  (segment (start 86.923223 123.318197) (end 86.909261 123.335705) (width 0.1) (layer "B.Cu") (net 256))
  (segment (start 87.442355 123.112759) (end 87.464747 123.112758) (width 0.1) (layer "B.Cu") (net 256))
  (segment (start 87.12866 123.059514) (end 87.12866 123.081907) (width 0.1) (layer "B.Cu") (net 256))
  (segment (start 87.123677 123.037682) (end 87.12866 123.059514) (width 0.1) (layer "B.Cu") (net 256))
  (segment (start 87.506754 123.127457) (end 87.524262 123.141419) (width 0.1) (layer "B.Cu") (net 256))
  (segment (start 86.92808 121.405882) (end 86.924342 121.422255) (width 0.1) (layer "B.Cu") (net 256))
  (segment (start 88.15 124.05) (end 96.65 124.05) (width 0.1) (layer "B.Cu") (net 256))
  (segment (start 96.65 124.05) (end 96.7 124) (width 0.1) (layer "B.Cu") (net 256))
  (segment (start 87.12866 123.081907) (end 87.123677 123.103738) (width 0.1) (layer "B.Cu") (net 256))
  (segment (start 86.896113 121.543453) (end 86.906584 121.556583) (width 0.1) (layer "B.Cu") (net 256))
  (segment (start 87.400348 123.127457) (end 87.420524 123.117742) (width 0.1) (layer "B.Cu") (net 256))
  (segment (start 86.92808 121.389088) (end 86.92808 121.405882) (width 0.1) (layer "B.Cu") (net 256))
  (segment (start 87.5103 123.406753) (end 87.524262 123.424261) (width 0.1) (layer "B.Cu") (net 256))
  (segment (start 87.026961 123.483296) (end 87.047136 123.47358) (width 0.1) (layer "B.Cu") (net 256))
  (segment (start 86.95 121.6) (end 86.95 122.85) (width 0.1) (layer "B.Cu") (net 256))
  (segment (start 86.885089 121.495153) (end 86.885088 121.511947) (width 0.1) (layer "B.Cu") (net 256))
  (segment (start 86.3 121.85) (end 86.3 120.95) (width 0.1) (layer "B.Cu") (net 256))
  (segment (start 87.54794 123.179102) (end 87.552922 123.200933) (width 0.1) (layer "B.Cu") (net 256))
  (segment (start 86.486038 121.308928) (end 86.476322 121.329103) (width 0.1) (layer "B.Cu") (net 256))
  (segment (start 86.603738 121.456519) (end 86.623913 121.446803) (width 0.1) (layer "B.Cu") (net 256))
  (segment (start 86.471339 121.373328) (end 86.476322 121.395159) (width 0.1) (layer "B.Cu") (net 256))
  (segment (start 86.641421 121.432842) (end 86.765165 121.309098) (width 0.1) (layer "B.Cu") (net 256))
  (segment (start 87.495602 123.364748) (end 87.500585 123.386579) (width 0.1) (layer "B.Cu") (net 256))
  (segment (start 86.3 120.95) (end 86.5 121.15) (width 0.1) (layer "B.Cu") (net 256))
  (segment (start 86.960905 123.483296) (end 86.982737 123.488279) (width 0.1) (layer "B.Cu") (net 256))
  (segment (start 86.894562 123.377711) (end 86.894562 123.400104) (width 0.1) (layer "B.Cu") (net 256))
  (segment (start 86.476322 121.329103) (end 86.471339 121.350935) (width 0.1) (layer "B.Cu") (net 256))
  (segment (start 86.923223 123.459619) (end 86.94073 123.47358) (width 0.1) (layer "B.Cu") (net 256))
  (segment (start 86.896112 121.463647) (end 86.888826 121.47878) (width 0.1) (layer "B.Cu") (net 256))
  (segment (start 87.552923 123.223327) (end 87.54794 123.245158) (width 0.1) (layer "B.Cu") (net 256))
  (segment (start 86.888826 121.47878) (end 86.885089 121.495153) (width 0.1) (layer "B.Cu") (net 256))
  (segment (start 87.552922 123.200933) (end 87.552923 123.223327) (width 0.1) (layer "B.Cu") (net 256))
  (segment (start 86.885088 121.511947) (end 86.888825 121.52832) (width 0.1) (layer "B.Cu") (net 256))
  (segment (start 86.7 122.25) (end 86.3 121.85) (width 0.1) (layer "B.Cu") (net 256))
  (segment (start 86.5 121.15) (end 86.513961 121.167507) (width 0.1) (layer "B.Cu") (net 256))
  (segment (start 86.52866 121.209514) (end 86.52866 121.231907) (width 0.1) (layer "B.Cu") (net 256))
  (segment (start 86.842967 121.291339) (end 86.858098 121.298625) (width 0.1) (layer "B.Cu") (net 256))
  (segment (start 86.135 123) (end 86.55 123) (width 0.1) (layer "B.Cu") (net 256))
  (segment (start 86.471339 121.350935) (end 86.471339 121.373328) (width 0.1) (layer "B.Cu") (net 256))
  (segment (start 86.513961 121.167507) (end 86.523677 121.187682) (width 0.1) (layer "B.Cu") (net 256))
  (segment (start 85.99 123.695) (end 85.99 123.145) (width 0.1) (layer "B.Cu") (net 256))
  (segment (start 87.382842 123.141421) (end 87.400348 123.127457) (width 0.1) (layer "B.Cu") (net 256))
  (segment (start 87.00513 123.488279) (end 87.026961 123.483296) (width 0.1) (layer "B.Cu") (net 256))
  (segment (start 86.899545 123.35588) (end 86.894562 123.377711) (width 0.1) (layer "B.Cu") (net 256))
  (segment (start 87.524262 123.141419) (end 87.538223 123.158926) (width 0.1) (layer "B.Cu") (net 256))
  (segment (start 86.513961 121.273913) (end 86.486038 121.308928) (width 0.1) (layer "B.Cu") (net 256))
  (segment (start 86.55 123) (end 86.7 122.85) (width 0.1) (layer "B.Cu") (net 256))
  (segment (start 87.047136 123.47358) (end 87.064644 123.459619) (width 0.1) (layer "B.Cu") (net 256))
  (segment (start 86.523677 121.187682) (end 86.52866 121.209514) (width 0.1) (layer "B.Cu") (net 256))
  (segment (start 86.909261 123.442111) (end 86.923223 123.459619) (width 0.1) (layer "B.Cu") (net 256))
  (segment (start 85.9 121.35) (end 85.5 120.95) (width 0.15) (layer "F.Cu") (net 257))
  (segment (start 89.497492 122.015483) (end 89.5 121.993231) (width 0.1) (layer "F.Cu") (net 257))
  (segment (start 89.062348 122.071414) (end 89.078183 122.055579) (width 0.1) (layer "F.Cu") (net 257))
  (segment (start 89.222252 121.309277) (end 89.243388 121.316673) (width 0.1) (layer "F.Cu") (net 257))
  (segment (start 89.577747 121.309277) (end 89.6 121.306769) (width 0.1) (layer "F.Cu") (net 257))
  (segment (start 89.509903 121.363381) (end 89.521816 121.344421) (width 0.1) (layer "F.Cu") (net 257))
  (segment (start 90.062348 121.328586) (end 90.078183 121.344421) (width 0.1) (layer "F.Cu") (net 257))
  (segment (start 90.022252 121.309277) (end 90.043388 121.316673) (width 0.1) (layer "F.Cu") (net 257))
  (segment (start 88.577747 122.090723) (end 88.6 122.093231) (width 0.1) (layer "F.Cu") (net 257))
  (segment (start 88.702507 121.384517) (end 88.709903 121.363381) (width 0.1) (layer "F.Cu") (net 257))
  (segment (start 89.977747 121.309277) (end 90 121.306769) (width 0.1) (layer "F.Cu") (net 257))
  (segment (start 89.7 121.406769) (end 89.7 121.993231) (width 0.1) (layer "F.Cu") (net 257))
  (segment (start 89.490096 122.036619) (end 89.497492 122.015483) (width 0.1) (layer "F.Cu") (net 257))
  (segment (start 88.756611 121.316673) (end 88.777747 121.309277) (width 0.1) (layer "F.Cu") (net 257))
  (segment (start 88.502507 122.015483) (end 88.509903 122.036619) (width 0.1) (layer "F.Cu") (net 257))
  (segment (start 90.6 121.7) (end 91 121.7) (width 0.1) (layer "F.Cu") (net 257))
  (segment (start 89.177747 121.309277) (end 89.2 121.306769) (width 0.1) (layer "F.Cu") (net 257))
  (segment (start 89.278183 121.344421) (end 89.290096 121.363381) (width 0.1) (layer "F.Cu") (net 257))
  (segment (start 89.043388 122.083327) (end 89.062348 122.071414) (width 0.1) (layer "F.Cu") (net 257))
  (segment (start 89.956611 121.316673) (end 89.977747 121.309277) (width 0.1) (layer "F.Cu") (net 257))
  (segment (start 88.956611 122.083327) (end 88.977747 122.090723) (width 0.1) (layer "F.Cu") (net 257))
  (segment (start 90.302507 121.384517) (end 90.309903 121.363381) (width 0.1) (layer "F.Cu") (net 257))
  (segment (start 88.822252 121.309277) (end 88.843388 121.316673) (width 0.1) (layer "F.Cu") (net 257))
  (segment (start 87.85 121.1) (end 87.85 121.45) (width 0.1) (layer "F.Cu") (net 257))
  (segment (start 88.662348 122.071414) (end 88.678183 122.055579) (width 0.1) (layer "F.Cu") (net 257))
  (segment (start 91.25 121.45) (end 91.25 119.6) (width 0.1) (layer "F.Cu") (net 257))
  (segment (start 90.497492 121.384517) (end 90.5 121.406769) (width 0.1) (layer "F.Cu") (net 257))
  (segment (start 89.622252 121.309277) (end 89.643388 121.316673) (width 0.1) (layer "F.Cu") (net 257))
  (segment (start 90.097492 121.384517) (end 90.1 121.406769) (width 0.1) (layer "F.Cu") (net 257))
  (segment (start 89.897492 122.015483) (end 89.9 121.993231) (width 0.1) (layer "F.Cu") (net 257))
  (segment (start 90.222252 122.090723) (end 90.243388 122.083327) (width 0.1) (layer "F.Cu") (net 257))
  (segment (start 90 121.306769) (end 90.022252 121.309277) (width 0.1) (layer "F.Cu") (net 257))
  (segment (start 89.709903 122.036619) (end 89.721816 122.055579) (width 0.1) (layer "F.Cu") (net 257))
  (segment (start 91.5 119.35) (end 92 119.35) (width 0.1) (layer "F.Cu") (net 257))
  (segment (start 89.121816 121.344421) (end 89.137651 121.328586) (width 0.1) (layer "F.Cu") (net 257))
  (segment (start 90.502507 121.622253) (end 90.509903 121.643389) (width 0.1) (layer "F.Cu") (net 257))
  (segment (start 88.9 121.406769) (end 88.9 121.993231) (width 0.1) (layer "F.Cu") (net 257))
  (segment (start 90.102507 122.015483) (end 90.109903 122.036619) (width 0.1) (layer "F.Cu") (net 257))
  (segment (start 90.478183 121.344421) (end 90.490096 121.363381) (width 0.1) (layer "F.Cu") (net 257))
  (segment (start 89.777747 122.090723) (end 89.8 122.093231) (width 0.1) (layer "F.Cu") (net 257))
  (segment (start 91.25 119.6) (end 91.5 119.35) (width 0.1) (layer "F.Cu") (net 257))
  (segment (start 88.721816 121.344421) (end 88.737651 121.328586) (width 0.1) (layer "F.Cu") (net 257))
  (segment (start 88.7 121.406769) (end 88.702507 121.384517) (width 0.1) (layer "F.Cu") (net 257))
  (segment (start 89.2 121.306769) (end 89.222252 121.309277) (width 0.1) (layer "F.Cu") (net 257))
  (segment (start 90.121816 122.055579) (end 90.137651 122.071414) (width 0.1) (layer "F.Cu") (net 257))
  (segment (start 88.5 121.8) (end 88.5 121.993231) (width 0.1) (layer "F.Cu") (net 257))
  (segment (start 88.622252 122.090723) (end 88.643388 122.083327) (width 0.1) (layer "F.Cu") (net 257))
  (segment (start 90.321816 121.344421) (end 90.337651 121.328586) (width 0.1) (layer "F.Cu") (net 257))
  (segment (start 89.377747 122.090723) (end 89.4 122.093231) (width 0.1) (layer "F.Cu") (net 257))
  (segment (start 89.937651 121.328586) (end 89.956611 121.316673) (width 0.1) (layer "F.Cu") (net 257))
  (segment (start 90.422252 121.309277) (end 90.443388 121.316673) (width 0.1) (layer "F.Cu") (net 257))
  (segment (start 90.262348 122.071414) (end 90.278183 122.055579) (width 0.1) (layer "F.Cu") (net 257))
  (segment (start 89.1 121.993231) (end 89.1 121.406769) (width 0.1) (layer "F.Cu") (net 257))
  (segment (start 89.678183 121.344421) (end 89.690096 121.363381) (width 0.1) (layer "F.Cu") (net 257))
  (segment (start 88.862348 121.328586) (end 88.878183 121.344421) (width 0.1) (layer "F.Cu") (net 257))
  (segment (start 88.521816 122.055579) (end 88.537651 122.071414) (width 0.1) (layer "F.Cu") (net 257))
  (segment (start 90.577747 121.697493) (end 90.6 121.7) (width 0.1) (layer "F.Cu") (net 257))
  (segment (start 89.290096 121.363381) (end 89.297492 121.384517) (width 0.1) (layer "F.Cu") (net 257))
  (segment (start 89 122.093231) (end 89.022252 122.090723) (width 0.1) (layer "F.Cu") (net 257))
  (segment (start 90.243388 122.083327) (end 90.262348 122.071414) (width 0.1) (layer "F.Cu") (net 257))
  (segment (start 88.537651 122.071414) (end 88.556611 122.083327) (width 0.1) (layer "F.Cu") (net 257))
  (segment (start 89.309903 122.036619) (end 89.321816 122.055579) (width 0.1) (layer "F.Cu") (net 257))
  (segment (start 89.643388 121.316673) (end 89.662348 121.328586) (width 0.1) (layer "F.Cu") (net 257))
  (segment (start 89.243388 121.316673) (end 89.262348 121.328586) (width 0.1) (layer "F.Cu") (net 257))
  (segment (start 88.422252 121.702507) (end 88.443388 121.709903) (width 0.1) (layer "F.Cu") (net 257))
  (segment (start 89.297492 121.384517) (end 89.3 121.406769) (width 0.1) (layer "F.Cu") (net 257))
  (segment (start 90.490096 121.363381) (end 90.497492 121.384517) (width 0.1) (layer "F.Cu") (net 257))
  (segment (start 88.737651 121.328586) (end 88.756611 121.316673) (width 0.1) (layer "F.Cu") (net 257))
  (segment (start 89.737651 122.071414) (end 89.756611 122.083327) (width 0.1) (layer "F.Cu") (net 257))
  (segment (start 89.878183 122.055579) (end 89.890096 122.036619) (width 0.1) (layer "F.Cu") (net 257))
  (segment (start 90.462348 121.328586) (end 90.478183 121.344421) (width 0.1) (layer "F.Cu") (net 257))
  (segment (start 89.862348 122.071414) (end 89.878183 122.055579) (width 0.1) (layer "F.Cu") (net 257))
  (segment (start 90.5 121.6) (end 90.502507 121.622253) (width 0.1) (layer "F.Cu") (net 257))
  (segment (start 89.5 121.406769) (end 89.502507 121.384517) (width 0.1) (layer "F.Cu") (net 257))
  (segment (start 88.977747 122.090723) (end 89 122.093231) (width 0.1) (layer "F.Cu") (net 257))
  (segment (start 88.509903 122.036619) (end 88.521816 122.055579) (width 0.1) (layer "F.Cu") (net 257))
  (segment (start 88.556611 122.083327) (end 88.577747 122.090723) (width 0.1) (layer "F.Cu") (net 257))
  (segment (start 89.078183 122.055579) (end 89.090096 122.036619) (width 0.1) (layer "F.Cu") (net 257))
  (segment (start 90.156611 122.083327) (end 90.177747 122.090723) (width 0.1) (layer "F.Cu") (net 257))
  (segment (start 89.478183 122.055579) (end 89.490096 122.036619) (width 0.1) (layer "F.Cu") (net 257))
  (segment (start 89.822252 122.090723) (end 89.843388 122.083327) (width 0.1) (layer "F.Cu") (net 257))
  (segment (start 90.2 122.093231) (end 90.222252 122.090723) (width 0.1) (layer "F.Cu") (net 257))
  (segment (start 89.909903 121.363381) (end 89.921816 121.344421) (width 0.1) (layer "F.Cu") (net 257))
  (segment (start 90.537651 121.678184) (end 90.556611 121.690097) (width 0.1) (layer "F.Cu") (net 257))
  (segment (start 89.1 121.406769) (end 89.102507 121.384517) (width 0.1) (layer "F.Cu") (net 257))
  (segment (start 88.9 121.993231) (end 88.902507 122.015483) (width 0.1) (layer "F.Cu") (net 257))
  (segment (start 89.7 121.993231) (end 89.702507 122.015483) (width 0.1) (layer "F.Cu") (net 257))
  (segment (start 89.662348 121.328586) (end 89.678183 121.344421) (width 0.1) (layer "F.Cu") (net 257))
  (segment (start 88.709903 121.363381) (end 88.721816 121.344421) (width 0.1) (layer "F.Cu") (net 257))
  (segment (start 89.690096 121.363381) (end 89.697492 121.384517) (width 0.1) (layer "F.Cu") (net 257))
  (segment (start 89.022252 122.090723) (end 89.043388 122.083327) (width 0.1) (layer "F.Cu") (net 257))
  (segment (start 90.4 121.306769) (end 90.422252 121.309277) (width 0.1) (layer "F.Cu") (net 257))
  (segment (start 88.5 121.993231) (end 88.502507 122.015483) (width 0.1) (layer "F.Cu") (net 257))
  (segment (start 90.177747 122.090723) (end 90.2 122.093231) (width 0.1) (layer "F.Cu") (net 257))
  (segment (start 90.1 121.993231) (end 90.102507 122.015483) (width 0.1) (layer "F.Cu") (net 257))
  (segment (start 90.297492 122.015483) (end 90.3 121.993231) (width 0.1) (layer "F.Cu") (net 257))
  (segment (start 90.090096 121.363381) (end 90.097492 121.384517) (width 0.1) (layer "F.Cu") (net 257))
  (segment (start 89.537651 121.328586) (end 89.556611 121.316673) (width 0.1) (layer "F.Cu") (net 257))
  (segment (start 89.321816 122.055579) (end 89.337651 122.071414) (width 0.1) (layer "F.Cu") (net 257))
  (segment (start 89.6 121.306769) (end 89.622252 121.309277) (width 0.1) (layer "F.Cu") (net 257))
  (segment (start 89.356611 122.083327) (end 89.377747 122.090723) (width 0.1) (layer "F.Cu") (net 257))
  (segment (start 88.4 121.7) (end 88.422252 121.702507) (width 0.1) (layer "F.Cu") (net 257))
  (segment (start 89.721816 122.055579) (end 89.737651 122.071414) (width 0.1) (layer "F.Cu") (net 257))
  (segment (start 89.090096 122.036619) (end 89.097492 122.015483) (width 0.1) (layer "F.Cu") (net 257))
  (segment (start 90.1 121.406769) (end 90.1 121.993231) (width 0.1) (layer "F.Cu") (net 257))
  (segment (start 88.777747 121.309277) (end 88.8 121.306769) (width 0.1) (layer "F.Cu") (net 257))
  (segment (start 88.6 122.093231) (end 88.622252 122.090723) (width 0.1) (layer "F.Cu") (net 257))
  (segment (start 89.5 121.993231) (end 89.5 121.406769) (width 0.1) (layer "F.Cu") (net 257))
  (segment (start 90.337651 121.328586) (end 90.356611 121.316673) (width 0.1) (layer "F.Cu") (net 257))
  (segment (start 88.490096 121.756611) (end 88.497492 121.777747) (width 0.1) (layer "F.Cu") (net 257))
  (segment (start 88.890096 121.363381) (end 88.897492 121.384517) (width 0.1) (layer "F.Cu") (net 257))
  (segment (start 90.3 121.993231) (end 90.3 121.406769) (width 0.1) (layer "F.Cu") (net 257))
  (segment (start 89.9 121.406769) (end 89.902507 121.384517) (width 0.1) (layer "F.Cu") (net 257))
  (segment (start 88.902507 122.015483) (end 88.909903 122.036619) (width 0.1) (layer "F.Cu") (net 257))
  (segment (start 89.262348 121.328586) (end 89.278183 121.344421) (width 0.1) (layer "F.Cu") (net 257))
  (segment (start 89.097492 122.015483) (end 89.1 121.993231) (width 0.1) (layer "F.Cu") (net 257))
  (segment (start 89.102507 121.384517) (end 89.109903 121.363381) (width 0.1) (layer "F.Cu") (net 257))
  (segment (start 90.278183 122.055579) (end 90.290096 122.036619) (width 0.1) (layer "F.Cu") (net 257))
  (segment (start 90.309903 121.363381) (end 90.321816 121.344421) (width 0.1) (layer "F.Cu") (net 257))
  (segment (start 88.897492 121.384517) (end 88.9 121.406769) (width 0.1) (layer "F.Cu") (net 257))
  (segment (start 90.443388 121.316673) (end 90.462348 121.328586) (width 0.1) (layer "F.Cu") (net 257))
  (segment (start 90.109903 122.036619) (end 90.121816 122.055579) (width 0.1) (layer "F.Cu") (net 257))
  (segment (start 90.043388 121.316673) (end 90.062348 121.328586) (width 0.1) (layer "F.Cu") (net 257))
  (segment (start 90.356611 121.316673) (end 90.377747 121.309277) (width 0.1) (layer "F.Cu") (net 257))
  (segment (start 88.7 121.993231) (end 88.7 121.406769) (width 0.1) (layer "F.Cu") (net 257))
  (segment (start 89.4 122.093231) (end 89.422252 122.090723) (width 0.1) (layer "F.Cu") (net 257))
  (segment (start 87.85 121.45) (end 88.1 121.7) (width 0.1) (layer "F.Cu") (net 257))
  (segment (start 90.3 121.406769) (end 90.302507 121.384517) (width 0.1) (layer "F.Cu") (net 257))
  (segment (start 88.497492 121.777747) (end 88.5 121.8) (width 0.1) (layer "F.Cu") (net 257))
  (segment (start 88.921816 122.055579) (end 88.937651 122.071414) (width 0.1) (layer "F.Cu") (net 257))
  (segment (start 90.521816 121.662349) (end 90.537651 121.678184) (width 0.1) (layer "F.Cu") (net 257))
  (segment (start 90.377747 121.309277) (end 90.4 121.306769) (width 0.1) (layer "F.Cu") (net 257))
  (segment (start 89.697492 121.384517) (end 89.7 121.406769) (width 0.1) (layer "F.Cu") (net 257))
  (segment (start 88.443388 121.709903) (end 88.462348 121.721816) (width 0.1) (layer "F.Cu") (net 257))
  (segment (start 89.890096 122.036619) (end 89.897492 122.015483) (width 0.1) (layer "F.Cu") (net 257))
  (segment (start 89.422252 122.090723) (end 89.443388 122.083327) (width 0.1) (layer "F.Cu") (net 257))
  (segment (start 88.843388 121.316673) (end 88.862348 121.328586) (width 0.1) (layer "F.Cu") (net 257))
  (segment (start 88.909903 122.036619) (end 88.921816 122.055579) (width 0.1) (layer "F.Cu") (net 257))
  (segment (start 91 121.7) (end 91.25 121.45) (width 0.1) (layer "F.Cu") (net 257))
  (segment (start 89.3 121.993231) (end 89.302507 122.015483) (width 0.1) (layer "F.Cu") (net 257))
  (segment (start 89.443388 122.083327) (end 89.462348 122.071414) (width 0.1) (layer "F.Cu") (net 257))
  (segment (start 90.078183 121.344421) (end 90.090096 121.363381) (width 0.1) (layer "F.Cu") (net 257))
  (segment (start 89.843388 122.083327) (end 89.862348 122.071414) (width 0.1) (layer "F.Cu") (net 257))
  (segment (start 89.337651 122.071414) (end 89.356611 122.083327) (width 0.1) (layer "F.Cu") (net 257))
  (segment (start 88.937651 122.071414) (end 88.956611 122.083327) (width 0.1) (layer "F.Cu") (net 257))
  (segment (start 90.290096 122.036619) (end 90.297492 122.015483) (width 0.1) (layer "F.Cu") (net 257))
  (segment (start 89.156611 121.316673) (end 89.177747 121.309277) (width 0.1) (layer "F.Cu") (net 257))
  (segment (start 88.643388 122.083327) (end 88.662348 122.071414) (width 0.1) (layer "F.Cu") (net 257))
  (segment (start 89.462348 122.071414) (end 89.478183 122.055579) (width 0.1) (layer "F.Cu") (net 257))
  (segment (start 89.9 121.993231) (end 89.9 121.406769) (width 0.1) (layer "F.Cu") (net 257))
  (segment (start 89.8 122.093231) (end 89.822252 122.090723) (width 0.1) (layer "F.Cu") (net 257))
  (segment (start 90.509903 121.643389) (end 90.521816 121.662349) (width 0.1) (layer "F.Cu") (net 257))
  (segment (start 89.502507 121.384517) (end 89.509903 121.363381) (width 0.1) (layer "F.Cu") (net 257))
  (segment (start 89.756611 122.083327) (end 89.777747 122.090723) (width 0.1) (layer "F.Cu") (net 257))
  (segment (start 89.921816 121.344421) (end 89.937651 121.328586) (width 0.1) (layer "F.Cu") (net 257))
  (segment (start 88.8 121.306769) (end 88.822252 121.309277) (width 0.1) (layer "F.Cu") (net 257))
  (segment (start 89.302507 122.015483) (end 89.309903 122.036619) (width 0.1) (layer "F.Cu") (net 257))
  (segment (start 88.678183 122.055579) (end 88.690096 122.036619) (width 0.1) (layer "F.Cu") (net 257))
  (segment (start 89.3 121.406769) (end 89.3 121.993231) (width 0.1) (layer "F.Cu") (net 257))
  (segment (start 88.697492 122.015483) (end 88.7 121.993231) (width 0.1) (layer "F.Cu") (net 257))
  (segment (start 89.902507 121.384517) (end 89.909903 121.363381) (width 0.1) (layer "F.Cu") (net 257))
  (segment (start 89.556611 121.316673) (end 89.577747 121.309277) (width 0.1) (layer "F.Cu") (net 257))
  (segment (start 90.137651 122.071414) (end 90.156611 122.083327) (width 0.1) (layer "F.Cu") (net 257))
  (segment (start 90.556611 121.690097) (end 90.577747 121.697493) (width 0.1) (layer "F.Cu") (net 257))
  (segment (start 88.478183 121.737651) (end 88.490096 121.756611) (width 0.1) (layer "F.Cu") (net 257))
  (segment (start 88.878183 121.344421) (end 88.890096 121.363381) (width 0.1) (layer "F.Cu") (net 257))
  (segment (start 88.690096 122.036619) (end 88.697492 122.015483) (width 0.1) (layer "F.Cu") (net 257))
  (segment (start 89.521816 121.344421) (end 89.537651 121.328586) (width 0.1) (layer "F.Cu") (net 257))
  (segment (start 88.1 121.7) (end 88.4 121.7) (width 0.1) (layer "F.Cu") (net 257))
  (segment (start 89.702507 122.015483) (end 89.709903 122.036619) (width 0.1) (layer "F.Cu") (net 257))
  (segment (start 89.137651 121.328586) (end 89.156611 121.316673) (width 0.1) (layer "F.Cu") (net 257))
  (segment (start 89.109903 121.363381) (end 89.121816 121.344421) (width 0.1) (layer "F.Cu") (net 257))
  (segment (start 88.462348 121.721816) (end 88.478183 121.737651) (width 0.1) (layer "F.Cu") (net 257))
  (segment (start 90.5 121.406769) (end 90.5 121.6) (width 0.1) (layer "F.Cu") (net 257))
  (via (at 85.5 120.95) (size 0.5) (drill 0.2) (layers "F.Cu" "B.Cu") (net 257))
  (via blind (at 87.85 121.1) (size 0.5) (drill 0.2) (layers "F.Cu" "In2.Cu") (net 257))
  (segment (start 85.5 120.95) (end 85.65 120.95) (width 0.1) (layer "In2.Cu") (net 257))
  (segment (start 86.1 121.4) (end 87.55 121.4) (width 0.1) (layer "In2.Cu") (net 257))
  (segment (start 85.65 120.95) (end 86.1 121.4) (width 0.1) (layer "In2.Cu") (net 257))
  (segment (start 87.55 121.4) (end 87.85 121.1) (width 0.1) (layer "In2.Cu") (net 257))
  (segment (start 85.49001 123.14499) (end 85.49001 123.74001) (width 0.1) (layer "B.Cu") (net 257))
  (segment (start 85.9 122.735) (end 85.49001 123.14499) (width 0.1) (layer "B.Cu") (net 257))
  (segment (start 85.9 121.35) (end 85.9 122.735) (width 0.1) (layer "B.Cu") (net 257))
  (segment (start 85.9 121.35) (end 85.5 120.95) (width 0.1) (layer "B.Cu") (net 257))
  (segment (start 93.35 124.4) (end 93.6 124.65) (width 0.1) (layer "F.Cu") (net 258))
  (segment (start 84.7 122.55) (end 85.1 122.95) (width 0.1) (layer "F.Cu") (net 258))
  (segment (start 91.15 124.4) (end 93.35 124.4) (width 0.1) (layer "F.Cu") (net 258))
  (segment (start 93.6 124.65) (end 93.6 124.95) (width 0.1) (layer "F.Cu") (net 258))
  (segment (start 90.475 125.075) (end 91.15 124.4) (width 0.1) (layer "F.Cu") (net 258))
  (via (at 90.475 125.075) (size 0.5) (drill 0.2) (layers "F.Cu" "B.Cu") (net 258))
  (via (at 84.7 122.55) (size 0.5) (drill 0.2) (layers "F.Cu" "B.Cu") (net 258))
  (segment (start 85.125 123.375) (end 84.7 122.95) (width 0.1) (layer "In5.Cu") (net 258))
  (segment (start 84.7 122.95) (end 84.7 122.55) (width 0.1) (layer "In5.Cu") (net 258))
  (segment (start 90.475 125.075) (end 90.025 125.075) (width 0.1) (layer "In5.Cu") (net 258))
  (segment (start 90.025 125.075) (end 88.325 123.375) (width 0.1) (layer "In5.Cu") (net 258))
  (segment (start 88.325 123.375) (end 85.125 123.375) (width 0.1) (layer "In5.Cu") (net 258))
  (segment (start 84.49 123.695) (end 84.49 122.76) (width 0.1) (layer "B.Cu") (net 258))
  (segment (start 84.49 122.76) (end 84.7 122.55) (width 0.1) (layer "B.Cu") (net 258))
  (segment (start 88.846006 123.756611) (end 88.853402 123.777747) (width 0.1) (layer "F.Cu") (net 259))
  (segment (start 87.022252 122.152507) (end 87.043388 122.159903) (width 0.1) (layer "F.Cu") (net 259))
  (segment (start 88.818258 122.921816) (end 88.834093 122.937651) (width 0.1) (layer "F.Cu") (net 259))
  (segment (start 87.090096 122.206611) (end 87.097492 122.227747) (width 0.1) (layer "F.Cu") (net 259))
  (segment (start 87.177747 122.347492) (end 87.2 122.35) (width 0.1) (layer "F.Cu") (net 259))
  (segment (start 88.755909 122.9) (end 88.778162 122.902507) (width 0.1) (layer "F.Cu") (net 259))
  (segment (start 88.834093 123.862348) (end 88.818258 123.878183) (width 0.1) (layer "F.Cu") (net 259))
  (segment (start 88.556612 123.909903) (end 88.537652 123.921816) (width 0.1) (layer "F.Cu") (net 259))
  (segment (start 87 122.15) (end 87.022252 122.152507) (width 0.1) (layer "F.Cu") (net 259))
  (segment (start 87.843388 121.859904) (end 87.862348 121.871817) (width 0.1) (layer "F.Cu") (net 259))
  (segment (start 88.221838 123.297492) (end 88.244091 123.3) (width 0.1) (layer "F.Cu") (net 259))
  (segment (start 88.478183 122.662348) (end 88.462348 122.678183) (width 0.1) (layer "F.Cu") (net 259))
  (segment (start 88.144091 122.8) (end 88.146598 122.822252) (width 0.1) (layer "F.Cu") (net 259))
  (segment (start 87.490096 121.906612) (end 87.497492 121.927748) (width 0.1) (layer "F.Cu") (net 259))
  (segment (start 87.542458 122.292572) (end 87.55831 122.298119) (width 0.1) (layer "F.Cu") (net 259))
  (segment (start 87.878183 121.887652) (end 87.890096 121.906612) (width 0.1) (layer "F.Cu") (net 259))
  (segment (start 88.846006 123.443388) (end 88.834093 123.462348) (width 0.1) (layer "F.Cu") (net 259))
  (segment (start 88.846006 122.956611) (end 88.853402 122.977747) (width 0.1) (layer "F.Cu") (net 259))
  (segment (start 88.490096 122.643388) (end 88.478183 122.662348) (width 0.1) (layer "F.Cu") (net 259))
  (segment (start 87.50188 122.241689) (end 87.507427 122.257541) (width 0.1) (layer "F.Cu") (net 259))
  (segment (start 88.855909 123.8) (end 88.853402 123.822252) (width 0.1) (layer "F.Cu") (net 259))
  (segment (start 88.5 122.45) (end 88.5 122.6) (width 0.1) (layer "F.Cu") (net 259))
  (segment (start 88.834093 122.937651) (end 88.846006 122.956611) (width 0.1) (layer "F.Cu") (net 259))
  (segment (start 87.262348 122.328183) (end 87.278183 122.312348) (width 0.1) (layer "F.Cu") (net 259))
  (segment (start 88.165907 122.737651) (end 88.153994 122.756611) (width 0.1) (layer "F.Cu") (net 259))
  (segment (start 88.422252 122.697492) (end 88.4 122.7) (width 0.1) (layer "F.Cu") (net 259))
  (segment (start 88.799298 123.490096) (end 88.778162 123.497492) (width 0.1) (layer "F.Cu") (net 259))
  (segment (start 88.200702 123.690096) (end 88.221838 123.697492) (width 0.1) (layer "F.Cu") (net 259))
  (segment (start 86.7 122.15) (end 87 122.15) (width 0.1) (layer "F.Cu") (net 259))
  (segment (start 87.721816 121.887652) (end 87.737651 121.871817) (width 0.1) (layer "F.Cu") (net 259))
  (segment (start 87.575 122.3) (end 87.625 122.3) (width 0.1) (layer "F.Cu") (net 259))
  (segment (start 87.043388 122.159903) (end 87.062348 122.171816) (width 0.1) (layer "F.Cu") (net 259))
  (segment (start 87.862348 121.871817) (end 87.878183 121.887652) (width 0.1) (layer "F.Cu") (net 259))
  (segment (start 87.657541 122.292572) (end 87.671761 122.283637) (width 0.1) (layer "F.Cu") (net 259))
  (segment (start 88.153994 122.756611) (end 88.146598 122.777747) (width 0.1) (layer "F.Cu") (net 259))
  (segment (start 87.956611 122.140097) (end 87.977747 122.147493) (width 0.1) (layer "F.Cu") (net 259))
  (segment (start 87.625 122.3) (end 87.641689 122.298119) (width 0.1) (layer "F.Cu") (net 259))
  (segment (start 87.5 122.225) (end 87.50188 122.241689) (width 0.1) (layer "F.Cu") (net 259))
  (segment (start 87.4 121.85) (end 87.422252 121.852508) (width 0.1) (layer "F.Cu") (net 259))
  (segment (start 87.462348 121.871817) (end 87.478183 121.887652) (width 0.1) (layer "F.Cu") (net 259))
  (segment (start 87.337651 121.871817) (end 87.356611 121.859904) (width 0.1) (layer "F.Cu") (net 259))
  (segment (start 87.2 122.35) (end 87.222252 122.347492) (width 0.1) (layer "F.Cu") (net 259))
  (segment (start 87.528238 122.283637) (end 87.542458 122.292572) (width 0.1) (layer "F.Cu") (net 259))
  (segment (start 87.890096 121.906612) (end 87.897492 121.927748) (width 0.1) (layer "F.Cu") (net 259))
  (segment (start 87.356611 121.859904) (end 87.377747 121.852508) (width 0.1) (layer "F.Cu") (net 259))
  (segment (start 87.8 121.85) (end 87.822252 121.852508) (width 0.1) (layer "F.Cu") (net 259))
  (segment (start 87.692572 122.257541) (end 87.698119 122.241689) (width 0.1) (layer "F.Cu") (net 259))
  (segment (start 87.278183 122.312348) (end 87.290096 122.293388) (width 0.1) (layer "F.Cu") (net 259))
  (segment (start 88.537652 123.921816) (end 88.521817 123.937651) (width 0.1) (layer "F.Cu") (net 259))
  (segment (start 88.778162 123.097492) (end 88.755909 123.1) (width 0.1) (layer "F.Cu") (net 259))
  (segment (start 87.478183 121.887652) (end 87.490096 121.906612) (width 0.1) (layer "F.Cu") (net 259))
  (segment (start 88.846006 123.356611) (end 88.853402 123.377747) (width 0.1) (layer "F.Cu") (net 259))
  (segment (start 88.165907 123.537651) (end 88.153994 123.556611) (width 0.1) (layer "F.Cu") (net 259))
  (segment (start 88.200702 123.509903) (end 88.181742 123.521816) (width 0.1) (layer "F.Cu") (net 259))
  (segment (start 88.855909 123) (end 88.853402 123.022252) (width 0.1) (layer "F.Cu") (net 259))
  (segment (start 87.297492 122.272252) (end 87.3 122.25) (width 0.1) (layer "F.Cu") (net 259))
  (segment (start 88.200702 123.109903) (end 88.181742 123.121816) (width 0.1) (layer "F.Cu") (net 259))
  (segment (start 88.855909 123.4) (end 88.853402 123.422252) (width 0.1) (layer "F.Cu") (net 259))
  (segment (start 88.244091 123.1) (end 88.221838 123.102507) (width 0.1) (layer "F.Cu") (net 259))
  (segment (start 88.497492 122.622252) (end 88.490096 122.643388) (width 0.1) (layer "F.Cu") (net 259))
  (segment (start 88.181742 123.678183) (end 88.200702 123.690096) (width 0.1) (layer "F.Cu") (net 259))
  (segment (start 88.221838 123.102507) (end 88.200702 123.109903) (width 0.1) (layer "F.Cu") (net 259))
  (segment (start 88.853402 122.977747) (end 88.855909 123) (width 0.1) (layer "F.Cu") (net 259))
  (segment (start 87.709903 121.906612) (end 87.721816 121.887652) (width 0.1) (layer "F.Cu") (net 259))
  (segment (start 88.244091 123.7) (end 88.755909 123.7) (width 0.1) (layer "F.Cu") (net 259))
  (segment (start 87.309903 121.906612) (end 87.321816 121.887652) (width 0.1) (layer "F.Cu") (net 259))
  (segment (start 88.153994 123.556611) (end 88.146598 123.577747) (width 0.1) (layer "F.Cu") (net 259))
  (segment (start 88.799298 123.309903) (end 88.818258 123.321816) (width 0.1) (layer "F.Cu") (net 259))
  (segment (start 87.822252 121.852508) (end 87.843388 121.859904) (width 0.1) (layer "F.Cu") (net 259))
  (segment (start 87.422252 121.852508) (end 87.443388 121.859904) (width 0.1) (layer "F.Cu") (net 259))
  (segment (start 88.577748 123.902507) (end 88.556612 123.909903) (width 0.1) (layer "F.Cu") (net 259))
  (segment (start 88.5 122.6) (end 88.497492 122.622252) (width 0.1) (layer "F.Cu") (net 259))
  (segment (start 88.462348 122.678183) (end 88.443388 122.690096) (width 0.1) (layer "F.Cu") (net 259))
  (segment (start 87.516362 122.271761) (end 87.528238 122.283637) (width 0.1) (layer "F.Cu") (net 259))
  (segment (start 87.3 121.95) (end 87.302507 121.927748) (width 0.1) (layer "F.Cu") (net 259))
  (segment (start 87.671761 122.283637) (end 87.683637 122.271761) (width 0.1) (layer "F.Cu") (net 259))
  (segment (start 88.146598 123.622252) (end 88.153994 123.643388) (width 0.1) (layer "F.Cu") (net 259))
  (segment (start 88.200702 122.709903) (end 88.181742 122.721816) (width 0.1) (layer "F.Cu") (net 259))
  (segment (start 88.146598 122.822252) (end 88.153994 122.843388) (width 0.1) (layer "F.Cu") (net 259))
  (segment (start 88.5 124) (end 88.5 125.65) (width 0.1) (layer "F.Cu") (net 259))
  (segment (start 88.834093 123.337651) (end 88.846006 123.356611) (width 0.1) (layer "F.Cu") (net 259))
  (segment (start 87.977747 122.147493) (end 88 122.15) (width 0.1) (layer "F.Cu") (net 259))
  (segment (start 88.153994 123.156611) (end 88.146598 123.177747) (width 0.1) (layer "F.Cu") (net 259))
  (segment (start 87.3 122.25) (end 87.3 121.95) (width 0.1) (layer "F.Cu") (net 259))
  (segment (start 88.200702 122.890096) (end 88.221838 122.897492) (width 0.1) (layer "F.Cu") (net 259))
  (segment (start 88.165907 123.662348) (end 88.181742 123.678183) (width 0.1) (layer "F.Cu") (net 259))
  (segment (start 88.834093 123.737651) (end 88.846006 123.756611) (width 0.1) (layer "F.Cu") (net 259))
  (segment (start 88.146598 123.222252) (end 88.153994 123.243388) (width 0.1) (layer "F.Cu") (net 259))
  (segment (start 87.102507 122.272252) (end 87.109903 122.293388) (width 0.1) (layer "F.Cu") (net 259))
  (segment (start 88.181742 123.121816) (end 88.165907 123.137651) (width 0.1) (layer "F.Cu") (net 259))
  (segment (start 88.244091 123.5) (end 88.221838 123.502507) (width 0.1) (layer "F.Cu") (net 259))
  (segment (start 88.165907 123.137651) (end 88.153994 123.156611) (width 0.1) (layer "F.Cu") (net 259))
  (segment (start 88.818258 123.878183) (end 88.799298 123.890096) (width 0.1) (layer "F.Cu") (net 259))
  (segment (start 88.443388 122.690096) (end 88.422252 122.697492) (width 0.1) (layer "F.Cu") (net 259))
  (segment (start 88.165907 123.262348) (end 88.181742 123.278183) (width 0.1) (layer "F.Cu") (net 259))
  (segment (start 87.497492 121.927748) (end 87.5 121.95) (width 0.1) (layer "F.Cu") (net 259))
  (segment (start 88.799298 123.709903) (end 88.818258 123.721816) (width 0.1) (layer "F.Cu") (net 259))
  (segment (start 88.153994 122.843388) (end 88.165907 122.862348) (width 0.1) (layer "F.Cu") (net 259))
  (segment (start 87.777747 121.852508) (end 87.8 121.85) (width 0.1) (layer "F.Cu") (net 259))
  (segment (start 88.146598 123.577747) (end 88.144091 123.6) (width 0.1) (layer "F.Cu") (net 259))
  (segment (start 88.755909 123.3) (end 88.778162 123.302507) (width 0.1) (layer "F.Cu") (net 259))
  (segment (start 88.144091 123.2) (end 88.146598 123.222252) (width 0.1) (layer "F.Cu") (net 259))
  (segment (start 88.181742 122.878183) (end 88.200702 122.890096) (width 0.1) (layer "F.Cu") (net 259))
  (segment (start 87.698119 122.241689) (end 87.7 122.225) (width 0.1) (layer "F.Cu") (net 259))
  (segment (start 88.799298 122.909903) (end 88.818258 122.921816) (width 0.1) (layer "F.Cu") (net 259))
  (segment (start 88.221838 122.897492) (end 88.244091 122.9) (width 0.1) (layer "F.Cu") (net 259))
  (segment (start 88.853402 123.422252) (end 88.846006 123.443388) (width 0.1) (layer "F.Cu") (net 259))
  (segment (start 87.756611 121.859904) (end 87.777747 121.852508) (width 0.1) (layer "F.Cu") (net 259))
  (segment (start 88.181742 123.278183) (end 88.200702 123.290096) (width 0.1) (layer "F.Cu") (net 259))
  (segment (start 87.683637 122.271761) (end 87.692572 122.257541) (width 0.1) (layer "F.Cu") (net 259))
  (segment (start 88.818258 123.478183) (end 88.799298 123.490096) (width 0.1) (layer "F.Cu") (net 259))
  (segment (start 88.153994 123.643388) (end 88.165907 123.662348) (width 0.1) (layer "F.Cu") (net 259))
  (segment (start 88.4 122.7) (end 88.244091 122.7) (width 0.1) (layer "F.Cu") (net 259))
  (segment (start 88.834093 123.062348) (end 88.818258 123.078183) (width 0.1) (layer "F.Cu") (net 259))
  (segment (start 87.5 121.95) (end 87.5 122.225) (width 0.1) (layer "F.Cu") (net 259))
  (segment (start 88.6 123.9) (end 88.577748 123.902507) (width 0.1) (layer "F.Cu") (net 259))
  (segment (start 88.144091 123.6) (end 88.146598 123.622252) (width 0.1) (layer "F.Cu") (net 259))
  (segment (start 88.818258 123.078183) (end 88.799298 123.090096) (width 0.1) (layer "F.Cu") (net 259))
  (segment (start 88.778162 122.902507) (end 88.799298 122.909903) (width 0.1) (layer "F.Cu") (net 259))
  (segment (start 87.909903 122.093389) (end 87.921816 122.112349) (width 0.1) (layer "F.Cu") (net 259))
  (segment (start 88.853402 123.822252) (end 88.846006 123.843388) (width 0.1) (layer "F.Cu") (net 259))
  (segment (start 88.778162 123.702507) (end 88.799298 123.709903) (width 0.1) (layer "F.Cu") (net 259))
  (segment (start 88.834093 123.462348) (end 88.818258 123.478183) (width 0.1) (layer "F.Cu") (net 259))
  (segment (start 88.181742 123.521816) (end 88.165907 123.537651) (width 0.1) (layer "F.Cu") (net 259))
  (segment (start 87.290096 122.293388) (end 87.297492 122.272252) (width 0.1) (layer "F.Cu") (net 259))
  (segment (start 88.509904 123.956611) (end 88.502508 123.977747) (width 0.1) (layer "F.Cu") (net 259))
  (segment (start 88.755909 123.5) (end 88.244091 123.5) (width 0.1) (layer "F.Cu") (net 259))
  (segment (start 87.443388 121.859904) (end 87.462348 121.871817) (width 0.1) (layer "F.Cu") (net 259))
  (segment (start 87.156611 122.340096) (end 87.177747 122.347492) (width 0.1) (layer "F.Cu") (net 259))
  (segment (start 88.221838 122.702507) (end 88.200702 122.709903) (width 0.1) (layer "F.Cu") (net 259))
  (segment (start 88.200702 123.290096) (end 88.221838 123.297492) (width 0.1) (layer "F.Cu") (net 259))
  (segment (start 88.244091 122.9) (end 88.755909 122.9) (width 0.1) (layer "F.Cu") (net 259))
  (segment (start 87.243388 122.340096) (end 87.262348 122.328183) (width 0.1) (layer "F.Cu") (net 259))
  (segment (start 88.221838 123.697492) (end 88.244091 123.7) (width 0.1) (layer "F.Cu") (net 259))
  (segment (start 88.853402 123.022252) (end 88.846006 123.043388) (width 0.1) (layer "F.Cu") (net 259))
  (segment (start 88.846006 123.843388) (end 88.834093 123.862348) (width 0.1) (layer "F.Cu") (net 259))
  (segment (start 87.507427 122.257541) (end 87.516362 122.271761) (width 0.1) (layer "F.Cu") (net 259))
  (segment (start 88.755909 123.7) (end 88.778162 123.702507) (width 0.1) (layer "F.Cu") (net 259))
  (segment (start 87.109903 122.293388) (end 87.121816 122.312348) (width 0.1) (layer "F.Cu") (net 259))
  (segment (start 87.7 122.225) (end 87.7 121.95) (width 0.1) (layer "F.Cu") (net 259))
  (segment (start 87.078183 122.187651) (end 87.090096 122.206611) (width 0.1) (layer "F.Cu") (net 259))
  (segment (start 88.755909 123.1) (end 88.244091 123.1) (width 0.1) (layer "F.Cu") (net 259))
  (segment (start 87.9 121.95) (end 87.9 122.05) (width 0.1) (layer "F.Cu") (net 259))
  (segment (start 88.146598 122.777747) (end 88.144091 122.8) (width 0.1) (layer "F.Cu") (net 259))
  (segment (start 87.921816 122.112349) (end 87.937651 122.128184) (width 0.1) (layer "F.Cu") (net 259))
  (segment (start 88.153994 123.243388) (end 88.165907 123.262348) (width 0.1) (layer "F.Cu") (net 259))
  (segment (start 88.221838 123.502507) (end 88.200702 123.509903) (width 0.1) (layer "F.Cu") (net 259))
  (segment (start 88.2 122.15) (end 88.5 122.45) (width 0.1) (layer "F.Cu") (net 259))
  (segment (start 87.7 121.95) (end 87.702507 121.927748) (width 0.1) (layer "F.Cu") (net 259))
  (segment (start 88.799298 123.090096) (end 88.778162 123.097492) (width 0.1) (layer "F.Cu") (net 259))
  (segment (start 87.55831 122.298119) (end 87.575 122.3) (width 0.1) (layer "F.Cu") (net 259))
  (segment (start 88.853402 123.377747) (end 88.855909 123.4) (width 0.1) (layer "F.Cu") (net 259))
  (segment (start 94.4 126.55) (end 94 126.15) (width 0.15) (layer "F.Cu") (net 259))
  (segment (start 88.521817 123.937651) (end 88.509904 123.956611) (width 0.1) (layer "F.Cu") (net 259))
  (segment (start 88 122.15) (end 88.2 122.15) (width 0.1) (layer "F.Cu") (net 259))
  (segment (start 88.778162 123.497492) (end 88.755909 123.5) (width 0.1) (layer "F.Cu") (net 259))
  (segment (start 87.641689 122.298119) (end 87.657541 122.292572) (width 0.1) (layer "F.Cu") (net 259))
  (segment (start 88.755909 123.9) (end 88.6 123.9) (width 0.1) (layer "F.Cu") (net 259))
  (segment (start 88.181742 122.721816) (end 88.165907 122.737651) (width 0.1) (layer "F.Cu") (net 259))
  (segment (start 87.897492 121.927748) (end 87.9 121.95) (width 0.1) (layer "F.Cu") (net 259))
  (segment (start 88.818258 123.721816) (end 88.834093 123.737651) (width 0.1) (layer "F.Cu") (net 259))
  (segment (start 87.937651 122.128184) (end 87.956611 122.140097) (width 0.1) (layer "F.Cu") (net 259))
  (segment (start 88.778162 123.302507) (end 88.799298 123.309903) (width 0.1) (layer "F.Cu") (net 259))
  (segment (start 87.902507 122.072253) (end 87.909903 122.093389) (width 0.1) (layer "F.Cu") (net 259))
  (segment (start 87.137651 122.328183) (end 87.156611 122.340096) (width 0.1) (layer "F.Cu") (net 259))
  (segment (start 87.737651 121.871817) (end 87.756611 121.859904) (width 0.1) (layer "F.Cu") (net 259))
  (segment (start 87.302507 121.927748) (end 87.309903 121.906612) (width 0.1) (layer "F.Cu") (net 259))
  (segment (start 87.097492 122.227747) (end 87.102507 122.272252) (width 0.1) (layer "F.Cu") (net 259))
  (segment (start 88.502508 123.977747) (end 88.5 124) (width 0.1) (layer "F.Cu") (net 259))
  (segment (start 87.121816 122.312348) (end 87.137651 122.328183) (width 0.1) (layer "F.Cu") (net 259))
  (segment (start 87.702507 121.927748) (end 87.709903 121.906612) (width 0.1) (layer "F.Cu") (net 259))
  (segment (start 88.244091 122.7) (end 88.221838 122.702507) (width 0.1) (layer "F.Cu") (net 259))
  (segment (start 88.778162 123.897492) (end 88.755909 123.9) (width 0.1) (layer "F.Cu") (net 259))
  (segment (start 88.853402 123.777747) (end 88.855909 123.8) (width 0.1) (layer "F.Cu") (net 259))
  (segment (start 88.846006 123.043388) (end 88.834093 123.062348) (width 0.1) (layer "F.Cu") (net 259))
  (segment (start 87.377747 121.852508) (end 87.4 121.85) (width 0.1) (layer "F.Cu") (net 259))
  (segment (start 88.244091 123.3) (end 88.755909 123.3) (width 0.1) (layer "F.Cu") (net 259))
  (segment (start 87.9 122.05) (end 87.902507 122.072253) (width 0.1) (layer "F.Cu") (net 259))
  (segment (start 88.165907 122.862348) (end 88.181742 122.878183) (width 0.1) (layer "F.Cu") (net 259))
  (segment (start 88.146598 123.177747) (end 88.144091 123.2) (width 0.1) (layer "F.Cu") (net 259))
  (segment (start 87.062348 122.171816) (end 87.078183 122.187651) (width 0.1) (layer "F.Cu") (net 259))
  (segment (start 87.222252 122.347492) (end 87.243388 122.340096) (width 0.1) (layer "F.Cu") (net 259))
  (segment (start 87.321816 121.887652) (end 87.337651 121.871817) (width 0.1) (layer "F.Cu") (net 259))
  (segment (start 88.799298 123.890096) (end 88.778162 123.897492) (width 0.1) (layer "F.Cu") (net 259))
  (segment (start 88.818258 123.321816) (end 88.834093 123.337651) (width 0.1) (layer "F.Cu") (net 259))
  (via blind (at 94 126.15) (size 0.5) (drill 0.2) (layers "F.Cu" "In2.Cu") (net 259))
  (via (at 88.5 125.65) (size 0.5) (drill 0.2) (layers "F.Cu" "B.Cu") (net 259))
  (segment (start 94 126.15) (end 93.6 125.75) (width 0.1) (layer "In2.Cu") (net 259))
  (segment (start 91.65 125.75) (end 91.35 126.05) (width 0.1) (layer "In2.Cu") (net 259))
  (segment (start 93.6 125.75) (end 91.65 125.75) (width 0.1) (layer "In2.Cu") (net 259))
  (segment (start 88.9 126.05) (end 88.5 125.65) (width 0.1) (layer "In2.Cu") (net 259))
  (segment (start 91.35 126.05) (end 88.9 126.05) (width 0.1) (layer "In2.Cu") (net 259))
  (segment (start 87.445 123.695) (end 86.49 123.695) (width 0.1) (layer "B.Cu") (net 259))
  (segment (start 88.5 124.75) (end 87.445 123.695) (width 0.1) (layer "B.Cu") (net 259))
  (segment (start 88.5 124.75) (end 88.5 125.65) (width 0.1) (layer "B.Cu") (net 259))
  (segment (start 79.885 122.555) (end 79.895 122.555) (width 0.1) (layer "F.Cu") (net 260))
  (segment (start 79.895 122.555) (end 80.3 122.15) (width 0.1) (layer "F.Cu") (net 260))
  (segment (start 92 123.35) (end 91.6 122.95) (width 0.15) (layer "F.Cu") (net 260))
  (via (at 91.6 122.95) (size 0.5) (drill 0.2) (layers "F.Cu" "B.Cu") (net 260))
  (via (at 79.885 122.555) (size 0.5) (drill 0.2) (layers "F.Cu" "B.Cu") (net 260))
  (segment (start 88.459903 122.806612) (end 88.471816 122.787652) (width 0.1) (layer "In2.Cu") (net 260))
  (segment (start 88.240096 123.006611) (end 88.247492 123.027747) (width 0.1) (layer "In2.Cu") (net 260))
  (segment (start 81.131611 122.682399) (end 81.152747 122.675003) (width 0.1) (layer "In2.Cu") (net 260))
  (segment (start 81.331611 123.367601) (end 81.352747 123.374997) (width 0.1) (layer "In2.Cu") (net 260))
  (segment (start 81.352747 123.374997) (end 81.375 123.377505) (width 0.1) (layer "In2.Cu") (net 260))
  (segment (start 81.512651 122.544312) (end 81.531611 122.532399) (width 0.1) (layer "In2.Cu") (net 260))
  (segment (start 88.572252 122.752508) (end 88.593388 122.759904) (width 0.1) (layer "In2.Cu") (net 260))
  (segment (start 88.927747 122.952507) (end 88.95 122.95) (width 0.1) (layer "In2.Cu") (net 260))
  (segment (start 88.506611 122.759904) (end 88.527747 122.752508) (width 0.1) (layer "In2.Cu") (net 260))
  (segment (start 88.247492 123.027747) (end 88.252507 123.072252) (width 0.1) (layer "In2.Cu") (net 260))
  (segment (start 81.884903 123.006611) (end 81.896816 122.987651) (width 0.1) (layer "In2.Cu") (net 260))
  (segment (start 88.652507 123.072252) (end 88.659903 123.093388) (width 0.1) (layer "In2.Cu") (net 260))
  (segment (start 81.237348 122.694312) (end 81.253183 122.710147) (width 0.1) (layer "In2.Cu") (net 260))
  (segment (start 81.112651 122.694312) (end 81.131611 122.682399) (width 0.1) (layer "In2.Cu") (net 260))
  (segment (start 80.864623 122.961662) (end 80.865376 122.968337) (width 0.1) (layer "In2.Cu") (net 260))
  (segment (start 81.275 122.772495) (end 81.275 123.277505) (width 0.1) (layer "In2.Cu") (net 260))
  (segment (start 81.065 122.965) (end 81.065 122.95) (width 0.1) (layer "In2.Cu") (net 260))
  (segment (start 88.428183 123.112348) (end 88.440096 123.093388) (width 0.1) (layer "In2.Cu") (net 260))
  (segment (start 80.873491 122.978514) (end 80.876662 122.979623) (width 0.1) (layer "In2.Cu") (net 260))
  (segment (start 88.75 123.15) (end 88.772252 123.147492) (width 0.1) (layer "In2.Cu") (net 260))
  (segment (start 81.496816 122.560147) (end 81.512651 122.544312) (width 0.1) (layer "In2.Cu") (net 260))
  (segment (start 81.775 123.377505) (end 81.797252 123.374997) (width 0.1) (layer "In2.Cu") (net 260))
  (segment (start 88.847492 123.072252) (end 88.852507 123.027747) (width 0.1) (layer "In2.Cu") (net 260))
  (segment (start 81.975 122.95) (end 82.125 122.95) (width 0.1) (layer "In2.Cu") (net 260))
  (segment (start 81.05 122.98) (end 81.053337 122.979623) (width 0.1) (layer "In2.Cu") (net 260))
  (segment (start 81.096816 122.710147) (end 81.112651 122.694312) (width 0.1) (layer "In2.Cu") (net 260))
  (segment (start 81.272492 122.750243) (end 81.275 122.772495) (width 0.1) (layer "In2.Cu") (net 260))
  (segment (start 81.375 123.377505) (end 81.397252 123.374997) (width 0.1) (layer "In2.Cu") (net 260))
  (segment (start 81.253183 122.710147) (end 81.265096 122.729107) (width 0.1) (layer "In2.Cu") (net 260))
  (segment (start 80.861727 122.955647) (end 80.863514 122.958491) (width 0.1) (layer "In2.Cu") (net 260))
  (segment (start 81.064623 122.968337) (end 81.065 122.965) (width 0.1) (layer "In2.Cu") (net 260))
  (segment (start 81.675 123.277505) (end 81.677507 123.299757) (width 0.1) (layer "In2.Cu") (net 260))
  (segment (start 81.418388 123.367601) (end 81.437348 123.355688) (width 0.1) (layer "In2.Cu") (net 260))
  (segment (start 81.084903 122.729107) (end 81.096816 122.710147) (width 0.1) (layer "In2.Cu") (net 260))
  (segment (start 80.863514 122.958491) (end 80.864623 122.961662) (width 0.1) (layer "In2.Cu") (net 260))
  (segment (start 88.793388 123.140096) (end 88.812348 123.128183) (width 0.1) (layer "In2.Cu") (net 260))
  (segment (start 88.95 122.95) (end 91.6 122.95) (width 0.1) (layer "In2.Cu") (net 260))
  (segment (start 81.877507 123.027747) (end 81.884903 123.006611) (width 0.1) (layer "In2.Cu") (net 260))
  (segment (start 88.471816 122.787652) (end 88.487651 122.771817) (width 0.1) (layer "In2.Cu") (net 260))
  (segment (start 81.872492 123.299757) (end 81.875 123.277505) (width 0.1) (layer "In2.Cu") (net 260))
  (segment (start 81.397252 123.374997) (end 81.418388 123.367601) (width 0.1) (layer "In2.Cu") (net 260))
  (segment (start 81.853183 123.339853) (end 81.865096 123.320893) (width 0.1) (layer "In2.Cu") (net 260))
  (segment (start 88.45 122.85) (end 88.452507 122.827748) (width 0.1) (layer "In2.Cu") (net 260))
  (segment (start 81.077507 122.750243) (end 81.084903 122.729107) (width 0.1) (layer "In2.Cu") (net 260))
  (segment (start 88.35 123.15) (end 88.372252 123.147492) (width 0.1) (layer "In2.Cu") (net 260))
  (segment (start 81.475 122.622495) (end 81.477507 122.600243) (width 0.1) (layer "In2.Cu") (net 260))
  (segment (start 88.55 122.75) (end 88.572252 122.752508) (width 0.1) (layer "In2.Cu") (net 260))
  (segment (start 88.640096 122.806612) (end 88.647492 122.827748) (width 0.1) (layer "In2.Cu") (net 260))
  (segment (start 81.675 122.622495) (end 81.675 123.277505) (width 0.1) (layer "In2.Cu") (net 260))
  (segment (start 81.637348 122.544312) (end 81.653183 122.560147) (width 0.1) (layer "In2.Cu") (net 260))
  (segment (start 88.327747 123.147492) (end 88.35 123.15) (width 0.1) (layer "In2.Cu") (net 260))
  (segment (start 81.752747 123.374997) (end 81.775 123.377505) (width 0.1) (layer "In2.Cu") (net 260))
  (segment (start 88.859903 123.006611) (end 88.871816 122.987651) (width 0.1) (layer "In2.Cu") (net 260))
  (segment (start 88.727747 123.147492) (end 88.75 123.15) (width 0.1) (layer "In2.Cu") (net 260))
  (segment (start 88.393388 123.140096) (end 88.412348 123.128183) (width 0.1) (layer "In2.Cu") (net 260))
  (segment (start 88.772252 123.147492) (end 88.793388 123.140096) (width 0.1) (layer "In2.Cu") (net 260))
  (segment (start 88.193388 122.959903) (end 88.212348 122.971816) (width 0.1) (layer "In2.Cu") (net 260))
  (segment (start 80.856508 122.951485) (end 80.859352 122.953272) (width 0.1) (layer "In2.Cu") (net 260))
  (segment (start 81.797252 123.374997) (end 81.818388 123.367601) (width 0.1) (layer "In2.Cu") (net 260))
  (segment (start 80.865376 122.968337) (end 80.866485 122.971508) (width 0.1) (layer "In2.Cu") (net 260))
  (segment (start 81.065 122.95) (end 81.075 122.95) (width 0.1) (layer "In2.Cu") (net 260))
  (segment (start 81.912651 122.971816) (end 81.931611 122.959903) (width 0.1) (layer "In2.Cu") (net 260))
  (segment (start 81.075 122.95) (end 81.075 122.772495) (width 0.1) (layer "In2.Cu") (net 260))
  (segment (start 88.852507 123.027747) (end 88.859903 123.006611) (width 0.1) (layer "In2.Cu") (net 260))
  (segment (start 80.28 122.95) (end 80.85 122.95) (width 0.1) (layer "In2.Cu") (net 260))
  (segment (start 81.075 122.772495) (end 81.077507 122.750243) (width 0.1) (layer "In2.Cu") (net 260))
  (segment (start 88.487651 122.771817) (end 88.506611 122.759904) (width 0.1) (layer "In2.Cu") (net 260))
  (segment (start 81.531611 122.532399) (end 81.552747 122.525003) (width 0.1) (layer "In2.Cu") (net 260))
  (segment (start 81.472492 123.299757) (end 81.475 123.277505) (width 0.1) (layer "In2.Cu") (net 260))
  (segment (start 88.840096 123.093388) (end 88.847492 123.072252) (width 0.1) (layer "In2.Cu") (net 260))
  (segment (start 88.671816 123.112348) (end 88.687651 123.128183) (width 0.1) (layer "In2.Cu") (net 260))
  (segment (start 81.818388 123.367601) (end 81.837348 123.355688) (width 0.1) (layer "In2.Cu") (net 260))
  (segment (start 81.684903 123.320893) (end 81.696816 123.339853) (width 0.1) (layer "In2.Cu") (net 260))
  (segment (start 80.85 122.95) (end 80.853337 122.950376) (width 0.1) (layer "In2.Cu") (net 260))
  (segment (start 81.284903 123.320893) (end 81.296816 123.339853) (width 0.1) (layer "In2.Cu") (net 260))
  (segment (start 81.597252 122.525003) (end 81.618388 122.532399) (width 0.1) (layer "In2.Cu") (net 260))
  (segment (start 88.906611 122.959903) (end 88.927747 122.952507) (width 0.1) (layer "In2.Cu") (net 260))
  (segment (start 88.706611 123.140096) (end 88.727747 123.147492) (width 0.1) (layer "In2.Cu") (net 260))
  (segment (start 81.277507 123.299757) (end 81.284903 123.320893) (width 0.1) (layer "In2.Cu") (net 260))
  (segment (start 88.372252 123.147492) (end 88.393388 123.140096) (width 0.1) (layer "In2.Cu") (net 260))
  (segment (start 81.896816 122.987651) (end 81.912651 122.971816) (width 0.1) (layer "In2.Cu") (net 260))
  (segment (start 81.453183 123.339853) (end 81.465096 123.320893) (width 0.1) (layer "In2.Cu") (net 260))
  (segment (start 81.618388 122.532399) (end 81.637348 122.544312) (width 0.1) (layer "In2.Cu") (net 260))
  (segment (start 81.653183 122.560147) (end 81.665096 122.579107) (width 0.1) (layer "In2.Cu") (net 260))
  (segment (start 81.875 123.05) (end 81.877507 123.027747) (width 0.1) (layer "In2.Cu") (net 260))
  (segment (start 81.475 123.277505) (end 81.475 122.622495) (width 0.1) (layer "In2.Cu") (net 260))
  (segment (start 88.828183 123.112348) (end 88.840096 123.093388) (width 0.1) (layer "In2.Cu") (net 260))
  (segment (start 81.731611 123.367601) (end 81.752747 123.374997) (width 0.1) (layer "In2.Cu") (net 260))
  (segment (start 80.859352 122.953272) (end 80.861727 122.955647) (width 0.1) (layer "In2.Cu") (net 260))
  (segment (start 88.659903 123.093388) (end 88.671816 123.112348) (width 0.1) (layer "In2.Cu") (net 260))
  (segment (start 88.527747 122.752508) (end 88.55 122.75) (width 0.1) (layer "In2.Cu") (net 260))
  (segment (start 81.665096 122.579107) (end 81.672492 122.600243) (width 0.1) (layer "In2.Cu") (net 260))
  (segment (start 88.593388 122.759904) (end 88.612348 122.771817) (width 0.1) (layer "In2.Cu") (net 260))
  (segment (start 81.672492 122.600243) (end 81.675 122.622495) (width 0.1) (layer "In2.Cu") (net 260))
  (segment (start 81.197252 122.675003) (end 81.218388 122.682399) (width 0.1) (layer "In2.Cu") (net 260))
  (segment (start 81.477507 122.600243) (end 81.484903 122.579107) (width 0.1) (layer "In2.Cu") (net 260))
  (segment (start 81.875 123.277505) (end 81.875 123.05) (width 0.1) (layer "In2.Cu") (net 260))
  (segment (start 81.053337 122.979623) (end 81.056508 122.978514) (width 0.1) (layer "In2.Cu") (net 260))
  (segment (start 88.252507 123.072252) (end 88.259903 123.093388) (width 0.1) (layer "In2.Cu") (net 260))
  (segment (start 81.837348 123.355688) (end 81.853183 123.339853) (width 0.1) (layer "In2.Cu") (net 260))
  (segment (start 88.812348 123.128183) (end 88.828183 123.112348) (width 0.1) (layer "In2.Cu") (net 260))
  (segment (start 81.152747 122.675003) (end 81.175 122.672495) (width 0.1) (layer "In2.Cu") (net 260))
  (segment (start 81.677507 123.299757) (end 81.684903 123.320893) (width 0.1) (layer "In2.Cu") (net 260))
  (segment (start 88.212348 122.971816) (end 88.228183 122.987651) (width 0.1) (layer "In2.Cu") (net 260))
  (segment (start 82.125 122.95) (end 82.325 123.15) (width 0.1) (layer "In2.Cu") (net 260))
  (segment (start 88.172252 122.952507) (end 88.193388 122.959903) (width 0.1) (layer "In2.Cu") (net 260))
  (segment (start 81.265096 122.729107) (end 81.272492 122.750243) (width 0.1) (layer "In2.Cu") (net 260))
  (segment (start 81.296816 123.339853) (end 81.312651 123.355688) (width 0.1) (layer "In2.Cu") (net 260))
  (segment (start 88.452507 122.827748) (end 88.459903 122.806612) (width 0.1) (layer "In2.Cu") (net 260))
  (segment (start 88.447492 123.072252) (end 88.45 123.05) (width 0.1) (layer "In2.Cu") (net 260))
  (segment (start 88.65 122.85) (end 88.65 123.05) (width 0.1) (layer "In2.Cu") (net 260))
  (segment (start 81.218388 122.682399) (end 81.237348 122.694312) (width 0.1) (layer "In2.Cu") (net 260))
  (segment (start 88.65 123.05) (end 88.652507 123.072252) (width 0.1) (layer "In2.Cu") (net 260))
  (segment (start 88.306611 123.140096) (end 88.327747 123.147492) (width 0.1) (layer "In2.Cu") (net 260))
  (segment (start 81.952747 122.952507) (end 81.975 122.95) (width 0.1) (layer "In2.Cu") (net 260))
  (segment (start 88.687651 123.128183) (end 88.706611 123.140096) (width 0.1) (layer "In2.Cu") (net 260))
  (segment (start 81.712651 123.355688) (end 81.731611 123.367601) (width 0.1) (layer "In2.Cu") (net 260))
  (segment (start 88.45 123.05) (end 88.45 122.85) (width 0.1) (layer "In2.Cu") (net 260))
  (segment (start 80.88 122.98) (end 81.05 122.98) (width 0.1) (layer "In2.Cu") (net 260))
  (segment (start 88.871816 122.987651) (end 88.887651 122.971816) (width 0.1) (layer "In2.Cu") (net 260))
  (segment (start 81.061727 122.974352) (end 81.063514 122.971508) (width 0.1) (layer "In2.Cu") (net 260))
  (segment (start 88.287651 123.128183) (end 88.306611 123.140096) (width 0.1) (layer "In2.Cu") (net 260))
  (segment (start 81.312651 123.355688) (end 81.331611 123.367601) (width 0.1) (layer "In2.Cu") (net 260))
  (segment (start 79.885 122.555) (end 80.28 122.95) (width 0.1) (layer "In2.Cu") (net 260))
  (segment (start 88.259903 123.093388) (end 88.271816 123.112348) (width 0.1) (layer "In2.Cu") (net 260))
  (segment (start 81.575 122.522495) (end 81.597252 122.525003) (width 0.1) (layer "In2.Cu") (net 260))
  (segment (start 80.866485 122.971508) (end 80.868272 122.974352) (width 0.1) (layer "In2.Cu") (net 260))
  (segment (start 81.063514 122.971508) (end 81.064623 122.968337) (width 0.1) (layer "In2.Cu") (net 260))
  (segment (start 81.059352 122.976727) (end 81.061727 122.974352) (width 0.1) (layer "In2.Cu") (net 260))
  (segment (start 81.056508 122.978514) (end 81.059352 122.976727) (width 0.1) (layer "In2.Cu") (net 260))
  (segment (start 81.465096 123.320893) (end 81.472492 123.299757) (width 0.1) (layer "In2.Cu") (net 260))
  (segment (start 81.865096 123.320893) (end 81.872492 123.299757) (width 0.1) (layer "In2.Cu") (net 260))
  (segment (start 80.876662 122.979623) (end 80.88 122.98) (width 0.1) (layer "In2.Cu") (net 260))
  (segment (start 80.853337 122.950376) (end 80.856508 122.951485) (width 0.1) (layer "In2.Cu") (net 260))
  (segment (start 81.696816 123.339853) (end 81.712651 123.355688) (width 0.1) (layer "In2.Cu") (net 260))
  (segment (start 81.484903 122.579107) (end 81.496816 122.560147) (width 0.1) (layer "In2.Cu") (net 260))
  (segment (start 80.870647 122.976727) (end 80.873491 122.978514) (width 0.1) (layer "In2.Cu") (net 260))
  (segment (start 88.412348 123.128183) (end 88.428183 123.112348) (width 0.1) (layer "In2.Cu") (net 260))
  (segment (start 80.868272 122.974352) (end 80.870647 122.976727) (width 0.1) (layer "In2.Cu") (net 260))
  (segment (start 81.175 122.672495) (end 81.197252 122.675003) (width 0.1) (layer "In2.Cu") (net 260))
  (segment (start 88.440096 123.093388) (end 88.447492 123.072252) (width 0.1) (layer "In2.Cu") (net 260))
  (segment (start 88.612348 122.771817) (end 88.628183 122.787652) (width 0.1) (layer "In2.Cu") (net 260))
  (segment (start 88.628183 122.787652) (end 88.640096 122.806612) (width 0.1) (layer "In2.Cu") (net 260))
  (segment (start 88.647492 122.827748) (end 88.65 122.85) (width 0.1) (layer "In2.Cu") (net 260))
  (segment (start 87.7675 123.15) (end 87.9675 122.95) (width 0.1) (layer "In2.Cu") (net 260))
  (segment (start 81.931611 122.959903) (end 81.952747 122.952507) (width 0.1) (layer "In2.Cu") (net 260))
  (segment (start 87.9675 122.95) (end 88.15 122.95) (width 0.1) (layer "In2.Cu") (net 260))
  (segment (start 82.325 123.15) (end 87.7675 123.15) (width 0.1) (layer "In2.Cu") (net 260))
  (segment (start 88.15 122.95) (end 88.172252 122.952507) (width 0.1) (layer "In2.Cu") (net 260))
  (segment (start 81.552747 122.525003) (end 81.575 122.522495) (width 0.1) (layer "In2.Cu") (net 260))
  (segment (start 88.271816 123.112348) (end 88.287651 123.128183) (width 0.1) (layer "In2.Cu") (net 260))
  (segment (start 88.887651 122.971816) (end 88.906611 122.959903) (width 0.1) (layer "In2.Cu") (net 260))
  (segment (start 88.228183 122.987651) (end 88.240096 123.006611) (width 0.1) (layer "In2.Cu") (net 260))
  (segment (start 81.437348 123.355688) (end 81.453183 123.339853) (width 0.1) (layer "In2.Cu") (net 260))
  (segment (start 81.275 123.277505) (end 81.277507 123.299757) (width 0.1) (layer "In2.Cu") (net 260))
  (segment (start 79.885 122.555) (end 79.885 121.585) (width 0.1) (layer "B.Cu") (net 260))
  (segment (start 82.25 122.95) (end 81.9 122.95) (width 0.1) (layer "F.Cu") (net 261))
  (segment (start 82.5 122.7) (end 82.25 122.95) (width 0.1) (layer "F.Cu") (net 261))
  (segment (start 95.2 118.55) (end 94.8 118.95) (width 0.1) (layer "F.Cu") (net 261))
  (via (at 94.8 118.95) (size 0.5) (drill 0.2) (layers "F.Cu" "B.Cu") (net 261))
  (via (at 82.5 122.7) (size 0.5) (drill 0.2) (layers "F.Cu" "B.Cu") (net 261))
  (segment (start 83.551296 121.625) (end 83.554568 121.621727) (width 0.1) (layer "B.Cu") (net 261))
  (segment (start 83.52657 121.42544) (end 83.52657 121.403566) (width 0.1) (layer "B.Cu") (net 261))
  (segment (start 92.2 119.65) (end 92.8 120.25) (width 0.1) (layer "B.Cu") (net 261))
  (segment (start 90.65 120.2) (end 91.2 119.65) (width 0.1) (layer "B.Cu") (net 261))
  (segment (start 94.55 119.2) (end 94.8 118.95) (width 0.1) (layer "B.Cu") (net 261))
  (segment (start 84.7 120.2) (end 90.65 120.2) (width 0.1) (layer "B.Cu") (net 261))
  (segment (start 93.5 120.25) (end 93.7 120.05) (width 0.1) (layer "B.Cu") (net 261))
  (segment (start 83.920695 121.031318) (end 83.942022 121.036186) (width 0.1) (layer "B.Cu") (net 261))
  (segment (start 83.396046 121.611361) (end 83.43025 121.638638) (width 0.1) (layer "B.Cu") (net 261))
  (segment (start 83.865407 121.258873) (end 83.86054 121.237547) (width 0.1) (layer "B.Cu") (net 261))
  (segment (start 83.557842 121.342158) (end 83.574944 121.328519) (width 0.1) (layer "B.Cu") (net 261))
  (segment (start 83.678888 121.328519) (end 83.713092 121.355796) (width 0.1) (layer "B.Cu") (net 261))
  (segment (start 83.568207 121.604625) (end 83.577698 121.584916) (width 0.1) (layer "B.Cu") (net 261))
  (segment (start 83.582565 121.541715) (end 83.577698 121.520389) (width 0.1) (layer "B.Cu") (net 261))
  (segment (start 83.149999 122.050001) (end 83.15 121.75) (width 0.1) (layer "B.Cu") (net 261))
  (segment (start 83.86054 121.237547) (end 83.851049 121.217838) (width 0.1) (layer "B.Cu") (net 261))
  (segment (start 83.594652 121.319028) (end 83.615979 121.31416) (width 0.1) (layer "B.Cu") (net 261))
  (segment (start 83.823771 121.079689) (end 83.83741 121.062587) (width 0.1) (layer "B.Cu") (net 261))
  (segment (start 84.11698 121.059316) (end 84.120252 121.056043) (width 0.1) (layer "B.Cu") (net 261))
  (segment (start 93.7 120.05) (end 94.3 120.05) (width 0.1) (layer "B.Cu") (net 261))
  (segment (start 83.15 121.75) (end 83.275 121.625) (width 0.1) (layer "B.Cu") (net 261))
  (segment (start 83.531438 121.446767) (end 83.52657 121.42544) (width 0.1) (layer "B.Cu") (net 261))
  (segment (start 92.8 120.25) (end 93.5 120.25) (width 0.1) (layer "B.Cu") (net 261))
  (segment (start 83.554568 121.621727) (end 83.568207 121.604625) (width 0.1) (layer "B.Cu") (net 261))
  (segment (start 83.574944 121.328519) (end 83.594652 121.319028) (width 0.1) (layer "B.Cu") (net 261))
  (segment (start 84.143382 121.019232) (end 84.148249 120.997906) (width 0.1) (layer "B.Cu") (net 261))
  (segment (start 84.123526 120.776473) (end 84.7 120.2) (width 0.1) (layer "B.Cu") (net 261))
  (segment (start 84.058843 121.087313) (end 84.08017 121.082445) (width 0.1) (layer "B.Cu") (net 261))
  (segment (start 84.097122 120.881083) (end 84.092254 120.859756) (width 0.1) (layer "B.Cu") (net 261))
  (segment (start 83.83741 121.062587) (end 83.840684 121.059316) (width 0.1) (layer "B.Cu") (net 261))
  (segment (start 84.099878 121.072954) (end 84.11698 121.059316) (width 0.1) (layer "B.Cu") (net 261))
  (segment (start 83.471285 121.652997) (end 83.493159 121.652997) (width 0.1) (layer "B.Cu") (net 261))
  (segment (start 83.865407 121.280748) (end 83.865407 121.258873) (width 0.1) (layer "B.Cu") (net 261))
  (segment (start 83.834138 121.342158) (end 83.83741 121.338885) (width 0.1) (layer "B.Cu") (net 261))
  (segment (start 83.81428 121.099397) (end 83.823771 121.079689) (width 0.1) (layer "B.Cu") (net 261))
  (segment (start 83.577698 121.584916) (end 83.582565 121.56359) (width 0.1) (layer "B.Cu") (net 261))
  (segment (start 84.036969 121.087313) (end 84.058843 121.087313) (width 0.1) (layer "B.Cu") (net 261))
  (segment (start 84.015642 121.082445) (end 84.036969 121.087313) (width 0.1) (layer "B.Cu") (net 261))
  (segment (start 84.148249 120.997906) (end 84.148249 120.976031) (width 0.1) (layer "B.Cu") (net 261))
  (segment (start 83.355011 121.597002) (end 83.376338 121.60187) (width 0.1) (layer "B.Cu") (net 261))
  (segment (start 84.106613 120.900791) (end 84.097122 120.881083) (width 0.1) (layer "B.Cu") (net 261))
  (segment (start 83.809412 121.120724) (end 83.81428 121.099397) (width 0.1) (layer "B.Cu") (net 261))
  (segment (start 82.5 122.7) (end 83.149999 122.050001) (width 0.1) (layer "B.Cu") (net 261))
  (segment (start 83.809412 121.142598) (end 83.809412 121.120724) (width 0.1) (layer "B.Cu") (net 261))
  (segment (start 83.83741 121.338885) (end 83.851049 121.321783) (width 0.1) (layer "B.Cu") (net 261))
  (segment (start 83.333137 121.597002) (end 83.355011 121.597002) (width 0.1) (layer "B.Cu") (net 261))
  (segment (start 84.133891 121.038941) (end 84.143382 121.019232) (width 0.1) (layer "B.Cu") (net 261))
  (segment (start 83.514486 121.648129) (end 83.534194 121.638638) (width 0.1) (layer "B.Cu") (net 261))
  (segment (start 84.092254 120.837882) (end 84.097122 120.816555) (width 0.1) (layer "B.Cu") (net 261))
  (segment (start 83.31181 121.60187) (end 83.333137 121.597002) (width 0.1) (layer "B.Cu") (net 261))
  (segment (start 83.776001 121.370155) (end 83.797328 121.365287) (width 0.1) (layer "B.Cu") (net 261))
  (segment (start 94.55 119.8) (end 94.55 119.2) (width 0.1) (layer "B.Cu") (net 261))
  (segment (start 84.08017 121.082445) (end 84.099878 121.072954) (width 0.1) (layer "B.Cu") (net 261))
  (segment (start 83.713092 121.355796) (end 83.7328 121.365287) (width 0.1) (layer "B.Cu") (net 261))
  (segment (start 83.554568 121.345429) (end 83.557842 121.342158) (width 0.1) (layer "B.Cu") (net 261))
  (segment (start 83.96173 121.045677) (end 83.995934 121.072954) (width 0.1) (layer "B.Cu") (net 261))
  (segment (start 83.43025 121.638638) (end 83.449958 121.648129) (width 0.1) (layer "B.Cu") (net 261))
  (segment (start 83.7328 121.365287) (end 83.754127 121.370155) (width 0.1) (layer "B.Cu") (net 261))
  (segment (start 83.851049 121.217838) (end 83.823771 121.183633) (width 0.1) (layer "B.Cu") (net 261))
  (segment (start 82.5 123.1) (end 82.005 123.595) (width 0.1) (layer "B.Cu") (net 261))
  (segment (start 84.120252 120.779745) (end 84.123526 120.776473) (width 0.1) (layer "B.Cu") (net 261))
  (segment (start 83.52657 121.403566) (end 83.531438 121.382239) (width 0.1) (layer "B.Cu") (net 261))
  (segment (start 83.540929 121.362531) (end 83.554568 121.345429) (width 0.1) (layer "B.Cu") (net 261))
  (segment (start 83.577698 121.520389) (end 83.568207 121.50068) (width 0.1) (layer "B.Cu") (net 261))
  (segment (start 83.86054 121.302074) (end 83.865407 121.280748) (width 0.1) (layer "B.Cu") (net 261))
  (segment (start 83.754127 121.370155) (end 83.776001 121.370155) (width 0.1) (layer "B.Cu") (net 261))
  (segment (start 83.582565 121.56359) (end 83.582565 121.541715) (width 0.1) (layer "B.Cu") (net 261))
  (segment (start 83.857786 121.045677) (end 83.877494 121.036186) (width 0.1) (layer "B.Cu") (net 261))
  (segment (start 83.376338 121.60187) (end 83.396046 121.611361) (width 0.1) (layer "B.Cu") (net 261))
  (segment (start 83.531438 121.382239) (end 83.540929 121.362531) (width 0.1) (layer "B.Cu") (net 261))
  (segment (start 84.097122 120.816555) (end 84.106613 120.796847) (width 0.1) (layer "B.Cu") (net 261))
  (segment (start 83.797328 121.365287) (end 83.817036 121.355796) (width 0.1) (layer "B.Cu") (net 261))
  (segment (start 83.898821 121.031318) (end 83.920695 121.031318) (width 0.1) (layer "B.Cu") (net 261))
  (segment (start 83.65918 121.319028) (end 83.678888 121.328519) (width 0.1) (layer "B.Cu") (net 261))
  (segment (start 83.615979 121.31416) (end 83.637853 121.31416) (width 0.1) (layer "B.Cu") (net 261))
  (segment (start 84.106613 120.796847) (end 84.120252 120.779745) (width 0.1) (layer "B.Cu") (net 261))
  (segment (start 83.877494 121.036186) (end 83.898821 121.031318) (width 0.1) (layer "B.Cu") (net 261))
  (segment (start 83.942022 121.036186) (end 83.96173 121.045677) (width 0.1) (layer "B.Cu") (net 261))
  (segment (start 83.540929 121.466475) (end 83.531438 121.446767) (width 0.1) (layer "B.Cu") (net 261))
  (segment (start 83.995934 121.072954) (end 84.015642 121.082445) (width 0.1) (layer "B.Cu") (net 261))
  (segment (start 83.840684 121.059316) (end 83.857786 121.045677) (width 0.1) (layer "B.Cu") (net 261))
  (segment (start 91.2 119.65) (end 92.2 119.65) (width 0.1) (layer "B.Cu") (net 261))
  (segment (start 84.120252 121.056043) (end 84.133891 121.038941) (width 0.1) (layer "B.Cu") (net 261))
  (segment (start 84.148249 120.976031) (end 84.143382 120.954705) (width 0.1) (layer "B.Cu") (net 261))
  (segment (start 84.133891 120.934996) (end 84.106613 120.900791) (width 0.1) (layer "B.Cu") (net 261))
  (segment (start 83.851049 121.321783) (end 83.86054 121.302074) (width 0.1) (layer "B.Cu") (net 261))
  (segment (start 83.493159 121.652997) (end 83.514486 121.648129) (width 0.1) (layer "B.Cu") (net 261))
  (segment (start 83.817036 121.355796) (end 83.834138 121.342158) (width 0.1) (layer "B.Cu") (net 261))
  (segment (start 83.292102 121.611361) (end 83.31181 121.60187) (width 0.1) (layer "B.Cu") (net 261))
  (segment (start 83.449958 121.648129) (end 83.471285 121.652997) (width 0.1) (layer "B.Cu") (net 261))
  (segment (start 83.81428 121.163925) (end 83.809412 121.142598) (width 0.1) (layer "B.Cu") (net 261))
  (segment (start 83.275 121.625) (end 83.292102 121.611361) (width 0.1) (layer "B.Cu") (net 261))
  (segment (start 82.005 123.595) (end 81.575 123.595) (width 0.1) (layer "B.Cu") (net 261))
  (segment (start 82.5 123.1) (end 82.5 122.7) (width 0.1) (layer "B.Cu") (net 261))
  (segment (start 83.534194 121.638638) (end 83.551296 121.625) (width 0.1) (layer "B.Cu") (net 261))
  (segment (start 84.143382 120.954705) (end 84.133891 120.934996) (width 0.1) (layer "B.Cu") (net 261))
  (segment (start 83.637853 121.31416) (end 83.65918 121.319028) (width 0.1) (layer "B.Cu") (net 261))
  (segment (start 83.823771 121.183633) (end 83.81428 121.163925) (width 0.1) (layer "B.Cu") (net 261))
  (segment (start 94.3 120.05) (end 94.55 119.8) (width 0.1) (layer "B.Cu") (net 261))
  (segment (start 84.092254 120.859756) (end 84.092254 120.837882) (width 0.1) (layer "B.Cu") (net 261))
  (segment (start 83.568207 121.50068) (end 83.540929 121.466475) (width 0.1) (layer "B.Cu") (net 261))
  (segment (start 82.5 122.05) (end 82.4 122.15) (width 0.1) (layer "F.Cu") (net 262))
  (segment (start 94.4 118.55) (end 94 118.95) (width 0.1) (layer "F.Cu") (net 262))
  (segment (start 82.4 122.15) (end 81.9 122.15) (width 0.1) (layer "F.Cu") (net 262))
  (via (at 94 118.95) (size 0.5) (drill 0.2) (layers "F.Cu" "B.Cu") (net 262))
  (via (at 82.5 122.05) (size 0.5) (drill 0.2) (layers "F.Cu" "B.Cu") (net 262))
  (segment (start 83.228648 120.991951) (end 83.251042 120.99195) (width 0.1) (layer "B.Cu") (net 262))
  (segment (start 83.155171 121.038118) (end 83.169134 121.02061) (width 0.1) (layer "B.Cu") (net 262))
  (segment (start 92.3 119.45) (end 92.9 120.05) (width 0.1) (layer "B.Cu") (net 262))
  (segment (start 83.723619 120.355558) (end 83.746013 120.355557) (width 0.1) (layer "B.Cu") (net 262))
  (segment (start 83.083866 121.475481) (end 83.087912 121.477428) (width 0.1) (layer "B.Cu") (net 262))
  (segment (start 83.650143 120.508132) (end 83.640428 120.487956) (width 0.1) (layer "B.Cu") (net 262))
  (segment (start 83.411946 121.107997) (end 83.433777 121.11298) (width 0.1) (layer "B.Cu") (net 262))
  (segment (start 82.944254 121.605229) (end 82.945253 121.600852) (width 0.1) (layer "B.Cu") (net 262))
  (segment (start 83.505903 120.898457) (end 83.515682 120.886194) (width 0.1) (layer "B.Cu") (net 262))
  (segment (start 83.640428 120.4219) (end 83.650144 120.401724) (width 0.1) (layer "B.Cu") (net 262))
  (segment (start 83.107843 121.485973) (end 83.11222 121.484974) (width 0.1) (layer "B.Cu") (net 262))
  (segment (start 82.954746 121.642447) (end 82.955745 121.63807) (width 0.1) (layer "B.Cu") (net 262))
  (segment (start 84.063859 120.532598) (end 84.081365 120.518636) (width 0.1) (layer "B.Cu") (net 262))
  (segment (start 83.525461 120.99752) (end 83.505903 120.972993) (width 0.1) (layer "B.Cu") (net 262))
  (segment (start 83.256519 121.329477) (end 83.261501 121.307646) (width 0.1) (layer "B.Cu") (net 262))
  (segment (start 91.1 119.45) (end 92.3 119.45) (width 0.1) (layer "B.Cu") (net 262))
  (segment (start 82.945253 121.600852) (end 82.9472 121.596807) (width 0.1) (layer "B.Cu") (net 262))
  (segment (start 83.116265 121.483027) (end 83.119775 121.480227) (width 0.1) (layer "B.Cu") (net 262))
  (segment (start 83.499096 120.958861) (end 83.495606 120.943568) (width 0.1) (layer "B.Cu") (net 262))
  (segment (start 83.261502 121.285252) (end 83.256519 121.263421) (width 0.1) (layer "B.Cu") (net 262))
  (segment (start 84.65 119.95) (end 90.6 119.95) (width 0.1) (layer "B.Cu") (net 262))
  (segment (start 84.043683 120.542314) (end 84.063859 120.532598) (width 0.1) (layer "B.Cu") (net 262))
  (segment (start 83.478002 121.107997) (end 83.498178 121.09828) (width 0.1) (layer "B.Cu") (net 262))
  (segment (start 83.635444 120.466125) (end 83.635445 120.443731) (width 0.1) (layer "B.Cu") (net 262))
  (segment (start 83.063069 121.480228) (end 83.06658 121.477428) (width 0.1) (layer "B.Cu") (net 262))
  (segment (start 83.094931 121.483028) (end 83.098976 121.484975) (width 0.1) (layer "B.Cu") (net 262))
  (segment (start 83.075001 121.474481) (end 83.079489 121.474482) (width 0.1) (layer "B.Cu") (net 262))
  (segment (start 83.532268 121.011652) (end 83.525461 120.99752) (width 0.1) (layer "B.Cu") (net 262))
  (segment (start 83.630708 120.82725) (end 83.64484 120.834056) (width 0.1) (layer "B.Cu") (net 262))
  (segment (start 83.495606 120.927882) (end 83.499096 120.912591) (width 0.1) (layer "B.Cu") (net 262))
  (segment (start 83.293047 121.00665) (end 83.310556 121.02061) (width 0.1) (layer "B.Cu") (net 262))
  (segment (start 83.140473 121.102517) (end 83.140472 121.080125) (width 0.1) (layer "B.Cu") (net 262))
  (segment (start 83.456171 121.112979) (end 83.478002 121.107997) (width 0.1) (layer "B.Cu") (net 262))
  (segment (start 83.169133 121.162032) (end 83.155172 121.144524) (width 0.1) (layer "B.Cu") (net 262))
  (segment (start 92.9 120.05) (end 93.4 120.05) (width 0.1) (layer "B.Cu") (net 262))
  (segment (start 94.35 119.7) (end 94.35 119.3) (width 0.1) (layer "B.Cu") (net 262))
  (segment (start 83.615414 120.823761) (end 83.630708 120.82725) (width 0.1) (layer "B.Cu") (net 262))
  (segment (start 83.664104 120.525639) (end 83.650143 120.508132) (width 0.1) (layer "B.Cu") (net 262))
  (segment (start 83.714479 120.863913) (end 83.72977 120.860423) (width 0.1) (layer "B.Cu") (net 262))
  (segment (start 83.251042 120.99195) (end 83.272873 120.996933) (width 0.1) (layer "B.Cu") (net 262))
  (segment (start 83.505903 120.972993) (end 83.499096 120.958861) (width 0.1) (layer "B.Cu") (net 262))
  (segment (start 82.95 121.65) (end 82.952799 121.646492) (width 0.1) (layer "B.Cu") (net 262))
  (segment (start 83.140472 121.080125) (end 83.145456 121.058292) (width 0.1) (layer "B.Cu") (net 262))
  (segment (start 83.681612 120.370257) (end 83.701788 120.36054) (width 0.1) (layer "B.Cu") (net 262))
  (segment (start 83.525461 121.072056) (end 83.532268 121.057922) (width 0.1) (layer "B.Cu") (net 262))
  (segment (start 83.23284 121.225739) (end 83.169133 121.162032) (width 0.1) (layer "B.Cu") (net 262))
  (segment (start 83.39177 121.098281) (end 83.411946 121.107997) (width 0.1) (layer "B.Cu") (net 262))
  (segment (start 83.798522 120.660057) (end 83.664104 120.525639) (width 0.1) (layer "B.Cu") (net 262))
  (segment (start 82.9528 121.625158) (end 82.947201 121.618139) (width 0.1) (layer "B.Cu") (net 262))
  (segment (start 83.957453 120.532597) (end 83.977627 120.542314) (width 0.1) (layer "B.Cu") (net 262))
  (segment (start 83.11222 121.484974) (end 83.116265 121.483027) (width 0.1) (layer "B.Cu") (net 262))
  (segment (start 83.788018 120.370257) (end 83.805527 120.384217) (width 0.1) (layer "B.Cu") (net 262))
  (segment (start 83.72977 120.860423) (end 83.743904 120.853616) (width 0.1) (layer "B.Cu") (net 262))
  (segment (start 83.59973 120.82376) (end 83.615414 120.823761) (width 0.1) (layer "B.Cu") (net 262))
  (segment (start 84.021852 120.547297) (end 84.043683 120.542314) (width 0.1) (layer "B.Cu") (net 262))
  (segment (start 83.650144 120.401724) (end 83.664105 120.384217) (width 0.1) (layer "B.Cu") (net 262))
  (segment (start 83.939946 120.518636) (end 83.957453 120.532597) (width 0.1) (layer "B.Cu") (net 262))
  (segment (start 83.06658 121.477428) (end 83.070624 121.47548) (width 0.1) (layer "B.Cu") (net 262))
  (segment (start 83.827183 120.741964) (end 83.827184 120.71957) (width 0.1) (layer "B.Cu") (net 262))
  (segment (start 83.664105 120.384217) (end 83.681612 120.370257) (width 0.1) (layer "B.Cu") (net 262))
  (segment (start 83.232841 121.367159) (end 83.246802 121.349653) (width 0.1) (layer "B.Cu") (net 262))
  (segment (start 83.310556 121.02061) (end 83.374264 121.084318) (width 0.1) (layer "B.Cu") (net 262))
  (segment (start 83.64484 120.834056) (end 83.669368 120.853616) (width 0.1) (layer "B.Cu") (net 262))
  (segment (start 82.954747 121.629203) (end 82.9528 121.625158) (width 0.1) (layer "B.Cu") (net 262))
  (segment (start 83.669368 120.853616) (end 83.6835 120.860423) (width 0.1) (layer "B.Cu") (net 262))
  (segment (start 83.495606 120.943568) (end 83.495606 120.927882) (width 0.1) (layer "B.Cu") (net 262))
  (segment (start 83.515682 121.084318) (end 83.525461 121.072056) (width 0.1) (layer "B.Cu") (net 262))
  (segment (start 83.977627 120.542314) (end 83.99946 120.547296) (width 0.1) (layer "B.Cu") (net 262))
  (segment (start 94.35 119.3) (end 94 118.95) (width 0.1) (layer "B.Cu") (net 262))
  (segment (start 83.498178 121.09828) (end 83.515683 121.084318) (width 0.1) (layer "B.Cu") (net 262))
  (segment (start 83.812484 120.783971) (end 83.822201 120.763795) (width 0.1) (layer "B.Cu") (net 262))
  (segment (start 83.635445 120.443731) (end 83.640428 120.4219) (width 0.1) (layer "B.Cu") (net 262))
  (segment (start 83.145456 121.058292) (end 83.155171 121.038118) (width 0.1) (layer "B.Cu") (net 262))
  (segment (start 83.103353 121.485974) (end 83.107843 121.485973) (width 0.1) (layer "B.Cu") (net 262))
  (segment (start 83.827184 120.71957) (end 83.822201 120.697739) (width 0.1) (layer "B.Cu") (net 262))
  (segment (start 83.6835 120.860423) (end 83.698793 120.863913) (width 0.1) (layer "B.Cu") (net 262))
  (segment (start 83.272873 120.996933) (end 83.293047 121.00665) (width 0.1) (layer "B.Cu") (net 262))
  (segment (start 83.433777 121.11298) (end 83.456171 121.112979) (width 0.1) (layer "B.Cu") (net 262))
  (segment (start 82.5 122.05) (end 82.85 122.05) (width 0.1) (layer "B.Cu") (net 262))
  (segment (start 83.756166 120.843837) (end 83.798523 120.801477) (width 0.1) (layer "B.Cu") (net 262))
  (segment (start 93.6 119.85) (end 94.2 119.85) (width 0.1) (layer "B.Cu") (net 262))
  (segment (start 83.070624 121.47548) (end 83.075001 121.474481) (width 0.1) (layer "B.Cu") (net 262))
  (segment (start 83.55804 120.843837) (end 83.570304 120.834057) (width 0.1) (layer "B.Cu") (net 262))
  (segment (start 82.9472 121.596807) (end 82.95 121.593296) (width 0.1) (layer "B.Cu") (net 262))
  (segment (start 83.169134 121.02061) (end 83.186641 121.00665) (width 0.1) (layer "B.Cu") (net 262))
  (segment (start 83.640428 120.487956) (end 83.635444 120.466125) (width 0.1) (layer "B.Cu") (net 262))
  (segment (start 84.081365 120.518636) (end 84.65 119.95) (width 0.1) (layer "B.Cu") (net 262))
  (segment (start 83.145456 121.124348) (end 83.140473 121.102517) (width 0.1) (layer "B.Cu") (net 262))
  (segment (start 93.4 120.05) (end 93.6 119.85) (width 0.1) (layer "B.Cu") (net 262))
  (segment (start 83.701788 120.36054) (end 83.723619 120.355558) (width 0.1) (layer "B.Cu") (net 262))
  (segment (start 81.955 122.595) (end 82.5 122.05) (width 0.1) (layer "B.Cu") (net 262))
  (segment (start 83.206817 120.996933) (end 83.228648 120.991951) (width 0.1) (layer "B.Cu") (net 262))
  (segment (start 82.85 122.05) (end 82.95 121.95) (width 0.1) (layer "B.Cu") (net 262))
  (segment (start 83.261501 121.307646) (end 83.261502 121.285252) (width 0.1) (layer "B.Cu") (net 262))
  (segment (start 82.952799 121.646492) (end 82.954746 121.642447) (width 0.1) (layer "B.Cu") (net 262))
  (segment (start 82.947201 121.618139) (end 82.945254 121.614094) (width 0.1) (layer "B.Cu") (net 262))
  (segment (start 83.246802 121.349653) (end 83.256519 121.329477) (width 0.1) (layer "B.Cu") (net 262))
  (segment (start 83.246802 121.243247) (end 83.23284 121.225739) (width 0.1) (layer "B.Cu") (net 262))
  (segment (start 82.95 121.95) (end 82.95 121.65) (width 0.1) (layer "B.Cu") (net 262))
  (segment (start 83.515683 121.084318) (end 83.515682 121.084318) (width 0.1) (layer "B.Cu") (net 262))
  (segment (start 83.805527 120.384217) (end 83.939946 120.518636) (width 0.1) (layer "B.Cu") (net 262))
  (segment (start 83.087912 121.477428) (end 83.094931 121.483028) (width 0.1) (layer "B.Cu") (net 262))
  (segment (start 82.945254 121.614094) (end 82.944255 121.609717) (width 0.1) (layer "B.Cu") (net 262))
  (segment (start 83.515682 120.886194) (end 83.55804 120.843837) (width 0.1) (layer "B.Cu") (net 262))
  (segment (start 82.944255 121.609717) (end 82.944254 121.605229) (width 0.1) (layer "B.Cu") (net 262))
  (segment (start 82.955746 121.63358) (end 82.954747 121.629203) (width 0.1) (layer "B.Cu") (net 262))
  (segment (start 83.746013 120.355557) (end 83.767844 120.36054) (width 0.1) (layer "B.Cu") (net 262))
  (segment (start 94.2 119.85) (end 94.35 119.7) (width 0.1) (layer "B.Cu") (net 262))
  (segment (start 83.186641 121.00665) (end 83.206817 120.996933) (width 0.1) (layer "B.Cu") (net 262))
  (segment (start 90.6 119.95) (end 91.1 119.45) (width 0.1) (layer "B.Cu") (net 262))
  (segment (start 83.098976 121.484975) (end 83.103353 121.485974) (width 0.1) (layer "B.Cu") (net 262))
  (segment (start 82.95 121.593296) (end 83.063069 121.480228) (width 0.1) (layer "B.Cu") (net 262))
  (segment (start 83.079489 121.474482) (end 83.083866 121.475481) (width 0.1) (layer "B.Cu") (net 262))
  (segment (start 83.767844 120.36054) (end 83.788018 120.370257) (width 0.1) (layer "B.Cu") (net 262))
  (segment (start 83.256519 121.263421) (end 83.246802 121.243247) (width 0.1) (layer "B.Cu") (net 262))
  (segment (start 83.584436 120.827251) (end 83.59973 120.82376) (width 0.1) (layer "B.Cu") (net 262))
  (segment (start 83.822201 120.697739) (end 83.812484 120.677565) (width 0.1) (layer "B.Cu") (net 262))
  (segment (start 81.955 122.595) (end 81.575 122.595) (width 0.1) (layer "B.Cu") (net 262))
  (segment (start 83.570304 120.834057) (end 83.584436 120.827251) (width 0.1) (layer "B.Cu") (net 262))
  (segment (start 83.812484 120.677565) (end 83.798522 120.660057) (width 0.1) (layer "B.Cu") (net 262))
  (segment (start 83.374264 121.084318) (end 83.39177 121.098281) (width 0.1) (layer "B.Cu") (net 262))
  (segment (start 83.99946 120.547296) (end 84.021852 120.547297) (width 0.1) (layer "B.Cu") (net 262))
  (segment (start 83.155172 121.144524) (end 83.145456 121.124348) (width 0.1) (layer "B.Cu") (net 262))
  (segment (start 83.119775 121.480227) (end 83.232841 121.367159) (width 0.1) (layer "B.Cu") (net 262))
  (segment (start 83.822201 120.763795) (end 83.827183 120.741964) (width 0.1) (layer "B.Cu") (net 262))
  (segment (start 82.955745 121.63807) (end 82.955746 121.63358) (width 0.1) (layer "B.Cu") (net 262))
  (segment (start 83.743904 120.853616) (end 83.756166 120.843837) (width 0.1) (layer "B.Cu") (net 262))
  (segment (start 83.532268 121.057922) (end 83.535758 121.042631) (width 0.1) (layer "B.Cu") (net 262))
  (segment (start 83.698793 120.863913) (end 83.714479 120.863913) (width 0.1) (layer "B.Cu") (net 262))
  (segment (start 83.499096 120.912591) (end 83.505903 120.898457) (width 0.1) (layer "B.Cu") (net 262))
  (segment (start 83.535758 121.042631) (end 83.535758 121.026945) (width 0.1) (layer "B.Cu") (net 262))
  (segment (start 83.798523 120.801477) (end 83.812484 120.783971) (width 0.1) (layer "B.Cu") (net 262))
  (segment (start 83.535758 121.026945) (end 83.532268 121.011652) (width 0.1) (layer "B.Cu") (net 262))
  (segment (start 92.8 120.15) (end 92.4 120.55) (width 0.15) (layer "F.Cu") (net 263))
  (segment (start 86.2898 116.95) (end 85.8898 117.35) (width 0.1) (layer "F.Cu") (net 263))
  (segment (start 88.25 116.95) (end 86.2898 116.95) (width 0.1) (layer "F.Cu") (net 263))
  (segment (start 88.65 117.35) (end 88.25 116.95) (width 0.1) (layer "F.Cu") (net 263))
  (segment (start 89.15 120.55) (end 88.65 120.05) (width 0.1) (layer "F.Cu") (net 263))
  (segment (start 88.65 120.05) (end 88.65 117.35) (width 0.1) (layer "F.Cu") (net 263))
  (segment (start 89.7 120.55) (end 89.15 120.55) (width 0.1) (layer "F.Cu") (net 263))
  (via blind (at 92.4 120.55) (size 0.5) (drill 0.2) (layers "F.Cu" "In2.Cu") (net 263))
  (via blind (at 89.7 120.55) (size 0.5) (drill 0.2) (layers "F.Cu" "In2.Cu") (net 263))
  (segment (start 89.7 120.55) (end 92.5 120.55) (width 0.1) (layer "In2.Cu") (net 263))
  (segment (start 92.5 120.55) (end 92.4 120.55) (width 0.1) (layer "In2.Cu") (net 263))
  (segment (start 127.39 175.844999) (end 127.39 177.135) (width 0.127) (layer "F.Cu") (net 264))
  (segment (start 125.425 172.286778) (end 127.565 174.426778) (width 0.127) (layer "F.Cu") (net 264))
  (segment (start 127.565 175.669999) (end 127.39 175.844999) (width 0.127) (layer "F.Cu") (net 264))
  (segment (start 125.425 166.162501) (end 125.425 172.286778) (width 0.127) (layer "F.Cu") (net 264))
  (segment (start 127.565 174.426778) (end 127.565 175.669999) (width 0.127) (layer "F.Cu") (net 264))
  (segment (start 125.3 164.875) (end 125.3 166.037501) (width 0.127) (layer "F.Cu") (net 264))
  (segment (start 125.3 166.037501) (end 125.425 166.162501) (width 0.127) (layer "F.Cu") (net 264))
  (segment (start 70.75 63.75) (end 70.75 65.4) (width 0.25) (layer "F.Cu") (net 265))
  (segment (start 68.1 61.1) (end 70.05 63.05) (width 0.25) (layer "F.Cu") (net 265))
  (segment (start 80.85 67.275) (end 81.8 67.275) (width 0.25) (layer "F.Cu") (net 265))
  (segment (start 70.05 63.05) (end 70.75 63.75) (width 0.25) (layer "F.Cu") (net 265))
  (segment (start 81.8 67.275) (end 82 67.475) (width 0.25) (layer "F.Cu") (net 265))
  (segment (start 76.8 65.8) (end 75.5 65.8) (width 0.5) (layer "F.Cu") (net 265))
  (via (at 74.55 66.4) (size 0.5) (drill 0.2) (layers "F.Cu" "B.Cu") (net 265))
  (via (at 80.85 67.275) (size 0.5) (drill 0.2) (layers "F.Cu" "B.Cu") (net 265))
  (segment (start 75.8 67.65) (end 74.55 66.4) (width 0.25) (layer "B.Cu") (net 265))
  (segment (start 80.85 67.275) (end 80.475 67.65) (width 0.25) (layer "B.Cu") (net 265))
  (segment (start 80.475 67.65) (end 75.8 67.65) (width 0.25) (layer "B.Cu") (net 265))
  (segment (start 125.675 172.183222) (end 127.815 174.323222) (width 0.127) (layer "F.Cu") (net 266))
  (segment (start 125.8 166.037501) (end 125.675 166.162501) (width 0.127) (layer "F.Cu") (net 266))
  (segment (start 127.815 175.669999) (end 127.99 175.844999) (width 0.127) (layer "F.Cu") (net 266))
  (segment (start 125.675 166.162501) (end 125.675 172.183222) (width 0.127) (layer "F.Cu") (net 266))
  (segment (start 127.815 174.323222) (end 127.815 175.669999) (width 0.127) (layer "F.Cu") (net 266))
  (segment (start 127.99 175.844999) (end 127.99 177.135) (width 0.127) (layer "F.Cu") (net 266))
  (segment (start 125.8 164.875) (end 125.8 166.037501) (width 0.127) (layer "F.Cu") (net 266))
  (segment (start 92.57 71.63) (end 92.45 71.75) (width 0.25) (layer "F.Cu") (net 267))
  (segment (start 92.57 70.45) (end 92.57 71.63) (width 0.25) (layer "F.Cu") (net 267))
  (segment (start 94.9 77.75) (end 94.785 77.865) (width 0.2) (layer "F.Cu") (net 267))
  (segment (start 93.285 77.9) (end 94.2 77.9) (width 0.25) (layer "F.Cu") (net 267))
  (segment (start 94.785 77.865) (end 94.3 77.865) (width 0.2) (layer "F.Cu") (net 267))
  (segment (start 94.9 75.6) (end 94.9 77.75) (width 0.2) (layer "F.Cu") (net 267))
  (via (at 92.45 71.75) (size 0.5) (drill 0.2) (layers "F.Cu" "B.Cu") (net 267))
  (via (at 94.9 75.6) (size 0.5) (drill 0.2) (layers "F.Cu" "B.Cu") (net 267))
  (segment (start 93.1 71.1) (end 92.45 71.75) (width 0.2) (layer "B.Cu") (net 267))
  (segment (start 94.9 75.6) (end 94.9 71.65) (width 0.2) (layer "B.Cu") (net 267))
  (segment (start 94.35 71.1) (end 93.1 71.1) (width 0.2) (layer "B.Cu") (net 267))
  (segment (start 94.9 71.65) (end 94.35 71.1) (width 0.2) (layer "B.Cu") (net 267))
  (segment (start 70.35 96.15) (end 69.95 95.75) (width 0.15) (layer "F.Cu") (net 268))
  (segment (start 69.95 95.75) (end 69.95 94.8) (width 0.15) (layer "F.Cu") (net 268))
  (segment (start 77.65 96.15) (end 70.35 96.15) (width 0.15) (layer "F.Cu") (net 268))
  (segment (start 94.395 129.735) (end 93.995 130.135) (width 0.15) (layer "F.Cu") (net 268))
  (segment (start 77.552 158.75802) (end 77.552 159.75712) (width 0.15) (layer "F.Cu") (net 268))
  (via (at 93.995 130.135) (size 0.5) (drill 0.2) (layers "F.Cu" "B.Cu") (net 268))
  (via (at 77.65 96.15) (size 0.5) (drill 0.2) (layers "F.Cu" "B.Cu") (net 268))
  (via (at 80.9 132.25) (size 0.5) (drill 0.2) (layers "F.Cu" "B.Cu") (net 268))
  (via (at 77.552 159.75712) (size 0.5) (drill 0.2) (layers "F.Cu" "B.Cu") (net 268))
  (segment (start 77.552 158.178) (end 91.450066 144.279934) (width 0.1) (layer "In5.Cu") (net 268))
  (segment (start 78.85 105.55) (end 78.85 97) (width 0.15) (layer "In5.Cu") (net 268))
  (segment (start 93.641447 130.135) (end 93.995 130.135) (width 0.1) (layer "In5.Cu") (net 268))
  (segment (start 91.450066 144.279934) (end 91.450066 134.849934) (width 0.1) (layer "In5.Cu") (net 268))
  (segment (start 78.85 97) (end 78 96.15) (width 0.15) (layer "In5.Cu") (net 268))
  (segment (start 68.45 108.75) (end 69.9 107.3) (width 0.15) (layer "In5.Cu") (net 268))
  (segment (start 80.9 132.25) (end 80.6 132.25) (width 0.15) (layer "In5.Cu") (net 268))
  (segment (start 93.099989 130.676458) (end 93.641447 130.135) (width 0.1) (layer "In5.Cu") (net 268))
  (segment (start 93.099989 133.200011) (end 93.099989 130.676458) (width 0.1) (layer "In5.Cu") (net 268))
  (segment (start 69.5 127.65) (end 68.45 126.6) (width 0.15) (layer "In5.Cu") (net 268))
  (segment (start 77.552 159.75712) (end 77.552 158.178) (width 0.1) (layer "In5.Cu") (net 268))
  (segment (start 76 127.65) (end 69.5 127.65) (width 0.15) (layer "In5.Cu") (net 268))
  (segment (start 69.9 107.3) (end 77.1 107.3) (width 0.15) (layer "In5.Cu") (net 268))
  (segment (start 80.6 132.25) (end 76 127.65) (width 0.15) (layer "In5.Cu") (net 268))
  (segment (start 77.1 107.3) (end 78.85 105.55) (width 0.15) (layer "In5.Cu") (net 268))
  (segment (start 91.450066 134.849934) (end 93.099989 133.200011) (width 0.1) (layer "In5.Cu") (net 268))
  (segment (start 78 96.15) (end 77.65 96.15) (width 0.15) (layer "In5.Cu") (net 268))
  (segment (start 68.45 126.6) (end 68.45 108.75) (width 0.15) (layer "In5.Cu") (net 268))
  (segment (start 91.95 128.8) (end 93.285 130.135) (width 0.15) (layer "B.Cu") (net 268))
  (segment (start 87.4 132.2) (end 90.8 128.8) (width 0.15) (layer "B.Cu") (net 268))
  (segment (start 80.9 132.25) (end 80.95 132.2) (width 0.15) (layer "B.Cu") (net 268))
  (segment (start 90.8 128.8) (end 91.95 128.8) (width 0.15) (layer "B.Cu") (net 268))
  (segment (start 93.285 130.135) (end 93.995 130.135) (width 0.15) (layer "B.Cu") (net 268))
  (segment (start 80.95 132.2) (end 87.4 132.2) (width 0.15) (layer "B.Cu") (net 268))
  (segment (start 74.06 161.85) (end 74.255 161.655) (width 0.15) (layer "F.Cu") (net 269))
  (segment (start 74.06 162.33) (end 74.06 161.85) (width 0.15) (layer "F.Cu") (net 269))
  (segment (start 74.255 161.02) (end 77.18912 161.02) (width 0.15) (layer "F.Cu") (net 269))
  (segment (start 77.18912 161.02) (end 78.052 160.15712) (width 0.15) (layer "F.Cu") (net 269))
  (segment (start 78.052 158.75802) (end 78.052 160.15712) (width 0.15) (layer "F.Cu") (net 269))
  (segment (start 74.255 161.655) (end 74.255 161.02) (width 0.15) (layer "F.Cu") (net 269))
  (segment (start 94.385 128.955) (end 94.785 129.355) (width 0.15) (layer "F.Cu") (net 269))
  (via (at 94.785 129.355) (size 0.5) (drill 0.2) (layers "F.Cu" "B.Cu") (net 269))
  (via (at 78.052 160.15712) (size 0.5) (drill 0.2) (layers "F.Cu" "B.Cu") (net 269))
  (segment (start 94.785 130.215) (end 94.464999 130.535001) (width 0.1) (layer "In5.Cu") (net 269))
  (segment (start 94.464999 130.535001) (end 93.714999 130.535001) (width 0.1) (layer "In5.Cu") (net 269))
  (segment (start 91.700077 134.999923) (end 91.700077 144.559923) (width 0.1) (layer "In5.Cu") (net 269))
  (segment (start 93.714999 130.535001) (end 93.35 130.9) (width 0.1) (layer "In5.Cu") (net 269))
  (segment (start 94.785 129.355) (end 94.785 130.215) (width 0.1) (layer "In5.Cu") (net 269))
  (segment (start 93.35 130.9) (end 93.35 133.35) (width 0.1) (layer "In5.Cu") (net 269))
  (segment (start 93.35 133.35) (end 91.700077 134.999923) (width 0.1) (layer "In5.Cu") (net 269))
  (segment (start 91.700077 144.559923) (end 78.052 158.208) (width 0.1) (layer "In5.Cu") (net 269))
  (segment (start 78.052 158.208) (end 78.052 160.15712) (width 0.1) (layer "In5.Cu") (net 269))
  (segment (start 77.749994 78.269994) (end 77.749994 79.050006) (width 0.2) (layer "F.Cu") (net 270))
  (segment (start 81.75 69.67) (end 82.645 69.67) (width 0.2) (layer "F.Cu") (net 270))
  (segment (start 82.65 69.665) (end 83.785 69.665) (width 0.2) (layer "F.Cu") (net 270))
  (segment (start 77.749994 77.390006) (end 77.749994 78.269994) (width 0.2) (layer "F.Cu") (net 270))
  (segment (start 82.65 69.25) (end 82.65 69.665) (width 0.2) (layer "F.Cu") (net 270))
  (segment (start 79.050857 76.825) (end 78.315 76.825) (width 0.2) (layer "F.Cu") (net 270))
  (segment (start 80.25 74.235) (end 80.25 74.95) (width 0.2) (layer "F.Cu") (net 270))
  (segment (start 82.3 68.9) (end 82.65 69.25) (width 0.2) (layer "F.Cu") (net 270))
  (segment (start 80.85 68.9) (end 82.3 68.9) (width 0.2) (layer "F.Cu") (net 270))
  (segment (start 82.645 69.67) (end 82.65 69.665) (width 0.2) (layer "F.Cu") (net 270))
  (segment (start 76.8 66.6) (end 75.9 66.6) (width 0.25) (layer "F.Cu") (net 270))
  (segment (start 78.315 76.825) (end 77.749994 77.390006) (width 0.2) (layer "F.Cu") (net 270))
  (via (at 80.85 68.9) (size 0.5) (drill 0.2) (layers "F.Cu" "B.Cu") (net 270))
  (via (at 75.9 66.6) (size 0.5) (drill 0.2) (layers "F.Cu" "B.Cu") (net 270))
  (via (at 77.75 78.33) (size 0.5) (drill 0.2) (layers "F.Cu" "B.Cu") (net 270))
  (via (at 80.25 74.95) (size 0.5) (drill 0.2) (layers "F.Cu" "B.Cu") (net 270))
  (via (at 81.75 69.67) (size 0.5) (drill 0.2) (layers "F.Cu" "B.Cu") (net 270))
  (via (at 73.7 91.75) (size 0.5) (drill 0.2) (layers "F.Cu" "B.Cu") (net 270))
  (segment (start 73.7 91.75) (end 77.749994 87.700006) (width 0.15) (layer "In5.Cu") (net 270))
  (segment (start 77.749994 87.700006) (end 77.749994 78.55) (width 0.15) (layer "In5.Cu") (net 270))
  (segment (start 77.699994 78.5) (end 77.749994 78.55) (width 0.15) (layer "In5.Cu") (net 270))
  (segment (start 77.749994 78.360006) (end 80.25 75.86) (width 0.2) (layer "B.Cu") (net 270))
  (segment (start 73.1 92.35) (end 73.7 91.75) (width 0.15) (layer "B.Cu") (net 270))
  (segment (start 81.35 68.4) (end 81.35 66.85) (width 0.2) (layer "B.Cu") (net 270))
  (segment (start 80.25 75.86) (end 80.25 74.95) (width 0.2) (layer "B.Cu") (net 270))
  (segment (start 72.25 92.35) (end 73.1 92.35) (width 0.15) (layer "B.Cu") (net 270))
  (segment (start 80.85 68.9) (end 81.35 68.4) (width 0.2) (layer "B.Cu") (net 270))
  (segment (start 80.95 66.45) (end 76.05 66.45) (width 0.2) (layer "B.Cu") (net 270))
  (segment (start 81.35 66.85) (end 80.95 66.45) (width 0.2) (layer "B.Cu") (net 270))
  (segment (start 80.25 74.95) (end 80.25 71.17) (width 0.2) (layer "B.Cu") (net 270))
  (segment (start 80.25 71.17) (end 81.75 69.67) (width 0.2) (layer "B.Cu") (net 270))
  (segment (start 76.05 66.45) (end 75.9 66.6) (width 0.2) (layer "B.Cu") (net 270))
  (segment (start 93.595 128.935) (end 93.195 129.335) (width 0.15) (layer "F.Cu") (net 271))
  (segment (start 78.572 154.34712) (end 78.572 151.85212) (width 0.15) (layer "F.Cu") (net 271))
  (via (at 78.552 151.83212) (size 0.5) (drill 0.2) (layers "F.Cu" "B.Cu") (net 271))
  (via (at 93.195 129.335) (size 0.5) (drill 0.2) (layers "F.Cu" "B.Cu") (net 271))
  (segment (start 92.71 128.85) (end 93.195 129.335) (width 0.1) (layer "In5.Cu") (net 271))
  (segment (start 79.03412 151.35) (end 80.9 151.35) (width 0.1) (layer "In5.Cu") (net 271))
  (segment (start 80.9 151.35) (end 89.95 142.3) (width 0.1) (layer "In5.Cu") (net 271))
  (segment (start 91.1 128.85) (end 92.71 128.85) (width 0.1) (layer "In5.Cu") (net 271))
  (segment (start 89.95 142.3) (end 89.95 130) (width 0.1) (layer "In5.Cu") (net 271))
  (segment (start 78.552 151.83212) (end 79.03412 151.35) (width 0.1) (layer "In5.Cu") (net 271))
  (segment (start 89.95 130) (end 91.1 128.85) (width 0.1) (layer "In5.Cu") (net 271))
  (segment (start 75.052 158.75802) (end 75.052 160.15712) (width 0.15) (layer "F.Cu") (net 272))
  (segment (start 90.75 133.85) (end 92.7 133.85) (width 0.1) (layer "F.Cu") (net 272))
  (segment (start 90.35 133.45) (end 90.75 133.85) (width 0.1) (layer "F.Cu") (net 272))
  (segment (start 92.7 133.85) (end 93.6 132.95) (width 0.1) (layer "F.Cu") (net 272))
  (via (at 90.35 133.45) (size 0.5) (drill 0.2) (layers "F.Cu" "B.Cu") (net 272))
  (via (at 75.052 160.15712) (size 0.5) (drill 0.2) (layers "F.Cu" "B.Cu") (net 272))
  (segment (start 75.052 157.824122) (end 90.200011 142.676111) (width 0.1) (layer "In5.Cu") (net 272))
  (segment (start 90.200011 142.676111) (end 90.200011 133.599989) (width 0.1) (layer "In5.Cu") (net 272))
  (segment (start 75.052 160.15712) (end 75.052 157.824122) (width 0.1) (layer "In5.Cu") (net 272))
  (segment (start 90.200011 133.599989) (end 90.35 133.45) (width 0.1) (layer "In5.Cu") (net 272))
  (segment (start 75.552 158.75802) (end 75.552 159.75712) (width 0.15) (layer "F.Cu") (net 273))
  (segment (start 91.995 132.185) (end 91.598599 132.581401) (width 0.15) (layer "F.Cu") (net 273))
  (segment (start 91.598599 132.581401) (end 91.497985 132.581401) (width 0.15) (layer "F.Cu") (net 273))
  (via (at 91.497985 132.581401) (size 0.5) (drill 0.2) (layers "F.Cu" "B.Cu") (net 273))
  (via (at 75.552 159.75712) (size 0.5) (drill 0.2) (layers "F.Cu" "B.Cu") (net 273))
  (segment (start 90.8 133.6) (end 90.8 133.279386) (width 0.1) (layer "In5.Cu") (net 273))
  (segment (start 90.8 133.279386) (end 91.497985 132.581401) (width 0.1) (layer "In5.Cu") (net 273))
  (segment (start 90.450022 143.119978) (end 90.450022 133.949978) (width 0.1) (layer "In5.Cu") (net 273))
  (segment (start 75.552 159.75712) (end 75.552 158.018) (width 0.1) (layer "In5.Cu") (net 273))
  (segment (start 90.450022 133.949978) (end 90.8 133.6) (width 0.1) (layer "In5.Cu") (net 273))
  (segment (start 75.552 158.018) (end 90.450022 143.119978) (width 0.1) (layer "In5.Cu") (net 273))
  (segment (start 76.052 158.75802) (end 76.052 160.15712) (width 0.15) (layer "F.Cu") (net 274))
  (segment (start 92.8 132.95) (end 92.415 133.335) (width 0.1) (layer "F.Cu") (net 274))
  (segment (start 92.415 133.335) (end 91.45 133.335) (width 0.1) (layer "F.Cu") (net 274))
  (via (at 91.45 133.335) (size 0.5) (drill 0.2) (layers "F.Cu" "B.Cu") (net 274))
  (via (at 76.052 160.15712) (size 0.5) (drill 0.2) (layers "F.Cu" "B.Cu") (net 274))
  (segment (start 90.700033 134.084967) (end 91.45 133.335) (width 0.1) (layer "In5.Cu") (net 274))
  (segment (start 76.052 158.038) (end 90.700033 143.389967) (width 0.1) (layer "In5.Cu") (net 274))
  (segment (start 76.052 160.15712) (end 76.052 158.038) (width 0.1) (layer "In5.Cu") (net 274))
  (segment (start 90.700033 143.389967) (end 90.700033 134.084967) (width 0.1) (layer "In5.Cu") (net 274))
  (segment (start 76.552 158.75802) (end 76.552 159.75712) (width 0.15) (layer "F.Cu") (net 275))
  (segment (start 92.795 130.535) (end 92.395 130.935) (width 0.15) (layer "F.Cu") (net 275))
  (via (at 92.395 130.935) (size 0.5) (drill 0.2) (layers "F.Cu" "B.Cu") (net 275))
  (via (at 76.552 159.75712) (size 0.5) (drill 0.2) (layers "F.Cu" "B.Cu") (net 275))
  (segment (start 90.950044 143.669956) (end 90.950044 134.499956) (width 0.1) (layer "In5.Cu") (net 275))
  (segment (start 91.95 131.38) (end 92.395 130.935) (width 0.1) (layer "In5.Cu") (net 275))
  (segment (start 76.552 158.068) (end 90.950044 143.669956) (width 0.1) (layer "In5.Cu") (net 275))
  (segment (start 90.950044 134.499956) (end 91.897995 133.552005) (width 0.1) (layer "In5.Cu") (net 275))
  (segment (start 91.897995 132.427439) (end 91.95 132.375434) (width 0.1) (layer "In5.Cu") (net 275))
  (segment (start 76.552 159.75712) (end 76.552 158.068) (width 0.1) (layer "In5.Cu") (net 275))
  (segment (start 91.897995 133.552005) (end 91.897995 132.427439) (width 0.1) (layer "In5.Cu") (net 275))
  (segment (start 91.95 132.375434) (end 91.95 131.38) (width 0.1) (layer "In5.Cu") (net 275))
  (segment (start 77.052 158.75802) (end 77.052 160.15712) (width 0.15) (layer "F.Cu") (net 276))
  (segment (start 92.429483 131.700517) (end 92.429483 131.723506) (width 0.15) (layer "F.Cu") (net 276))
  (segment (start 92.795 131.335) (end 92.429483 131.700517) (width 0.15) (layer "F.Cu") (net 276))
  (via (at 77.052 160.15712) (size 0.5) (drill 0.2) (layers "F.Cu" "B.Cu") (net 276))
  (via (at 92.429483 131.723506) (size 0.5) (drill 0.2) (layers "F.Cu" "B.Cu") (net 276))
  (segment (start 91.200055 134.649945) (end 92.75 133.1) (width 0.1) (layer "In5.Cu") (net 276))
  (segment (start 92.429483 131.723506) (end 92.75 132.044023) (width 0.1) (layer "In5.Cu") (net 276))
  (segment (start 92.75 133.1) (end 92.75 132.044023) (width 0.1) (layer "In5.Cu") (net 276))
  (segment (start 91.200055 143.999945) (end 91.200055 134.649945) (width 0.1) (layer "In5.Cu") (net 276))
  (segment (start 77.052 158.148) (end 91.200055 143.999945) (width 0.1) (layer "In5.Cu") (net 276))
  (segment (start 77.052 160.15712) (end 77.052 158.148) (width 0.1) (layer "In5.Cu") (net 276))
  (segment (start 116.4 137.45) (end 116.4 138.758134) (width 0.1) (layer "F.Cu") (net 277))
  (segment (start 113.6 153.387741) (end 110.49 156.497741) (width 0.1) (layer "F.Cu") (net 277))
  (segment (start 116.5 133.95) (end 116 133.45) (width 0.1) (layer "F.Cu") (net 277))
  (segment (start 113.6 141.558134) (end 113.6 153.387741) (width 0.1) (layer "F.Cu") (net 277))
  (segment (start 110.49 156.497741) (end 110.49 177.345) (width 0.1) (layer "F.Cu") (net 277))
  (segment (start 116.4 137.45) (end 116.5 137.35) (width 0.1) (layer "F.Cu") (net 277))
  (segment (start 116 133.45) (end 116 132.95) (width 0.1) (layer "F.Cu") (net 277))
  (segment (start 116.5 137.35) (end 116.5 133.95) (width 0.1) (layer "F.Cu") (net 277))
  (segment (start 116.4 138.758134) (end 113.6 141.558134) (width 0.1) (layer "F.Cu") (net 277))
  (via (at 116.45 135.85) (size 0.5) (drill 0.2) (layers "F.Cu" "B.Cu") (net 277))
  (segment (start 116.45 135.85) (end 116.2 136.1) (width 0.1) (layer "B.Cu") (net 277))
  (segment (start 116.2 136.1) (end 116.2 136.75) (width 0.1) (layer "B.Cu") (net 277))
  (segment (start 94.385 130.555) (end 94.785 130.955) (width 0.15) (layer "F.Cu") (net 278))
  (segment (start 76.475 162.45) (end 78.075 160.85) (width 0.15) (layer "F.Cu") (net 278))
  (segment (start 76.475 164.16) (end 76.475 162.45) (width 0.15) (layer "F.Cu") (net 278))
  (segment (start 76.46 165.36) (end 76.46 164.14) (width 0.15) (layer "F.Cu") (net 278))
  (via (at 78.075 160.85) (size 0.5) (drill 0.2) (layers "F.Cu" "B.Cu") (net 278))
  (via (at 94.785 130.955) (size 0.5) (drill 0.2) (layers "F.Cu" "B.Cu") (net 278))
  (via (at 92.29 135.43) (size 0.5) (drill 0.2) (layers "F.Cu" "B.Cu") (net 278))
  (segment (start 80.525 159.805) (end 80.525 156.915) (width 0.15) (layer "In5.Cu") (net 278))
  (segment (start 91.925087 135.794913) (end 92.29 135.43) (width 0.15) (layer "In5.Cu") (net 278))
  (segment (start 78.075 160.85) (end 79.48 160.85) (width 0.15) (layer "In5.Cu") (net 278))
  (segment (start 91.925087 145.514913) (end 91.925087 135.794913) (width 0.15) (layer "In5.Cu") (net 278))
  (segment (start 79.48 160.85) (end 80.525 159.805) (width 0.15) (layer "In5.Cu") (net 278))
  (segment (start 80.525 156.915) (end 91.925087 145.514913) (width 0.15) (layer "In5.Cu") (net 278))
  (segment (start 92.29 135.43) (end 93 134.72) (width 0.15) (layer "B.Cu") (net 278))
  (segment (start 93 134.72) (end 93 132.05) (width 0.15) (layer "B.Cu") (net 278))
  (segment (start 94.095 130.955) (end 93 132.05) (width 0.15) (layer "B.Cu") (net 278))
  (segment (start 94.785 130.955) (end 94.095 130.955) (width 0.15) (layer "B.Cu") (net 278))
  (segment (start 89.3 101.6) (end 89.8 102.1) (width 0.15) (layer "F.Cu") (net 279))
  (segment (start 94.4 117.75) (end 94 117.35) (width 0.15) (layer "F.Cu") (net 279))
  (segment (start 94 117.35) (end 94 117.11999) (width 0.15) (layer "F.Cu") (net 279))
  (via (at 94 117.11999) (size 0.5) (drill 0.2) (layers "F.Cu" "B.Cu") (net 279))
  (via (at 89.8 102.1) (size 0.5) (drill 0.2) (layers "F.Cu" "B.Cu") (net 279))
  (segment (start 90.123157 105.428763) (end 90.102904 105.460995) (width 0.15) (layer "In2.Cu") (net 279))
  (segment (start 90.007824 104.120737) (end 89.969996 104.125) (width 0.15) (layer "In2.Cu") (net 279))
  (segment (start 90.139991 103.955005) (end 90.135729 103.992832) (width 0.15) (layer "In2.Cu") (net 279))
  (segment (start 89.427339 103.675929) (end 89.448188 103.70911) (width 0.15) (layer "In2.Cu") (net 279))
  (segment (start 89.8 106.05) (end 89.8 116.199002) (width 0.15) (layer "In2.Cu") (net 279))
  (segment (start 89.546067 104.129387) (end 89.509079 104.14233) (width 0.15) (layer "In2.Cu") (net 279))
  (segment (start 90.102904 103.139004) (end 90.123157 103.171236) (width 0.15) (layer "In2.Cu") (net 279))
  (segment (start 89.585009 102.725) (end 89.546067 102.729387) (width 0.15) (layer "In2.Cu") (net 279))
  (segment (start 90.139991 103.944995) (end 90.139991 103.955005) (width 0.15) (layer "In2.Cu") (net 279))
  (segment (start 90.139991 103.255005) (end 90.135729 103.292832) (width 0.15) (layer "In2.Cu") (net 279))
  (segment (start 89.427339 102.82407) (end 89.414396 102.861058) (width 0.15) (layer "In2.Cu") (net 279))
  (segment (start 89.475898 104.43682) (end 89.509079 104.457669) (width 0.15) (layer "In2.Cu") (net 279))
  (segment (start 90.123157 104.728763) (end 90.102904 104.760995) (width 0.15) (layer "In2.Cu") (net 279))
  (segment (start 90.102904 103.839004) (end 90.123157 103.871236) (width 0.15) (layer "In2.Cu") (net 279))
  (segment (start 89.700929 102.707669) (end 89.663941 102.720612) (width 0.15) (layer "In2.Cu") (net 279))
  (segment (start 89.585009 103.425) (end 89.546067 103.429387) (width 0.15) (layer "In2.Cu") (net 279))
  (segment (start 89.509079 103.44233) (end 89.475898 103.463179) (width 0.15) (layer "In2.Cu") (net 279))
  (segment (start 89.427339 105.775929) (end 89.448188 105.80911) (width 0.15) (layer "In2.Cu") (net 279))
  (segment (start 89.475898 103.03682) (end 89.509079 103.057669) (width 0.15) (layer "In2.Cu") (net 279))
  (segment (start 89.427339 104.92407) (end 89.414396 104.961058) (width 0.15) (layer "In2.Cu") (net 279))
  (segment (start 89.969996 104.475) (end 90.007824 104.479262) (width 0.15) (layer "In2.Cu") (net 279))
  (segment (start 89.475898 103.73682) (end 89.509079 103.757669) (width 0.15) (layer "In2.Cu") (net 279))
  (segment (start 89.427339 105.62407) (end 89.414396 105.661058) (width 0.15) (layer "In2.Cu") (net 279))
  (segment (start 90.102904 103.360995) (end 90.075987 103.387912) (width 0.15) (layer "In2.Cu") (net 279))
  (segment (start 89.475898 104.863179) (end 89.448188 104.890889) (width 0.15) (layer "In2.Cu") (net 279))
  (segment (start 89.448188 103.490889) (end 89.427339 103.52407) (width 0.15) (layer "In2.Cu") (net 279))
  (segment (start 90.075987 104.787912) (end 90.043755 104.808165) (width 0.15) (layer "In2.Cu") (net 279))
  (segment (start 89.546067 103.429387) (end 89.509079 103.44233) (width 0.15) (layer "In2.Cu") (net 279))
  (segment (start 89.475898 105.13682) (end 89.509079 105.157669) (width 0.15) (layer "In2.Cu") (net 279))
  (segment (start 89.8 102.1) (end 89.8 102.55) (width 0.15) (layer "In2.Cu") (net 279))
  (segment (start 89.509079 105.157669) (end 89.546067 105.170612) (width 0.15) (layer "In2.Cu") (net 279))
  (segment (start 89.414396 104.261058) (end 89.410009 104.3) (width 0.15) (layer "In2.Cu") (net 279))
  (segment (start 89.427339 103.52407) (end 89.414396 103.561058) (width 0.15) (layer "In2.Cu") (net 279))
  (segment (start 90.043755 105.508165) (end 90.007824 105.520737) (width 0.15) (layer "In2.Cu") (net 279))
  (segment (start 90.075987 104.512087) (end 90.102904 104.539004) (width 0.15) (layer "In2.Cu") (net 279))
  (segment (start 89.969996 104.125) (end 89.585009 104.125) (width 0.15) (layer "In2.Cu") (net 279))
  (segment (start 89.427339 105.075929) (end 89.448188 105.10911) (width 0.15) (layer "In2.Cu") (net 279))
  (segment (start 89.414396 105.661058) (end 89.410009 105.7) (width 0.15) (layer "In2.Cu") (net 279))
  (segment (start 90.043755 103.408165) (end 90.007824 103.420737) (width 0.15) (layer "In2.Cu") (net 279))
  (segment (start 89.509079 105.857669) (end 89.546067 105.870612) (width 0.15) (layer "In2.Cu") (net 279))
  (segment (start 90.123157 104.028763) (end 90.102904 104.060995) (width 0.15) (layer "In2.Cu") (net 279))
  (segment (start 90.007824 104.820737) (end 89.969996 104.825) (width 0.15) (layer "In2.Cu") (net 279))
  (segment (start 89.448188 105.80911) (end 89.475898 105.83682) (width 0.15) (layer "In2.Cu") (net 279))
  (segment (start 89.448188 102.790889) (end 89.427339 102.82407) (width 0.15) (layer "In2.Cu") (net 279))
  (segment (start 90.135729 103.992832) (end 90.123157 104.028763) (width 0.15) (layer "In2.Cu") (net 279))
  (segment (start 89.448188 103.00911) (end 89.475898 103.03682) (width 0.15) (layer "In2.Cu") (net 279))
  (segment (start 89.73411 105.913179) (end 89.76182 105.940889) (width 0.15) (layer "In2.Cu") (net 279))
  (segment (start 89.795612 106.011058) (end 89.8 106.05) (width 0.15) (layer "In2.Cu") (net 279))
  (segment (start 89.585009 104.825) (end 89.546067 104.829387) (width 0.15) (layer "In2.Cu") (net 279))
  (segment (start 90.139991 103.244995) (end 90.139991 103.255005) (width 0.15) (layer "In2.Cu") (net 279))
  (segment (start 90.135729 105.392832) (end 90.123157 105.428763) (width 0.15) (layer "In2.Cu") (net 279))
  (segment (start 89.414396 103.638941) (end 89.427339 103.675929) (width 0.15) (layer "In2.Cu") (net 279))
  (segment (start 89.663941 105.879387) (end 89.700929 105.89233) (width 0.15) (layer "In2.Cu") (net 279))
  (segment (start 89.546067 103.070612) (end 89.585009 103.075) (width 0.15) (layer "In2.Cu") (net 279))
  (segment (start 90.075987 103.112087) (end 90.102904 103.139004) (width 0.15) (layer "In2.Cu") (net 279))
  (segment (start 90.123157 104.571236) (end 90.135729 104.607167) (width 0.15) (layer "In2.Cu") (net 279))
  (segment (start 90.007824 103.779262) (end 90.043755 103.791834) (width 0.15) (layer "In2.Cu") (net 279))
  (segment (start 89.546067 104.470612) (end 89.585009 104.475) (width 0.15) (layer "In2.Cu") (net 279))
  (segment (start 91.095999 117.495001) (end 93.624989 117.495001) (width 0.15) (layer "In2.Cu") (net 279))
  (segment (start 90.135729 104.607167) (end 90.139991 104.644995) (width 0.15) (layer "In2.Cu") (net 279))
  (segment (start 89.585009 105.525) (end 89.546067 105.529387) (width 0.15) (layer "In2.Cu") (net 279))
  (segment (start 90.075987 103.812087) (end 90.102904 103.839004) (width 0.15) (layer "In2.Cu") (net 279))
  (segment (start 89.414396 102.938941) (end 89.427339 102.975929) (width 0.15) (layer "In2.Cu") (net 279))
  (segment (start 89.73411 102.68682) (end 89.700929 102.707669) (width 0.15) (layer "In2.Cu") (net 279))
  (segment (start 89.410009 103.6) (end 89.414396 103.638941) (width 0.15) (layer "In2.Cu") (net 279))
  (segment (start 90.043755 103.091834) (end 90.075987 103.112087) (width 0.15) (layer "In2.Cu") (net 279))
  (segment (start 89.410009 102.9) (end 89.414396 102.938941) (width 0.15) (layer "In2.Cu") (net 279))
  (segment (start 89.546067 103.770612) (end 89.585009 103.775) (width 0.15) (layer "In2.Cu") (net 279))
  (segment (start 90.007824 105.179262) (end 90.043755 105.191834) (width 0.15) (layer "In2.Cu") (net 279))
  (segment (start 90.139991 105.355005) (end 90.135729 105.392832) (width 0.15) (layer "In2.Cu") (net 279))
  (segment (start 89.448188 105.590889) (end 89.427339 105.62407) (width 0.15) (layer "In2.Cu") (net 279))
  (segment (start 89.410009 104.3) (end 89.414396 104.338941) (width 0.15) (layer "In2.Cu") (net 279))
  (segment (start 90.043755 105.191834) (end 90.075987 105.212087) (width 0.15) (layer "In2.Cu") (net 279))
  (segment (start 89.585009 103.075) (end 89.969996 103.075) (width 0.15) (layer "In2.Cu") (net 279))
  (segment (start 89.414396 104.961058) (end 89.410009 105) (width 0.15) (layer "In2.Cu") (net 279))
  (segment (start 90.102904 104.060995) (end 90.075987 104.087912) (width 0.15) (layer "In2.Cu") (net 279))
  (segment (start 89.448188 104.190889) (end 89.427339 104.22407) (width 0.15) (layer "In2.Cu") (net 279))
  (segment (start 90.102904 105.460995) (end 90.075987 105.487912) (width 0.15) (layer "In2.Cu") (net 279))
  (segment (start 89.663941 102.720612) (end 89.625 102.725) (width 0.15) (layer "In2.Cu") (net 279))
  (segment (start 89.475898 103.463179) (end 89.448188 103.490889) (width 0.15) (layer "In2.Cu") (net 279))
  (segment (start 89.414396 103.561058) (end 89.410009 103.6) (width 0.15) (layer "In2.Cu") (net 279))
  (segment (start 90.135729 104.692832) (end 90.123157 104.728763) (width 0.15) (layer "In2.Cu") (net 279))
  (segment (start 89.509079 102.74233) (end 89.475898 102.763179) (width 0.15) (layer "In2.Cu") (net 279))
  (segment (start 90.075987 105.487912) (end 90.043755 105.508165) (width 0.15) (layer "In2.Cu") (net 279))
  (segment (start 89.782669 105.97407) (end 89.795612 106.011058) (width 0.15) (layer "In2.Cu") (net 279))
  (segment (start 90.139991 105.344995) (end 90.139991 105.355005) (width 0.15) (layer "In2.Cu") (net 279))
  (segment (start 89.625 105.875) (end 89.663941 105.879387) (width 0.15) (layer "In2.Cu") (net 279))
  (segment (start 89.414396 102.861058) (end 89.410009 102.9) (width 0.15) (layer "In2.Cu") (net 279))
  (segment (start 90.007824 103.420737) (end 89.969996 103.425) (width 0.15) (layer "In2.Cu") (net 279))
  (segment (start 90.102904 104.539004) (end 90.123157 104.571236) (width 0.15) (layer "In2.Cu") (net 279))
  (segment (start 89.475898 102.763179) (end 89.448188 102.790889) (width 0.15) (layer "In2.Cu") (net 279))
  (segment (start 89.585009 104.475) (end 89.969996 104.475) (width 0.15) (layer "In2.Cu") (net 279))
  (segment (start 90.043755 103.791834) (end 90.075987 103.812087) (width 0.15) (layer "In2.Cu") (net 279))
  (segment (start 89.585009 103.775) (end 89.969996 103.775) (width 0.15) (layer "In2.Cu") (net 279))
  (segment (start 89.969996 103.075) (end 90.007824 103.079262) (width 0.15) (layer "In2.Cu") (net 279))
  (segment (start 90.102904 105.239004) (end 90.123157 105.271236) (width 0.15) (layer "In2.Cu") (net 279))
  (segment (start 89.475898 105.83682) (end 89.509079 105.857669) (width 0.15) (layer "In2.Cu") (net 279))
  (segment (start 89.546067 102.729387) (end 89.509079 102.74233) (width 0.15) (layer "In2.Cu") (net 279))
  (segment (start 90.123157 103.871236) (end 90.135729 103.907167) (width 0.15) (layer "In2.Cu") (net 279))
  (segment (start 89.969996 103.425) (end 89.585009 103.425) (width 0.15) (layer "In2.Cu") (net 279))
  (segment (start 89.585009 105.175) (end 89.969996 105.175) (width 0.15) (layer "In2.Cu") (net 279))
  (segment (start 89.795612 102.588941) (end 89.782669 102.625929) (width 0.15) (layer "In2.Cu") (net 279))
  (segment (start 90.123157 103.328763) (end 90.102904 103.360995) (width 0.15) (layer "In2.Cu") (net 279))
  (segment (start 89.969996 103.775) (end 90.007824 103.779262) (width 0.15) (layer "In2.Cu") (net 279))
  (segment (start 89.475898 104.163179) (end 89.448188 104.190889) (width 0.15) (layer "In2.Cu") (net 279))
  (segment (start 90.123157 103.171236) (end 90.135729 103.207167) (width 0.15) (layer "In2.Cu") (net 279))
  (segment (start 89.448188 103.70911) (end 89.475898 103.73682) (width 0.15) (layer "In2.Cu") (net 279))
  (segment (start 90.135729 103.207167) (end 90.139991 103.244995) (width 0.15) (layer "In2.Cu") (net 279))
  (segment (start 89.509079 105.54233) (end 89.475898 105.563179) (width 0.15) (layer "In2.Cu") (net 279))
  (segment (start 89.585009 105.875) (end 89.625 105.875) (width 0.15) (layer "In2.Cu") (net 279))
  (segment (start 90.043755 104.491834) (end 90.075987 104.512087) (width 0.15) (layer "In2.Cu") (net 279))
  (segment (start 89.509079 104.84233) (end 89.475898 104.863179) (width 0.15) (layer "In2.Cu") (net 279))
  (segment (start 90.075987 104.087912) (end 90.043755 104.108165) (width 0.15) (layer "In2.Cu") (net 279))
  (segment (start 89.475898 105.563179) (end 89.448188 105.590889) (width 0.15) (layer "In2.Cu") (net 279))
  (segment (start 90.007824 105.520737) (end 89.969996 105.525) (width 0.15) (layer "In2.Cu") (net 279))
  (segment (start 89.625 102.725) (end 89.585009 102.725) (width 0.15) (layer "In2.Cu") (net 279))
  (segment (start 89.546067 104.829387) (end 89.509079 104.84233) (width 0.15) (layer "In2.Cu") (net 279))
  (segment (start 89.969996 104.825) (end 89.585009 104.825) (width 0.15) (layer "In2.Cu") (net 279))
  (segment (start 89.427339 104.22407) (end 89.414396 104.261058) (width 0.15) (layer "In2.Cu") (net 279))
  (segment (start 89.448188 104.890889) (end 89.427339 104.92407) (width 0.15) (layer "In2.Cu") (net 279))
  (segment (start 90.007824 103.079262) (end 90.043755 103.091834) (width 0.15) (layer "In2.Cu") (net 279))
  (segment (start 89.448188 105.10911) (end 89.475898 105.13682) (width 0.15) (layer "In2.Cu") (net 279))
  (segment (start 89.546067 105.870612) (end 89.585009 105.875) (width 0.15) (layer "In2.Cu") (net 279))
  (segment (start 89.969996 105.175) (end 90.007824 105.179262) (width 0.15) (layer "In2.Cu") (net 279))
  (segment (start 89.427339 104.375929) (end 89.448188 104.40911) (width 0.15) (layer "In2.Cu") (net 279))
  (segment (start 89.414396 105.038941) (end 89.427339 105.075929) (width 0.15) (layer "In2.Cu") (net 279))
  (segment (start 90.139991 104.655005) (end 90.135729 104.692832) (width 0.15) (layer "In2.Cu") (net 279))
  (segment (start 89.76182 102.65911) (end 89.73411 102.68682) (width 0.15) (layer "In2.Cu") (net 279))
  (segment (start 89.414396 104.338941) (end 89.427339 104.375929) (width 0.15) (layer "In2.Cu") (net 279))
  (segment (start 89.509079 104.14233) (end 89.475898 104.163179) (width 0.15) (layer "In2.Cu") (net 279))
  (segment (start 89.427339 102.975929) (end 89.448188 103.00911) (width 0.15) (layer "In2.Cu") (net 279))
  (segment (start 89.509079 104.457669) (end 89.546067 104.470612) (width 0.15) (layer "In2.Cu") (net 279))
  (segment (start 89.509079 103.057669) (end 89.546067 103.070612) (width 0.15) (layer "In2.Cu") (net 279))
  (segment (start 89.414396 105.738941) (end 89.427339 105.775929) (width 0.15) (layer "In2.Cu") (net 279))
  (segment (start 90.135729 105.307167) (end 90.139991 105.344995) (width 0.15) (layer "In2.Cu") (net 279))
  (segment (start 89.8 116.199002) (end 91.095999 117.495001) (width 0.15) (layer "In2.Cu") (net 279))
  (segment (start 89.509079 103.757669) (end 89.546067 103.770612) (width 0.15) (layer "In2.Cu") (net 279))
  (segment (start 90.102904 104.760995) (end 90.075987 104.787912) (width 0.15) (layer "In2.Cu") (net 279))
  (segment (start 89.448188 104.40911) (end 89.475898 104.43682) (width 0.15) (layer "In2.Cu") (net 279))
  (segment (start 90.123157 105.271236) (end 90.135729 105.307167) (width 0.15) (layer "In2.Cu") (net 279))
  (segment (start 89.585009 104.125) (end 89.546067 104.129387) (width 0.15) (layer "In2.Cu") (net 279))
  (segment (start 89.76182 105.940889) (end 89.782669 105.97407) (width 0.15) (layer "In2.Cu") (net 279))
  (segment (start 89.410009 105) (end 89.414396 105.038941) (width 0.15) (layer "In2.Cu") (net 279))
  (segment (start 90.075987 105.212087) (end 90.102904 105.239004) (width 0.15) (layer "In2.Cu") (net 279))
  (segment (start 89.8 102.55) (end 89.795612 102.588941) (width 0.15) (layer "In2.Cu") (net 279))
  (segment (start 89.410009 105.7) (end 89.414396 105.738941) (width 0.15) (layer "In2.Cu") (net 279))
  (segment (start 90.043755 104.108165) (end 90.007824 104.120737) (width 0.15) (layer "In2.Cu") (net 279))
  (segment (start 90.135729 103.907167) (end 90.139991 103.944995) (width 0.15) (layer "In2.Cu") (net 279))
  (segment (start 89.546067 105.529387) (end 89.509079 105.54233) (width 0.15) (layer "In2.Cu") (net 279))
  (segment (start 90.043755 104.808165) (end 90.007824 104.820737) (width 0.15) (layer "In2.Cu") (net 279))
  (segment (start 90.139991 104.644995) (end 90.139991 104.655005) (width 0.15) (layer "In2.Cu") (net 279))
  (segment (start 93.624989 117.495001) (end 94 117.11999) (width 0.15) (layer "In2.Cu") (net 279))
  (segment (start 90.075987 103.387912) (end 90.043755 103.408165) (width 0.15) (layer "In2.Cu") (net 279))
  (segment (start 89.700929 105.89233) (end 89.73411 105.913179) (width 0.15) (layer "In2.Cu") (net 279))
  (segment (start 89.546067 105.170612) (end 89.585009 105.175) (width 0.15) (layer "In2.Cu") (net 279))
  (segment (start 89.969996 105.525) (end 89.585009 105.525) (width 0.15) (layer "In2.Cu") (net 279))
  (segment (start 90.135729 103.292832) (end 90.123157 103.328763) (width 0.15) (layer "In2.Cu") (net 279))
  (segment (start 90.007824 104.479262) (end 90.043755 104.491834) (width 0.15) (layer "In2.Cu") (net 279))
  (segment (start 89.782669 102.625929) (end 89.76182 102.65911) (width 0.15) (layer "In2.Cu") (net 279))
  (segment (start 89.45 101.75) (end 89.8 102.1) (width 0.15) (layer "B.Cu") (net 279))
  (segment (start 89.45 101.75) (end 89.15 101.75) (width 0.15) (layer "B.Cu") (net 279))
  (segment (start 96.35 116.6) (end 96.8 116.15) (width 0.15) (layer "F.Cu") (net 280))
  (segment (start 95.6 116.6) (end 96.35 116.6) (width 0.15) (layer "F.Cu") (net 280))
  (segment (start 92.3 101.6) (end 92.8 102.1) (width 0.15) (layer "F.Cu") (net 280))
  (via (at 92.8 102.1) (size 0.5) (drill 0.2) (layers "F.Cu" "B.Cu") (net 280))
  (via (at 95.6 116.6) (size 0.5) (drill 0.2) (layers "F.Cu" "B.Cu") (net 280))
  (segment (start 92.573466 106.751737) (end 92.565006 106.765201) (width 0.15) (layer "In2.Cu") (net 280))
  (segment (start 92.584711 107.609507) (end 92.598175 107.617967) (width 0.15) (layer "In2.Cu") (net 280))
  (segment (start 92.557974 105.753987) (end 92.559754 105.769788) (width 0.15) (layer "In2.Cu") (net 280))
  (segment (start 92.557974 102.75) (end 92.559754 102.765801) (width 0.15) (layer "In2.Cu") (net 280))
  (segment (start 92.573466 103.151737) (end 92.565006 103.165201) (width 0.15) (layer "In2.Cu") (net 280))
  (segment (start 92.975405 107.321239) (end 92.942026 107.325) (width 0.15) (layer "In2.Cu") (net 280))
  (segment (start 92.598175 104.617967) (end 92.613185 104.623219) (width 0.15) (layer "In2.Cu") (net 280))
  (segment (start 92.613185 105.823219) (end 92.628987 105.825) (width 0.15) (layer "In2.Cu") (net 280))
  (segment (start 92.557974 105.596013) (end 92.557974 105.753987) (width 0.15) (layer "In2.Cu") (net 280))
  (segment (start 93.092026 105.375) (end 93.088266 105.408378) (width 0.15) (layer "In2.Cu") (net 280))
  (segment (start 93.03555 106.092274) (end 93.007109 106.110145) (width 0.15) (layer "In2.Cu") (net 280))
  (segment (start 92.598175 105.532032) (end 92.584711 105.540492) (width 0.15) (layer "In2.Cu") (net 280))
  (segment (start 92.628987 107.625) (end 92.942026 107.625) (width 0.15) (layer "In2.Cu") (net 280))
  (segment (start 92.584711 105.540492) (end 92.573466 105.551737) (width 0.15) (layer "In2.Cu") (net 280))
  (segment (start 92.714855 108.009917) (end 92.703761 108.041621) (width 0.15) (layer "In2.Cu") (net 280))
  (segment (start 95.6 115.65) (end 95.6 116.6) (width 0.15) (layer "In2.Cu") (net 280))
  (segment (start 93.077172 105.440082) (end 93.059301 105.468523) (width 0.15) (layer "In2.Cu") (net 280))
  (segment (start 93.007109 107.310145) (end 92.975405 107.321239) (width 0.15) (layer "In2.Cu") (net 280))
  (segment (start 92.565006 105.184798) (end 92.573466 105.198262) (width 0.15) (layer "In2.Cu") (net 280))
  (segment (start 92.573466 102.794275) (end 92.584711 102.80552) (width 0.15) (layer "In2.Cu") (net 280))
  (segment (start 92.557974 107.553987) (end 92.559754 107.569788) (width 0.15) (layer "In2.Cu") (net 280))
  (segment (start 93.007109 105.510145) (end 92.975405 105.521239) (width 0.15) (layer "In2.Cu") (net 280))
  (segment (start 92.573466 103.998262) (end 92.584711 104.009507) (width 0.15) (layer "In2.Cu") (net 280))
  (segment (start 93.03555 107.892274) (end 93.007109 107.910145) (width 0.15) (layer "In2.Cu") (net 280))
  (segment (start 93.007109 103.439854) (end 93.03555 103.457725) (width 0.15) (layer "In2.Cu") (net 280))
  (segment (start 92.613185 104.023219) (end 92.628987 104.025) (width 0.15) (layer "In2.Cu") (net 280))
  (segment (start 92.975405 107.921239) (end 92.942026 107.925) (width 0.15) (layer "In2.Cu") (net 280))
  (segment (start 93.03555 103.692274) (end 93.007109 103.710145) (width 0.15) (layer "In2.Cu") (net 280))
  (segment (start 93.007109 106.710145) (end 92.975405 106.721239) (width 0.15) (layer "In2.Cu") (net 280))
  (segment (start 93.088266 106.541621) (end 93.092026 106.575) (width 0.15) (layer "In2.Cu") (net 280))
  (segment (start 92.565006 104.365201) (end 92.559754 104.380211) (width 0.15) (layer "In2.Cu") (net 280))
  (segment (start 92.628987 107.025) (end 92.942026 107.025) (width 0.15) (layer "In2.Cu") (net 280))
  (segment (start 93.03555 105.492274) (end 93.007109 105.510145) (width 0.15) (layer "In2.Cu") (net 280))
  (segment (start 93.007109 103.710145) (end 92.975405 103.721239) (width 0.15) (layer "In2.Cu") (net 280))
  (segment (start 92.598175 103.132032) (end 92.584711 103.140492) (width 0.15) (layer "In2.Cu") (net 280))
  (segment (start 92.942026 103.425) (end 92.975405 103.42876) (width 0.15) (layer "In2.Cu") (net 280))
  (segment (start 92.565006 102.780811) (end 92.573466 102.794275) (width 0.15) (layer "In2.Cu") (net 280))
  (segment (start 92.613185 105.223219) (end 92.628987 105.225) (width 0.15) (layer "In2.Cu") (net 280))
  (segment (start 93.007109 105.239854) (end 93.03555 105.257725) (width 0.15) (layer "In2.Cu") (net 280))
  (segment (start 92.573466 105.198262) (end 92.584711 105.209507) (width 0.15) (layer "In2.Cu") (net 280))
  (segment (start 92.559754 107.380211) (end 92.557974 107.396013) (width 0.15) (layer "In2.Cu") (net 280))
  (segment (start 92.942026 103.725) (end 92.628987 103.725) (width 0.15) (layer "In2.Cu") (net 280))
  (segment (start 93.088266 107.141621) (end 93.092026 107.175) (width 0.15) (layer "In2.Cu") (net 280))
  (segment (start 93.088266 107.208378) (end 93.077172 107.240082) (width 0.15) (layer "In2.Cu") (net 280))
  (segment (start 92.584711 106.140492) (end 92.573466 106.151737) (width 0.15) (layer "In2.Cu") (net 280))
  (segment (start 92.573466 106.998262) (end 92.584711 107.009507) (width 0.15) (layer "In2.Cu") (net 280))
  (segment (start 93.007109 104.310145) (end 92.975405 104.321239) (width 0.15) (layer "In2.Cu") (net 280))
  (segment (start 92.573466 107.351737) (end 92.565006 107.365201) (width 0.15) (layer "In2.Cu") (net 280))
  (segment (start 92.565006 105.565201) (end 92.559754 105.580211) (width 0.15) (layer "In2.Cu") (net 280))
  (segment (start 92.565006 103.165201) (end 92.559754 103.180211) (width 0.15) (layer "In2.Cu") (net 280))
  (segment (start 92.975405 107.62876) (end 93.007109 107.639854) (width 0.15) (layer "In2.Cu") (net 280))
  (segment (start 92.559754 102.765801) (end 92.565006 102.780811) (width 0.15) (layer "In2.Cu") (net 280))
  (segment (start 92.559754 103.780211) (end 92.557974 103.796013) (width 0.15) (layer "In2.Cu") (net 280))
  (segment (start 93.092026 107.775) (end 93.088266 107.808378) (width 0.15) (layer "In2.Cu") (net 280))
  (segment (start 92.942026 107.325) (end 92.628987 107.325) (width 0.15) (layer "In2.Cu") (net 280))
  (segment (start 92.613185 103.72678) (end 92.598175 103.732032) (width 0.15) (layer "In2.Cu") (net 280))
  (segment (start 92.557974 106.796013) (end 92.557974 106.953987) (width 0.15) (layer "In2.Cu") (net 280))
  (segment (start 93.059301 107.081476) (end 93.077172 107.109917) (width 0.15) (layer "In2.Cu") (net 280))
  (segment (start 92.628987 103.125) (end 92.613185 103.12678) (width 0.15) (layer "In2.Cu") (net 280))
  (segment (start 92.584711 106.740492) (end 92.573466 106.751737) (width 0.15) (layer "In2.Cu") (net 280))
  (segment (start 92.557974 106.953987) (end 92.559754 106.969788) (width 0.15) (layer "In2.Cu") (net 280))
  (segment (start 92.942026 106.425) (end 92.975405 106.42876) (width 0.15) (layer "In2.Cu") (net 280))
  (segment (start 92.598175 106.132032) (end 92.584711 106.140492) (width 0.15) (layer "In2.Cu") (net 280))
  (segment (start 93.03555 107.657725) (end 93.059301 107.681476) (width 0.15) (layer "In2.Cu") (net 280))
  (segment (start 93.059301 106.668523) (end 93.03555 106.692274) (width 0.15) (layer "In2.Cu") (net 280))
  (segment (start 92.598175 106.732032) (end 92.584711 106.740492) (width 0.15) (layer "In2.Cu") (net 280))
  (segment (start 92.565006 102.561214) (end 92.559754 102.576224) (width 0.15) (layer "In2.Cu") (net 280))
  (segment (start 92.584711 104.009507) (end 92.598175 104.017967) (width 0.15) (layer "In2.Cu") (net 280))
  (segment (start 92.756477 107.957725) (end 92.732726 107.981476) (width 0.15) (layer "In2.Cu") (net 280))
  (segment (start 93.007109 105.839854) (end 93.03555 105.857725) (width 0.15) (layer "In2.Cu") (net 280))
  (segment (start 93.077172 103.040082) (end 93.059301 103.068523) (width 0.15) (layer "In2.Cu") (net 280))
  (segment (start 92.584711 103.740492) (end 92.573466 103.751737) (width 0.15) (layer "In2.Cu") (net 280))
  (segment (start 92.598175 102.528045) (end 92.584711 102.536505) (width 0.15) (layer "In2.Cu") (net 280))
  (segment (start 92.673262 102.50552) (end 92.659798 102.51398) (width 0.15) (layer "In2.Cu") (net 280))
  (segment (start 92.613185 103.12678) (end 92.598175 103.132032) (width 0.15) (layer "In2.Cu") (net 280))
  (segment (start 92.942026 104.925) (end 92.628987 104.925) (width 0.15) (layer "In2.Cu") (net 280))
  (segment (start 92.573466 104.598262) (end 92.584711 104.609507) (width 0.15) (layer "In2.Cu") (net 280))
  (segment (start 92.613185 107.023219) (end 92.628987 107.025) (width 0.15) (layer "In2.Cu") (net 280))
  (segment (start 93.059301 107.268523) (end 93.03555 107.292274) (width 0.15) (layer "In2.Cu") (net 280))
  (segment (start 92.584711 103.409507) (end 92.598175 103.417967) (width 0.15) (layer "In2.Cu") (net 280))
  (segment (start 92.573466 102.54775) (end 92.565006 102.561214) (width 0.15) (layer "In2.Cu") (net 280))
  (segment (start 92.573466 106.151737) (end 92.565006 106.165201) (width 0.15) (layer "In2.Cu") (net 280))
  (segment (start 93.077172 107.109917) (end 93.088266 107.141621) (width 0.15) (layer "In2.Cu") (net 280))
  (segment (start 92.784918 107.939854) (end 92.756477 107.957725) (width 0.15) (layer "In2.Cu") (net 280))
  (segment (start 92.975405 104.321239) (end 92.942026 104.325) (width 0.15) (layer "In2.Cu") (net 280))
  (segment (start 93.007109 104.039854) (end 93.03555 104.057725) (width 0.15) (layer "In2.Cu") (net 280))
  (segment (start 92.659798 102.51398) (end 92.644788 102.519232) (width 0.15) (layer "In2.Cu") (net 280))
  (segment (start 92.628987 106.125) (end 92.613185 106.12678) (width 0.15) (layer "In2.Cu") (net 280))
  (segment (start 92.565006 107.584798) (end 92.573466 107.598262) (width 0.15) (layer "In2.Cu") (net 280))
  (segment (start 93.03555 104.057725) (end 93.059301 104.081476) (width 0.15) (layer "In2.Cu") (net 280))
  (segment (start 92.598175 104.332032) (end 92.584711 104.340492) (width 0.15) (layer "In2.Cu") (net 280))
  (segment (start 92.584711 102.80552) (end 92.598175 102.81398) (width 0.15) (layer "In2.Cu") (net 280))
  (segment (start 93.077172 103.509917) (end 93.088266 103.541621) (width 0.15) (layer "In2.Cu") (net 280))
  (segment (start 93.077172 104.840082) (end 93.059301 104.868523) (width 0.15) (layer "In2.Cu") (net 280))
  (segment (start 93.059301 104.268523) (end 93.03555 104.292274) (width 0.15) (layer "In2.Cu") (net 280))
  (segment (start 93.088266 102.941621) (end 93.092026 102.975) (width 0.15) (layer "In2.Cu") (net 280))
  (segment (start 92.628987 104.325) (end 92.613185 104.32678) (width 0.15) (layer "In2.Cu") (net 280))
  (segment (start 92.942026 106.125) (end 92.628987 106.125) (width 0.15) (layer "In2.Cu") (net 280))
  (segment (start 93.077172 106.040082) (end 93.059301 106.068523) (width 0.15) (layer "In2.Cu") (net 280))
  (segment (start 92.613185 106.12678) (end 92.598175 106.132032) (width 0.15) (layer "In2.Cu") (net 280))
  (segment (start 92.598175 106.417967) (end 92.613185 106.423219) (width 0.15) (layer "In2.Cu") (net 280))
  (segment (start 93.03555 103.092274) (end 93.007109 103.110145) (width 0.15) (layer "In2.Cu") (net 280))
  (segment (start 92.613185 106.423219) (end 92.628987 106.425) (width 0.15) (layer "In2.Cu") (net 280))
  (segment (start 92.628987 105.525) (end 92.613185 105.52678) (width 0.15) (layer "In2.Cu") (net 280))
  (segment (start 92.613185 102.819232) (end 92.628987 102.821013) (width 0.15) (layer "In2.Cu") (net 280))
  (segment (start 92.942026 105.225) (end 92.975405 105.22876) (width 0.15) (layer "In2.Cu") (net 280))
  (segment (start 92.584711 105.209507) (end 92.598175 105.217967) (width 0.15) (layer "In2.Cu") (net 280))
  (segment (start 92.628987 104.625) (end 92.942026 104.625) (width 0.15) (layer "In2.Cu") (net 280))
  (segment (start 92.7 102.821013) (end 92.7 102.825) (width 0.15) (layer "In2.Cu") (net 280))
  (segment (start 92.975405 106.121239) (end 92.942026 106.125) (width 0.15) (layer "In2.Cu") (net 280))
  (segment (start 92.7 102.45) (end 92.698219 102.465801) (width 0.15) (layer "In2.Cu") (net 280))
  (segment (start 93.007109 103.110145) (end 92.975405 103.121239) (width 0.15) (layer "In2.Cu") (net 280))
  (segment (start 92.975405 106.721239) (end 92.942026 106.725) (width 0.15) (layer "In2.Cu") (net 280))
  (segment (start 92.598175 107.617967) (end 92.613185 107.623219) (width 0.15) (layer "In2.Cu") (net 280))
  (segment (start 92.598175 102.81398) (end 92.613185 102.819232) (width 0.15) (layer "In2.Cu") (net 280))
  (segment (start 93.088266 105.408378) (end 93.077172 105.440082) (width 0.15) (layer "In2.Cu") (net 280))
  (segment (start 92.573466 105.551737) (end 92.565006 105.565201) (width 0.15) (layer "In2.Cu") (net 280))
  (segment (start 93.007109 107.639854) (end 93.03555 107.657725) (width 0.15) (layer "In2.Cu") (net 280))
  (segment (start 92.613185 105.52678) (end 92.598175 105.532032) (width 0.15) (layer "In2.Cu") (net 280))
  (segment (start 92.613185 104.623219) (end 92.628987 104.625) (width 0.15) (layer "In2.Cu") (net 280))
  (segment (start 92.565006 106.165201) (end 92.559754 106.180211) (width 0.15) (layer "In2.Cu") (net 280))
  (segment (start 92.584711 107.009507) (end 92.598175 107.017967) (width 0.15) (layer "In2.Cu") (net 280))
  (segment (start 92.703761 108.041621) (end 92.7 108.075) (width 0.15) (layer "In2.Cu") (net 280))
  (segment (start 92.584711 103.140492) (end 92.573466 103.151737) (width 0.15) (layer "In2.Cu") (net 280))
  (segment (start 92.975405 105.82876) (end 93.007109 105.839854) (width 0.15) (layer "In2.Cu") (net 280))
  (segment (start 93.007109 107.039854) (end 93.03555 107.057725) (width 0.15) (layer "In2.Cu") (net 280))
  (segment (start 92.565006 103.384798) (end 92.573466 103.398262) (width 0.15) (layer "In2.Cu") (net 280))
  (segment (start 93.077172 102.909917) (end 93.088266 102.941621) (width 0.15) (layer "In2.Cu") (net 280))
  (segment (start 93.059301 104.081476) (end 93.077172 104.109917) (width 0.15) (layer "In2.Cu") (net 280))
  (segment (start 93.077172 107.840082) (end 93.059301 107.868523) (width 0.15) (layer "In2.Cu") (net 280))
  (segment (start 92.573466 105.798262) (end 92.584711 105.809507) (width 0.15) (layer "In2.Cu") (net 280))
  (segment (start 93.077172 106.640082) (end 93.059301 106.668523) (width 0.15) (layer "In2.Cu") (net 280))
  (segment (start 92.7 108.075) (end 92.7 108.85) (width 0.15) (layer "In2.Cu") (net 280))
  (segment (start 92.644788 102.519232) (end 92.613185 102.522793) (width 0.15) (layer "In2.Cu") (net 280))
  (segment (start 93.03555 105.257725) (end 93.059301 105.281476) (width 0.15) (layer "In2.Cu") (net 280))
  (segment (start 92.557974 103.196013) (end 92.557974 103.353987) (width 0.15) (layer "In2.Cu") (net 280))
  (segment (start 92.942026 104.025) (end 92.975405 104.02876) (width 0.15) (layer "In2.Cu") (net 280))
  (segment (start 92.598175 107.332032) (end 92.584711 107.340492) (width 0.15) (layer "In2.Cu") (net 280))
  (segment (start 92.584711 104.340492) (end 92.573466 104.351737) (width 0.15) (layer "In2.Cu") (net 280))
  (segment (start 92.565006 104.965201) (end 92.559754 104.980211) (width 0.15) (layer "In2.Cu") (net 280))
  (segment (start 93.007109 104.910145) (end 92.975405 104.921239) (width 0.15) (layer "In2.Cu") (net 280))
  (segment (start 93.088266 104.808378) (end 93.077172 104.840082) (width 0.15) (layer "In2.Cu") (net 280))
  (segment (start 92.628987 105.825) (end 92.942026 105.825) (width 0.15) (layer "In2.Cu") (net 280))
  (segment (start 92.557974 104.396013) (end 92.557974 104.553987) (width 0.15) (layer "In2.Cu") (net 280))
  (segment (start 92.557974 102.592026) (end 92.557974 102.75) (width 0.15) (layer "In2.Cu") (net 280))
  (segment (start 92.598175 105.817967) (end 92.613185 105.823219) (width 0.15) (layer "In2.Cu") (net 280))
  (segment (start 92.942026 104.325) (end 92.628987 104.325) (width 0.15) (layer "In2.Cu") (net 280))
  (segment (start 92.559754 102.576224) (end 92.557974 102.592026) (width 0.15) (layer "In2.Cu") (net 280))
  (segment (start 92.565006 103.765201) (end 92.559754 103.780211) (width 0.15) (layer "In2.Cu") (net 280))
  (segment (start 92.975405 107.02876) (end 93.007109 107.039854) (width 0.15) (layer "In2.Cu") (net 280))
  (segment (start 93.088266 105.941621) (end 93.092026 105.975) (width 0.15) (layer "In2.Cu") (net 280))
  (segment (start 92.598175 103.417967) (end 92.613185 103.423219) (width 0.15) (layer "In2.Cu") (net 280))
  (segment (start 92.557974 106.353987) (end 92.559754 106.369788) (width 0.15) (layer "In2.Cu") (net 280))
  (segment (start 93.03555 106.457725) (end 93.059301 106.481476) (width 0.15) (layer "In2.Cu") (net 280))
  (segment (start 93.088266 104.141621) (end 93.092026 104.175) (width 0.15) (layer "In2.Cu") (net 280))
  (segment (start 93.03555 106.692274) (end 93.007109 106.710145) (width 0.15) (layer "In2.Cu") (net 280))
  (segment (start 92.559754 106.969788) (end 92.565006 106.984798) (width 0.15) (layer "In2.Cu") (net 280))
  (segment (start 93.007109 104.639854) (end 93.03555 104.657725) (width 0.15) (layer "In2.Cu") (net 280))
  (segment (start 92.565006 106.384798) (end 92.573466 106.398262) (width 0.15) (layer "In2.Cu") (net 280))
  (segment (start 93.077172 103.640082) (end 93.059301 103.668523) (width 0.15) (layer "In2.Cu") (net 280))
  (segment (start 92.557974 106.196013) (end 92.557974 106.353987) (width 0.15) (layer "In2.Cu") (net 280))
  (segment (start 93.088266 103.541621) (end 93.092026 103.575) (width 0.15) (layer "In2.Cu") (net 280))
  (segment (start 92.557974 104.996013) (end 92.557974 105.153987) (width 0.15) (layer "In2.Cu") (net 280))
  (segment (start 92.975405 102.82876) (end 93.007109 102.839854) (width 0.15) (layer "In2.Cu") (net 280))
  (segment (start 93.059301 105.281476) (end 93.077172 105.309917) (width 0.15) (layer "In2.Cu") (net 280))
  (segment (start 93.088266 104.208378) (end 93.077172 104.240082) (width 0.15) (layer "In2.Cu") (net 280))
  (segment (start 93.03555 104.657725) (end 93.059301 104.681476) (width 0.15) (layer "In2.Cu") (net 280))
  (segment (start 92.942026 103.125) (end 92.628987 103.125) (width 0.15) (layer "In2.Cu") (net 280))
  (segment (start 92.559754 106.369788) (end 92.565006 106.384798) (width 0.15) (layer "In2.Cu") (net 280))
  (segment (start 92.573466 106.398262) (end 92.584711 106.409507) (width 0.15) (layer "In2.Cu") (net 280))
  (segment (start 92.584711 106.409507) (end 92.598175 106.417967) (width 0.15) (layer "In2.Cu") (net 280))
  (segment (start 92.557974 107.396013) (end 92.557974 107.553987) (width 0.15) (layer "In2.Cu") (net 280))
  (segment (start 92.557974 104.553987) (end 92.559754 104.569788) (width 0.15) (layer "In2.Cu") (net 280))
  (segment (start 92.975405 103.721239) (end 92.942026 103.725) (width 0.15) (layer "In2.Cu") (net 280))
  (segment (start 92.628987 106.425) (end 92.942026 106.425) (width 0.15) (layer "In2.Cu") (net 280))
  (segment (start 93.03555 102.857725) (end 93.059301 102.881476) (width 0.15) (layer "In2.Cu") (net 280))
  (segment (start 92.628987 103.425) (end 92.942026 103.425) (width 0.15) (layer "In2.Cu") (net 280))
  (segment (start 93.088266 107.741621) (end 93.092026 107.775) (width 0.15) (layer "In2.Cu") (net 280))
  (segment (start 92.573466 107.598262) (end 92.584711 107.609507) (width 0.15) (layer "In2.Cu") (net 280))
  (segment (start 93.092026 104.175) (end 93.088266 104.208378) (width 0.15) (layer "In2.Cu") (net 280))
  (segment (start 92.557974 103.353987) (end 92.559754 103.369788) (width 0.15) (layer "In2.Cu") (net 280))
  (segment (start 92.573466 104.351737) (end 92.565006 104.365201) (width 0.15) (layer "In2.Cu") (net 280))
  (segment (start 92.559754 104.569788) (end 92.565006 104.584798) (width 0.15) (layer "In2.Cu") (net 280))
  (segment (start 92.628987 104.025) (end 92.942026 104.025) (width 0.15) (layer "In2.Cu") (net 280))
  (segment (start 93.092026 103.575) (end 93.088266 103.608378) (width 0.15) (layer "In2.Cu") (net 280))
  (segment (start 92.613185 106.72678) (end 92.598175 106.732032) (width 0.15) (layer "In2.Cu") (net 280))
  (segment (start 92.559754 105.169788) (end 92.565006 105.184798) (width 0.15) (layer "In2.Cu") (net 280))
  (segment (start 92.942026 107.925) (end 92.85 107.925) (width 0.15) (layer "In2.Cu") (net 280))
  (segment (start 92.559754 106.180211) (end 92.557974 106.196013) (width 0.15) (layer "In2.Cu") (net 280))
  (segment (start 92.613185 107.623219) (end 92.628987 107.625) (width 0.15) (layer "In2.Cu") (net 280))
  (segment (start 93.25 109.4) (end 93.25 113.3) (width 0.15) (layer "In2.Cu") (net 280))
  (segment (start 92.613185 104.32678) (end 92.598175 104.332032) (width 0.15) (layer "In2.Cu") (net 280))
  (segment (start 92.557974 105.153987) (end 92.559754 105.169788) (width 0.15) (layer "In2.Cu") (net 280))
  (segment (start 92.628987 102.821013) (end 92.7 102.821013) (width 0.15) (layer "In2.Cu") (net 280))
  (segment (start 92.559754 103.969788) (end 92.565006 103.984798) (width 0.15) (layer "In2.Cu") (net 280))
  (segment (start 92.942026 102.825) (end 92.975405 102.82876) (width 0.15) (layer "In2.Cu") (net 280))
  (segment (start 92.628987 104.925) (end 92.613185 104.92678) (width 0.15) (layer "In2.Cu") (net 280))
  (segment (start 92.598175 103.732032) (end 92.584711 103.740492) (width 0.15) (layer "In2.Cu") (net 280))
  (segment (start 93.059301 103.481476) (end 93.077172 103.509917) (width 0.15) (layer "In2.Cu") (net 280))
  (segment (start 92.557974 103.953987) (end 92.559754 103.969788) (width 0.15) (layer "In2.Cu") (net 280))
  (segment (start 92.975405 103.42876) (end 93.007109 103.439854) (width 0.15) (layer "In2.Cu") (net 280))
  (segment (start 92.584711 107.340492) (end 92.573466 107.351737) (width 0.15) (layer "In2.Cu") (net 280))
  (segment (start 92.7 102.825) (end 92.942026 102.825) (width 0.15) (layer "In2.Cu") (net 280))
  (segment (start 92.613185 102.522793) (end 92.598175 102.528045) (width 0.15) (layer "In2.Cu") (net 280))
  (segment (start 92.975405 105.22876) (end 93.007109 105.239854) (width 0.15) (layer "In2.Cu") (net 280))
  (segment (start 93.007109 102.839854) (end 93.03555 102.857725) (width 0.15) (layer "In2.Cu") (net 280))
  (segment (start 93.077172 107.709917) (end 93.088266 107.741621) (width 0.15) (layer "In2.Cu") (net 280))
  (segment (start 93.03555 104.292274) (end 93.007109 104.310145) (width 0.15) (layer "In2.Cu") (net 280))
  (segment (start 92.557974 103.796013) (end 92.557974 103.953987) (width 0.15) (layer "In2.Cu") (net 280))
  (segment (start 92.559754 107.569788) (end 92.565006 107.584798) (width 0.15) (layer "In2.Cu") (net 280))
  (segment (start 92.975405 104.62876) (end 93.007109 104.639854) (width 0.15) (layer "In2.Cu") (net 280))
  (segment (start 92.559754 103.369788) (end 92.565006 103.384798) (width 0.15) (layer "In2.Cu") (net 280))
  (segment (start 92.584711 104.609507) (end 92.598175 104.617967) (width 0.15) (layer "In2.Cu") (net 280))
  (segment (start 92.584711 105.809507) (end 92.598175 105.817967) (width 0.15) (layer "In2.Cu") (net 280))
  (segment (start 92.565006 107.365201) (end 92.559754 107.380211) (width 0.15) (layer "In2.Cu") (net 280))
  (segment (start 93.088266 104.741621) (end 93.092026 104.775) (width 0.15) (layer "In2.Cu") (net 280))
  (segment (start 93.059301 107.681476) (end 93.077172 107.709917) (width 0.15) (layer "In2.Cu") (net 280))
  (segment (start 93.059301 102.881476) (end 93.077172 102.909917) (width 0.15) (layer "In2.Cu") (net 280))
  (segment (start 92.584711 104.940492) (end 92.573466 104.951737) (width 0.15) (layer "In2.Cu") (net 280))
  (segment (start 92.598175 107.017967) (end 92.613185 107.023219) (width 0.15) (layer "In2.Cu") (net 280))
  (segment (start 92.7 108.85) (end 93.25 109.4) (width 0.15) (layer "In2.Cu") (net 280))
  (segment (start 92.698219 102.465801) (end 92.692967 102.480811) (width 0.15) (layer "In2.Cu") (net 280))
  (segment (start 93.077172 104.109917) (end 93.088266 104.141621) (width 0.15) (layer "In2.Cu") (net 280))
  (segment (start 92.942026 104.625) (end 92.975405 104.62876) (width 0.15) (layer "In2.Cu") (net 280))
  (segment (start 92.816622 107.92876) (end 92.784918 107.939854) (width 0.15) (layer "In2.Cu") (net 280))
  (segment (start 92.559754 105.769788) (end 92.565006 105.784798) (width 0.15) (layer "In2.Cu") (net 280))
  (segment (start 92.628987 105.225) (end 92.942026 105.225) (width 0.15) (layer "In2.Cu") (net 280))
  (segment (start 93.007109 106.110145) (end 92.975405 106.121239) (width 0.15) (layer "In2.Cu") (net 280))
  (segment (start 93.088266 103.608378) (end 93.077172 103.640082) (width 0.15) (layer "In2.Cu") (net 280))
  (segment (start 92.613185 104.92678) (end 92.598175 104.932032) (width 0.15) (layer "In2.Cu") (net 280))
  (segment (start 92.8 102.1) (end 92.7 102.2) (width 0.15) (layer "In2.Cu") (net 280))
  (segment (start 93.059301 104.868523) (end 93.03555 104.892274) (width 0.15) (layer "In2.Cu") (net 280))
  (segment (start 93.059301 105.468523) (end 93.03555 105.492274) (width 0.15) (layer "In2.Cu") (net 280))
  (segment (start 93.059301 103.668523) (end 93.03555 103.692274) (width 0.15) (layer "In2.Cu") (net 280))
  (segment (start 92.975405 106.42876) (end 93.007109 106.439854) (width 0.15) (layer "In2.Cu") (net 280))
  (segment (start 93.007109 107.910145) (end 92.975405 107.921239) (width 0.15) (layer "In2.Cu") (net 280))
  (segment (start 92.598175 104.017967) (end 92.613185 104.023219) (width 0.15) (layer "In2.Cu") (net 280))
  (segment (start 93.092026 102.975) (end 93.088266 103.008378) (width 0.15) (layer "In2.Cu") (net 280))
  (segment (start 92.565006 104.584798) (end 92.573466 104.598262) (width 0.15) (layer "In2.Cu") (net 280))
  (segment (start 92.732726 107.981476) (end 92.714855 108.009917) (width 0.15) (layer "In2.Cu") (net 280))
  (segment (start 92.975405 104.921239) (end 92.942026 104.925) (width 0.15) (layer "In2.Cu") (net 280))
  (segment (start 92.559754 104.380211) (end 92.557974 104.396013) (width 0.15) (layer "In2.Cu") (net 280))
  (segment (start 93.03555 105.857725) (end 93.059301 105.881476) (width 0.15) (layer "In2.Cu") (net 280))
  (segment (start 92.598175 105.217967) (end 92.613185 105.223219) (width 0.15) (layer "In2.Cu") (net 280))
  (segment (start 92.559754 106.780211) (end 92.557974 106.796013) (width 0.15) (layer "In2.Cu") (net 280))
  (segment (start 92.975405 103.121239) (end 92.942026 103.125) (width 0.15) (layer "In2.Cu") (net 280))
  (segment (start 92.628987 106.725) (end 92.613185 106.72678) (width 0.15) (layer "In2.Cu") (net 280))
  (segment (start 92.573466 104.951737) (end 92.565006 104.965201) (width 0.15) (layer "In2.Cu") (net 280))
  (segment (start 93.059301 104.681476) (end 93.077172 104.709917) (width 0.15) (layer "In2.Cu") (net 280))
  (segment (start 92.628987 103.725) (end 92.613185 103.72678) (width 0.15) (layer "In2.Cu") (net 280))
  (segment (start 93.092026 104.775) (end 93.088266 104.808378) (width 0.15) (layer "In2.Cu") (net 280))
  (segment (start 93.077172 105.909917) (end 93.088266 105.941621) (width 0.15) (layer "In2.Cu") (net 280))
  (segment (start 92.559754 105.580211) (end 92.557974 105.596013) (width 0.15) (layer "In2.Cu") (net 280))
  (segment (start 92.565006 106.984798) (end 92.573466 106.998262) (width 0.15) (layer "In2.Cu") (net 280))
  (segment (start 93.092026 107.175) (end 93.088266 107.208378) (width 0.15) (layer "In2.Cu") (net 280))
  (segment (start 92.942026 107.625) (end 92.975405 107.62876) (width 0.15) (layer "In2.Cu") (net 280))
  (segment (start 93.077172 107.240082) (end 93.059301 107.268523) (width 0.15) (layer "In2.Cu") (net 280))
  (segment (start 92.942026 105.825) (end 92.975405 105.82876) (width 0.15) (layer "In2.Cu") (net 280))
  (segment (start 92.565006 106.765201) (end 92.559754 106.780211) (width 0.15) (layer "In2.Cu") (net 280))
  (segment (start 92.565006 105.784798) (end 92.573466 105.798262) (width 0.15) (layer "In2.Cu") (net 280))
  (segment (start 92.573466 103.751737) (end 92.565006 103.765201) (width 0.15) (layer "In2.Cu") (net 280))
  (segment (start 92.85 107.925) (end 92.816622 107.92876) (width 0.15) (layer "In2.Cu") (net 280))
  (segment (start 92.584711 102.536505) (end 92.573466 102.54775) (width 0.15) (layer "In2.Cu") (net 280))
  (segment (start 92.7 102.2) (end 92.7 102.45) (width 0.15) (layer "In2.Cu") (net 280))
  (segment (start 92.598175 104.932032) (end 92.584711 104.940492) (width 0.15) (layer "In2.Cu") (net 280))
  (segment (start 93.03555 103.457725) (end 93.059301 103.481476) (width 0.15) (layer "In2.Cu") (net 280))
  (segment (start 93.077172 104.240082) (end 93.059301 104.268523) (width 0.15) (layer "In2.Cu") (net 280))
  (segment (start 93.059301 106.481476) (end 93.077172 106.509917) (width 0.15) (layer "In2.Cu") (net 280))
  (segment (start 92.565006 103.984798) (end 92.573466 103.998262) (width 0.15) (layer "In2.Cu") (net 280))
  (segment (start 93.088266 103.008378) (end 93.077172 103.040082) (width 0.15) (layer "In2.Cu") (net 280))
  (segment (start 92.559754 104.980211) (end 92.557974 104.996013) (width 0.15) (layer "In2.Cu") (net 280))
  (segment (start 93.088266 106.008378) (end 93.077172 106.040082) (width 0.15) (layer "In2.Cu") (net 280))
  (segment (start 93.088266 106.608378) (end 93.077172 106.640082) (width 0.15) (layer "In2.Cu") (net 280))
  (segment (start 93.059301 105.881476) (end 93.077172 105.909917) (width 0.15) (layer "In2.Cu") (net 280))
  (segment (start 93.077172 105.309917) (end 93.088266 105.341621) (width 0.15) (layer "In2.Cu") (net 280))
  (segment (start 93.088266 107.808378) (end 93.077172 107.840082) (width 0.15) (layer "In2.Cu") (net 280))
  (segment (start 93.059301 103.068523) (end 93.03555 103.092274) (width 0.15) (layer "In2.Cu") (net 280))
  (segment (start 93.092026 106.575) (end 93.088266 106.608378) (width 0.15) (layer "In2.Cu") (net 280))
  (segment (start 93.077172 106.509917) (end 93.088266 106.541621) (width 0.15) (layer "In2.Cu") (net 280))
  (segment (start 92.692967 102.480811) (end 92.684507 102.494275) (width 0.15) (layer "In2.Cu") (net 280))
  (segment (start 93.092026 105.975) (end 93.088266 106.008378) (width 0.15) (layer "In2.Cu") (net 280))
  (segment (start 92.684507 102.494275) (end 92.673262 102.50552) (width 0.15) (layer "In2.Cu") (net 280))
  (segment (start 93.007109 106.439854) (end 93.03555 106.457725) (width 0.15) (layer "In2.Cu") (net 280))
  (segment (start 92.942026 106.725) (end 92.628987 106.725) (width 0.15) (layer "In2.Cu") (net 280))
  (segment (start 92.942026 107.025) (end 92.975405 107.02876) (width 0.15) (layer "In2.Cu") (net 280))
  (segment (start 92.942026 105.525) (end 92.628987 105.525) (width 0.15) (layer "In2.Cu") (net 280))
  (segment (start 93.03555 104.892274) (end 93.007109 104.910145) (width 0.15) (layer "In2.Cu") (net 280))
  (segment (start 93.25 113.3) (end 95.6 115.65) (width 0.15) (layer "In2.Cu") (net 280))
  (segment (start 93.077172 104.709917) (end 93.088266 104.741621) (width 0.15) (layer "In2.Cu") (net 280))
  (segment (start 92.975405 104.02876) (end 93.007109 104.039854) (width 0.15) (layer "In2.Cu") (net 280))
  (segment (start 92.975405 105.521239) (end 92.942026 105.525) (width 0.15) (layer "In2.Cu") (net 280))
  (segment (start 92.573466 103.398262) (end 92.584711 103.409507) (width 0.15) (layer "In2.Cu") (net 280))
  (segment (start 93.088266 105.341621) (end 93.092026 105.375) (width 0.15) (layer "In2.Cu") (net 280))
  (segment (start 92.559754 103.180211) (end 92.557974 103.196013) (width 0.15) (layer "In2.Cu") (net 280))
  (segment (start 92.613185 103.423219) (end 92.628987 103.425) (width 0.15) (layer "In2.Cu") (net 280))
  (segment (start 93.059301 106.068523) (end 93.03555 106.092274) (width 0.15) (layer "In2.Cu") (net 280))
  (segment (start 93.03555 107.292274) (end 93.007109 107.310145) (width 0.15) (layer "In2.Cu") (net 280))
  (segment (start 93.059301 107.868523) (end 93.03555 107.892274) (width 0.15) (layer "In2.Cu") (net 280))
  (segment (start 92.628987 107.325) (end 92.613185 107.32678) (width 0.15) (layer "In2.Cu") (net 280))
  (segment (start 93.03555 107.057725) (end 93.059301 107.081476) (width 0.15) (layer "In2.Cu") (net 280))
  (segment (start 92.613185 107.32678) (end 92.598175 107.332032) (width 0.15) (layer "In2.Cu") (net 280))
  (segment (start 93.3 101.6) (end 94.05 101.6) (width 0.15) (layer "B.Cu") (net 280))
  (segment (start 93.3 101.6) (end 92.8 102.1) (width 0.15) (layer "B.Cu") (net 280))
  (segment (start 92.92 117.07) (end 91.28 117.07) (width 0.15) (layer "F.Cu") (net 281))
  (segment (start 93.6 117.75) (end 92.92 117.07) (width 0.15) (layer "F.Cu") (net 281))
  (segment (start 89.3 100.6) (end 89.8 101.1) (width 0.15) (layer "F.Cu") (net 281))
  (via (at 89.8 101.1) (size 0.5) (drill 0.2) (layers "F.Cu" "B.Cu") (net 281))
  (via (at 91.28 117.07) (size 0.5) (drill 0.2) (layers "F.Cu" "B.Cu") (net 281))
  (segment (start 90.979236 103.337378) (end 91.002937 103.352271) (width 0.15) (layer "In2.Cu") (net 281))
  (segment (start 90.404387 104.511058) (end 90.4 104.55) (width 0.15) (layer "In2.Cu") (net 281))
  (segment (start 90.536058 102.279387) (end 90.49907 102.29233) (width 0.15) (layer "In2.Cu") (net 281))
  (segment (start 90.925 105.425) (end 90.952816 105.428134) (width 0.15) (layer "In2.Cu") (net 281))
  (segment (start 90.536058 103.320612) (end 90.575 103.325) (width 0.15) (layer "In2.Cu") (net 281))
  (segment (start 90.465889 103.28682) (end 90.49907 103.307669) (width 0.15) (layer "In2.Cu") (net 281))
  (segment (start 91.022729 104.327936) (end 91.002937 104.347728) (width 0.15) (layer "In2.Cu") (net 281))
  (segment (start 91.022729 103.627936) (end 91.002937 103.647728) (width 0.15) (layer "In2.Cu") (net 281))
  (segment (start 90.536058 105.779387) (end 90.49907 105.79233) (width 0.15) (layer "In2.Cu") (net 281))
  (segment (start 91.022729 105.027936) (end 91.002937 105.047728) (width 0.15) (layer "In2.Cu") (net 281))
  (segment (start 90.404387 102.411058) (end 90.4 102.45) (width 0.15) (layer "In2.Cu") (net 281))
  (segment (start 90.925 102.625) (end 90.952816 102.628134) (width 0.15) (layer "In2.Cu") (net 281))
  (segment (start 91.05 104.85) (end 91.05 104.95) (width 0.15) (layer "In2.Cu") (net 281))
  (segment (start 90.925 104.025) (end 90.952816 104.028134) (width 0.15) (layer "In2.Cu") (net 281))
  (segment (start 90.536058 102.979387) (end 90.49907 102.99233) (width 0.15) (layer "In2.Cu") (net 281))
  (segment (start 90.465889 103.713179) (end 90.438179 103.740889) (width 0.15) (layer "In2.Cu") (net 281))
  (segment (start 90.700929 102.257669) (end 90.663941 102.270612) (width 0.15) (layer "In2.Cu") (net 281))
  (segment (start 90.404387 103.811058) (end 90.4 103.85) (width 0.15) (layer "In2.Cu") (net 281))
  (segment (start 90.625 106.125) (end 90.663941 106.129387) (width 0.15) (layer "In2.Cu") (net 281))
  (segment (start 91.05 105.55) (end 91.05 105.65) (width 0.15) (layer "In2.Cu") (net 281))
  (segment (start 91.002937 105.047728) (end 90.979236 105.062621) (width 0.15) (layer "In2.Cu") (net 281))
  (segment (start 90.575 104.025) (end 90.925 104.025) (width 0.15) (layer "In2.Cu") (net 281))
  (segment (start 90.979236 104.737378) (end 91.002937 104.752271) (width 0.15) (layer "In2.Cu") (net 281))
  (segment (start 90.625 102.275) (end 90.575 102.275) (width 0.15) (layer "In2.Cu") (net 281))
  (segment (start 90.952816 103.328134) (end 90.979236 103.337378) (width 0.15) (layer "In2.Cu") (net 281))
  (segment (start 90.41733 105.87407) (end 90.404387 105.911058) (width 0.15) (layer "In2.Cu") (net 281))
  (segment (start 91.037622 102.904235) (end 91.022729 102.927936) (width 0.15) (layer "In2.Cu") (net 281))
  (segment (start 90.575 104.375) (end 90.536058 104.379387) (width 0.15) (layer "In2.Cu") (net 281))
  (segment (start 90.49907 105.79233) (end 90.465889 105.813179) (width 0.15) (layer "In2.Cu") (net 281))
  (segment (start 91.05 104.25) (end 91.046866 104.277815) (width 0.15) (layer "In2.Cu") (net 281))
  (segment (start 91.046866 105.522184) (end 91.05 105.55) (width 0.15) (layer "In2.Cu") (net 281))
  (segment (start 90.952816 105.771865) (end 90.925 105.775) (width 0.15) (layer "In2.Cu") (net 281))
  (segment (start 91.037622 104.304235) (end 91.022729 104.327936) (width 0.15) (layer "In2.Cu") (net 281))
  (segment (start 91.002937 104.752271) (end 91.022729 104.772063) (width 0.15) (layer "In2.Cu") (net 281))
  (segment (start 90.465889 105.38682) (end 90.49907 105.407669) (width 0.15) (layer "In2.Cu") (net 281))
  (segment (start 91.002937 103.352271) (end 91.022729 103.372063) (width 0.15) (layer "In2.Cu") (net 281))
  (segment (start 90.49907 103.307669) (end 90.536058 103.320612) (width 0.15) (layer "In2.Cu") (net 281))
  (segment (start 90.404387 105.211058) (end 90.4 105.25) (width 0.15) (layer "In2.Cu") (net 281))
  (segment (start 90.438179 105.35911) (end 90.465889 105.38682) (width 0.15) (layer "In2.Cu") (net 281))
  (segment (start 90.404387 105.288941) (end 90.41733 105.325929) (width 0.15) (layer "In2.Cu") (net 281))
  (segment (start 90.8 116.59) (end 91.28 117.07) (width 0.15) (layer "In2.Cu") (net 281))
  (segment (start 90.979236 104.037378) (end 91.002937 104.052271) (width 0.15) (layer "In2.Cu") (net 281))
  (segment (start 91.037622 105.495764) (end 91.046866 105.522184) (width 0.15) (layer "In2.Cu") (net 281))
  (segment (start 91.002937 104.052271) (end 91.022729 104.072063) (width 0.15) (layer "In2.Cu") (net 281))
  (segment (start 90.438179 103.25911) (end 90.465889 103.28682) (width 0.15) (layer "In2.Cu") (net 281))
  (segment (start 90.4 102.45) (end 90.404387 102.488941) (width 0.15) (layer "In2.Cu") (net 281))
  (segment (start 90.979236 105.437378) (end 91.002937 105.452271) (width 0.15) (layer "In2.Cu") (net 281))
  (segment (start 90.8 102.1) (end 90.795612 102.138941) (width 0.15) (layer "In2.Cu") (net 281))
  (segment (start 91.037622 104.095764) (end 91.046866 104.122184) (width 0.15) (layer "In2.Cu") (net 281))
  (segment (start 90.979236 102.637378) (end 91.002937 102.652271) (width 0.15) (layer "In2.Cu") (net 281))
  (segment (start 90.536058 104.379387) (end 90.49907 104.39233) (width 0.15) (layer "In2.Cu") (net 281))
  (segment (start 90.536058 102.620612) (end 90.575 102.625) (width 0.15) (layer "In2.Cu") (net 281))
  (segment (start 90.41733 102.37407) (end 90.404387 102.411058) (width 0.15) (layer "In2.Cu") (net 281))
  (segment (start 91.046866 104.122184) (end 91.05 104.15) (width 0.15) (layer "In2.Cu") (net 281))
  (segment (start 90.979236 105.762621) (end 90.952816 105.771865) (width 0.15) (layer "In2.Cu") (net 281))
  (segment (start 90.76182 102.20911) (end 90.73411 102.23682) (width 0.15) (layer "In2.Cu") (net 281))
  (segment (start 91.046866 103.422184) (end 91.05 103.45) (width 0.15) (layer "In2.Cu") (net 281))
  (segment (start 90.438179 103.95911) (end 90.465889 103.98682) (width 0.15) (layer "In2.Cu") (net 281))
  (segment (start 90.438179 104.440889) (end 90.41733 104.47407) (width 0.15) (layer "In2.Cu") (net 281))
  (segment (start 91.002937 102.947728) (end 90.979236 102.962621) (width 0.15) (layer "In2.Cu") (net 281))
  (segment (start 90.952816 103.671865) (end 90.925 103.675) (width 0.15) (layer "In2.Cu") (net 281))
  (segment (start 90.4 103.15) (end 90.404387 103.188941) (width 0.15) (layer "In2.Cu") (net 281))
  (segment (start 90.49907 102.99233) (end 90.465889 103.013179) (width 0.15) (layer "In2.Cu") (net 281))
  (segment (start 91.022729 105.727936) (end 91.002937 105.747728) (width 0.15) (layer "In2.Cu") (net 281))
  (segment (start 91.05 105.65) (end 91.046866 105.677815) (width 0.15) (layer "In2.Cu") (net 281))
  (segment (start 90.782669 102.175929) (end 90.76182 102.20911) (width 0.15) (layer "In2.Cu") (net 281))
  (segment (start 90.465889 102.313179) (end 90.438179 102.340889) (width 0.15) (layer "In2.Cu") (net 281))
  (segment (start 90.404387 105.911058) (end 90.4 105.95) (width 0.15) (layer "In2.Cu") (net 281))
  (segment (start 90.41733 103.77407) (end 90.404387 103.811058) (width 0.15) (layer "In2.Cu") (net 281))
  (segment (start 91.022729 102.672063) (end 91.037622 102.695764) (width 0.15) (layer "In2.Cu") (net 281))
  (segment (start 90.952816 104.371865) (end 90.925 104.375) (width 0.15) (layer "In2.Cu") (net 281))
  (segment (start 91.046866 102.722184) (end 91.05 102.75) (width 0.15) (layer "In2.Cu") (net 281))
  (segment (start 90.925 103.675) (end 90.575 103.675) (width 0.15) (layer "In2.Cu") (net 281))
  (segment (start 90.663941 106.129387) (end 90.700929 106.14233) (width 0.15) (layer "In2.Cu") (net 281))
  (segment (start 90.575 105.775) (end 90.536058 105.779387) (width 0.15) (layer "In2.Cu") (net 281))
  (segment (start 91.05 104.95) (end 91.046866 104.977815) (width 0.15) (layer "In2.Cu") (net 281))
  (segment (start 91.05 104.15) (end 91.05 104.25) (width 0.15) (layer "In2.Cu") (net 281))
  (segment (start 90.438179 104.65911) (end 90.465889 104.68682) (width 0.15) (layer "In2.Cu") (net 281))
  (segment (start 91.046866 102.877815) (end 91.037622 102.904235) (width 0.15) (layer "In2.Cu") (net 281))
  (segment (start 90.8 106.3) (end 90.8 116.59) (width 0.15) (layer "In2.Cu") (net 281))
  (segment (start 90.952816 102.971865) (end 90.925 102.975) (width 0.15) (layer "In2.Cu") (net 281))
  (segment (start 90.979236 103.662621) (end 90.952816 103.671865) (width 0.15) (layer "In2.Cu") (net 281))
  (segment (start 90.438179 102.55911) (end 90.465889 102.58682) (width 0.15) (layer "In2.Cu") (net 281))
  (segment (start 90.465889 103.98682) (end 90.49907 104.007669) (width 0.15) (layer "In2.Cu") (net 281))
  (segment (start 90.536058 103.679387) (end 90.49907 103.69233) (width 0.15) (layer "In2.Cu") (net 281))
  (segment (start 91.046866 104.977815) (end 91.037622 105.004235) (width 0.15) (layer "In2.Cu") (net 281))
  (segment (start 91.046866 104.822184) (end 91.05 104.85) (width 0.15) (layer "In2.Cu") (net 281))
  (segment (start 90.41733 103.07407) (end 90.404387 103.111058) (width 0.15) (layer "In2.Cu") (net 281))
  (segment (start 91.037622 103.604235) (end 91.022729 103.627936) (width 0.15) (layer "In2.Cu") (net 281))
  (segment (start 90.536058 104.020612) (end 90.575 104.025) (width 0.15) (layer "In2.Cu") (net 281))
  (segment (start 90.536058 105.079387) (end 90.49907 105.09233) (width 0.15) (layer "In2.Cu") (net 281))
  (segment (start 90.4 105.95) (end 90.404387 105.988941) (width 0.15) (layer "In2.Cu") (net 281))
  (segment (start 90.536058 105.420612) (end 90.575 105.425) (width 0.15) (layer "In2.Cu") (net 281))
  (segment (start 90.952816 105.428134) (end 90.979236 105.437378) (width 0.15) (layer "In2.Cu") (net 281))
  (segment (start 90.41733 104.625929) (end 90.438179 104.65911) (width 0.15) (layer "In2.Cu") (net 281))
  (segment (start 91.002937 104.347728) (end 90.979236 104.362621) (width 0.15) (layer "In2.Cu") (net 281))
  (segment (start 90.575 103.325) (end 90.925 103.325) (width 0.15) (layer "In2.Cu") (net 281))
  (segment (start 90.782669 106.22407) (end 90.795612 106.261058) (width 0.15) (layer "In2.Cu") (net 281))
  (segment (start 90.536058 106.120612) (end 90.575 106.125) (width 0.15) (layer "In2.Cu") (net 281))
  (segment (start 90.404387 103.888941) (end 90.41733 103.925929) (width 0.15) (layer "In2.Cu") (net 281))
  (segment (start 91.05 103.55) (end 91.046866 103.577815) (width 0.15) (layer "In2.Cu") (net 281))
  (segment (start 90.404387 105.988941) (end 90.41733 106.025929) (width 0.15) (layer "In2.Cu") (net 281))
  (segment (start 90.795612 102.138941) (end 90.782669 102.175929) (width 0.15) (layer "In2.Cu") (net 281))
  (segment (start 90.979236 104.362621) (end 90.952816 104.371865) (width 0.15) (layer "In2.Cu") (net 281))
  (segment (start 90.536058 104.720612) (end 90.575 104.725) (width 0.15) (layer "In2.Cu") (net 281))
  (segment (start 90.73411 102.23682) (end 90.700929 102.257669) (width 0.15) (layer "In2.Cu") (net 281))
  (segment (start 91.002937 105.452271) (end 91.022729 105.472063) (width 0.15) (layer "In2.Cu") (net 281))
  (segment (start 90.41733 102.525929) (end 90.438179 102.55911) (width 0.15) (layer "In2.Cu") (net 281))
  (segment (start 90.663941 102.270612) (end 90.625 102.275) (width 0.15) (layer "In2.Cu") (net 281))
  (segment (start 90.465889 105.113179) (end 90.438179 105.140889) (width 0.15) (layer "In2.Cu") (net 281))
  (segment (start 90.41733 103.925929) (end 90.438179 103.95911) (width 0.15) (layer "In2.Cu") (net 281))
  (segment (start 90.49907 104.007669) (end 90.536058 104.020612) (width 0.15) (layer "In2.Cu") (net 281))
  (segment (start 90.404387 104.588941) (end 90.41733 104.625929) (width 0.15) (layer "In2.Cu") (net 281))
  (segment (start 91.05 102.75) (end 91.05 102.85) (width 0.15) (layer "In2.Cu") (net 281))
  (segment (start 90.4 103.85) (end 90.404387 103.888941) (width 0.15) (layer "In2.Cu") (net 281))
  (segment (start 91.022729 104.772063) (end 91.037622 104.795764) (width 0.15) (layer "In2.Cu") (net 281))
  (segment (start 90.438179 103.040889) (end 90.41733 103.07407) (width 0.15) (layer "In2.Cu") (net 281))
  (segment (start 91.05 103.45) (end 91.05 103.55) (width 0.15) (layer "In2.Cu") (net 281))
  (segment (start 91.022729 104.072063) (end 91.037622 104.095764) (width 0.15) (layer "In2.Cu") (net 281))
  (segment (start 90.404387 103.111058) (end 90.4 103.15) (width 0.15) (layer "In2.Cu") (net 281))
  (segment (start 91.002937 103.647728) (end 90.979236 103.662621) (width 0.15) (layer "In2.Cu") (net 281))
  (segment (start 90.952816 102.628134) (end 90.979236 102.637378) (width 0.15) (layer "In2.Cu") (net 281))
  (segment (start 91.046866 105.677815) (end 91.037622 105.704235) (width 0.15) (layer "In2.Cu") (net 281))
  (segment (start 90.575 103.675) (end 90.536058 103.679387) (width 0.15) (layer "In2.Cu") (net 281))
  (segment (start 91.037622 104.795764) (end 91.046866 104.822184) (width 0.15) (layer "In2.Cu") (net 281))
  (segment (start 90.575 102.625) (end 90.925 102.625) (width 0.15) (layer "In2.Cu") (net 281))
  (segment (start 90.49907 104.707669) (end 90.536058 104.720612) (width 0.15) (layer "In2.Cu") (net 281))
  (segment (start 91.022729 103.372063) (end 91.037622 103.395764) (width 0.15) (layer "In2.Cu") (net 281))
  (segment (start 90.925 103.325) (end 90.952816 103.328134) (width 0.15) (layer "In2.Cu") (net 281))
  (segment (start 90.465889 105.813179) (end 90.438179 105.840889) (width 0.15) (layer "In2.Cu") (net 281))
  (segment (start 90.979236 102.962621) (end 90.952816 102.971865) (width 0.15) (layer "In2.Cu") (net 281))
  (segment (start 90.438179 105.140889) (end 90.41733 105.17407) (width 0.15) (layer "In2.Cu") (net 281))
  (segment (start 90.925 102.975) (end 90.575 102.975) (width 0.15) (layer "In2.Cu") (net 281))
  (segment (start 90.49907 104.39233) (end 90.465889 104.413179) (width 0.15) (layer "In2.Cu") (net 281))
  (segment (start 90.925 104.375) (end 90.575 104.375) (width 0.15) (layer "In2.Cu") (net 281))
  (segment (start 90.575 102.275) (end 90.536058 102.279387) (width 0.15) (layer "In2.Cu") (net 281))
  (segment (start 90.438179 102.340889) (end 90.41733 102.37407) (width 0.15) (layer "In2.Cu") (net 281))
  (segment (start 90.438179 105.840889) (end 90.41733 105.87407) (width 0.15) (layer "In2.Cu") (net 281))
  (segment (start 90.49907 102.607669) (end 90.536058 102.620612) (width 0.15) (layer "In2.Cu") (net 281))
  (segment (start 89.8 101.1) (end 90.8 102.1) (width 0.15) (layer "In2.Cu") (net 281))
  (segment (start 91.046866 104.277815) (end 91.037622 104.304235) (width 0.15) (layer "In2.Cu") (net 281))
  (segment (start 90.404387 102.488941) (end 90.41733 102.525929) (width 0.15) (layer "In2.Cu") (net 281))
  (segment (start 91.037622 102.695764) (end 91.046866 102.722184) (width 0.15) (layer "In2.Cu") (net 281))
  (segment (start 90.41733 106.025929) (end 90.438179 106.05911) (width 0.15) (layer "In2.Cu") (net 281))
  (segment (start 90.76182 106.190889) (end 90.782669 106.22407) (width 0.15) (layer "In2.Cu") (net 281))
  (segment (start 90.465889 106.08682) (end 90.49907 106.107669) (width 0.15) (layer "In2.Cu") (net 281))
  (segment (start 91.046866 103.577815) (end 91.037622 103.604235) (width 0.15) (layer "In2.Cu") (net 281))
  (segment (start 91.022729 102.927936) (end 91.002937 102.947728) (width 0.15) (layer "In2.Cu") (net 281))
  (segment (start 91.037622 103.395764) (end 91.046866 103.422184) (width 0.15) (layer "In2.Cu") (net 281))
  (segment (start 90.465889 102.58682) (end 90.49907 102.607669) (width 0.15) (layer "In2.Cu") (net 281))
  (segment (start 90.49907 105.407669) (end 90.536058 105.420612) (width 0.15) (layer "In2.Cu") (net 281))
  (segment (start 90.575 106.125) (end 90.625 106.125) (width 0.15) (layer "In2.Cu") (net 281))
  (segment (start 90.575 104.725) (end 90.925 104.725) (width 0.15) (layer "In2.Cu") (net 281))
  (segment (start 90.795612 106.261058) (end 90.8 106.3) (width 0.15) (layer "In2.Cu") (net 281))
  (segment (start 91.037622 105.704235) (end 91.022729 105.727936) (width 0.15) (layer "In2.Cu") (net 281))
  (segment (start 90.465889 104.68682) (end 90.49907 104.707669) (width 0.15) (layer "In2.Cu") (net 281))
  (segment (start 90.49907 102.29233) (end 90.465889 102.313179) (width 0.15) (layer "In2.Cu") (net 281))
  (segment (start 90.925 105.075) (end 90.575 105.075) (width 0.15) (layer "In2.Cu") (net 281))
  (segment (start 90.465889 103.013179) (end 90.438179 103.040889) (width 0.15) (layer "In2.Cu") (net 281))
  (segment (start 90.925 104.725) (end 90.952816 104.728134) (width 0.15) (layer "In2.Cu") (net 281))
  (segment (start 91.05 102.85) (end 91.046866 102.877815) (width 0.15) (layer "In2.Cu") (net 281))
  (segment (start 90.49907 106.107669) (end 90.536058 106.120612) (width 0.15) (layer "In2.Cu") (net 281))
  (segment (start 90.41733 104.47407) (end 90.404387 104.511058) (width 0.15) (layer "In2.Cu") (net 281))
  (segment (start 90.952816 105.071865) (end 90.925 105.075) (width 0.15) (layer "In2.Cu") (net 281))
  (segment (start 90.4 104.55) (end 90.404387 104.588941) (width 0.15) (layer "In2.Cu") (net 281))
  (segment (start 91.002937 102.652271) (end 91.022729 102.672063) (width 0.15) (layer "In2.Cu") (net 281))
  (segment (start 90.952816 104.728134) (end 90.979236 104.737378) (width 0.15) (layer "In2.Cu") (net 281))
  (segment (start 90.404387 103.188941) (end 90.41733 103.225929) (width 0.15) (layer "In2.Cu") (net 281))
  (segment (start 90.979236 105.062621) (end 90.952816 105.071865) (width 0.15) (layer "In2.Cu") (net 281))
  (segment (start 91.022729 105.472063) (end 91.037622 105.495764) (width 0.15) (layer "In2.Cu") (net 281))
  (segment (start 90.41733 103.225929) (end 90.438179 103.25911) (width 0.15) (layer "In2.Cu") (net 281))
  (segment (start 90.4 105.25) (end 90.404387 105.288941) (width 0.15) (layer "In2.Cu") (net 281))
  (segment (start 91.037622 105.004235) (end 91.022729 105.027936) (width 0.15) (layer "In2.Cu") (net 281))
  (segment (start 90.575 102.975) (end 90.536058 102.979387) (width 0.15) (layer "In2.Cu") (net 281))
  (segment (start 90.952816 104.028134) (end 90.979236 104.037378) (width 0.15) (layer "In2.Cu") (net 281))
  (segment (start 90.465889 104.413179) (end 90.438179 104.440889) (width 0.15) (layer "In2.Cu") (net 281))
  (segment (start 90.49907 103.69233) (end 90.465889 103.713179) (width 0.15) (layer "In2.Cu") (net 281))
  (segment (start 90.41733 105.17407) (end 90.404387 105.211058) (width 0.15) (layer "In2.Cu") (net 281))
  (segment (start 90.438179 103.740889) (end 90.41733 103.77407) (width 0.15) (layer "In2.Cu") (net 281))
  (segment (start 90.575 105.075) (end 90.536058 105.079387) (width 0.15) (layer "In2.Cu") (net 281))
  (segment (start 90.49907 105.09233) (end 90.465889 105.113179) (width 0.15) (layer "In2.Cu") (net 281))
  (segment (start 91.002937 105.747728) (end 90.979236 105.762621) (width 0.15) (layer "In2.Cu") (net 281))
  (segment (start 90.438179 106.05911) (end 90.465889 106.08682) (width 0.15) (layer "In2.Cu") (net 281))
  (segment (start 90.41733 105.325929) (end 90.438179 105.35911) (width 0.15) (layer "In2.Cu") (net 281))
  (segment (start 90.925 105.775) (end 90.575 105.775) (width 0.15) (layer "In2.Cu") (net 281))
  (segment (start 90.700929 106.14233) (end 90.73411 106.163179) (width 0.15) (layer "In2.Cu") (net 281))
  (segment (start 90.73411 106.163179) (end 90.76182 106.190889) (width 0.15) (layer "In2.Cu") (net 281))
  (segment (start 90.575 105.425) (end 90.925 105.425) (width 0.15) (layer "In2.Cu") (net 281))
  (segment (start 89.45 100.75) (end 89.8 101.1) (width 0.15) (layer "B.Cu") (net 281))
  (segment (start 89.45 100.75) (end 89 100.75) (width 0.15) (layer "B.Cu") (net 281))
  (segment (start 94.4 116.15) (end 94 115.75) (width 0.15) (layer "F.Cu") (net 282))
  (segment (start 92.3 100.6) (end 91.8 101.1) (width 0.15) (layer "F.Cu") (net 282))
  (via (at 94 115.75) (size 0.5) (drill 0.2) (layers "F.Cu" "B.Cu") (net 282))
  (via (at 91.8 101.1) (size 0.5) (drill 0.2) (layers "F.Cu" "B.Cu") (net 282))
  (segment (start 91.622928 108.287229) (end 91.599514 108.301941) (width 0.15) (layer "In2.Cu") (net 282))
  (segment (start 91.923491 109.675) (end 91.676509 109.675) (width 0.15) (layer "In2.Cu") (net 282))
  (segment (start 91.599514 107.198058) (end 91.622928 107.21277) (width 0.15) (layer "In2.Cu") (net 282))
  (segment (start 91.599514 102.701941) (end 91.57996 102.721495) (width 0.15) (layer "In2.Cu") (net 282))
  (segment (start 92.046981 108.15151) (end 92.043885 108.178989) (width 0.15) (layer "In2.Cu") (net 282))
  (segment (start 91.57996 109.021495) (end 91.565248 109.044909) (width 0.15) (layer "In2.Cu") (net 282))
  (segment (start 91.57996 104.121495) (end 91.565248 104.144909) (width 0.15) (layer "In2.Cu") (net 282))
  (segment (start 91.676509 103.375) (end 91.649029 103.378096) (width 0.15) (layer "In2.Cu") (net 282))
  (segment (start 91.676509 103.025) (end 91.923491 103.025) (width 0.15) (layer "In2.Cu") (net 282))
  (segment (start 91.57996 108.578504) (end 91.599514 108.598058) (width 0.15) (layer "In2.Cu") (net 282))
  (segment (start 91.923491 105.475) (end 91.676509 105.475) (width 0.15) (layer "In2.Cu") (net 282))
  (segment (start 91.977072 104.06277) (end 91.950971 104.071903) (width 0.15) (layer "In2.Cu") (net 282))
  (segment (start 91.553019 102.90151) (end 91.556115 102.928989) (width 0.15) (layer "In2.Cu") (net 282))
  (segment (start 92.034752 103.794909) (end 92.043885 103.82101) (width 0.15) (layer "In2.Cu") (net 282))
  (segment (start 91.676509 104.775) (end 91.649029 104.778096) (width 0.15) (layer "In2.Cu") (net 282))
  (segment (start 91.565248 106.944909) (end 91.556115 106.97101) (width 0.15) (layer "In2.Cu") (net 282))
  (segment (start 91.556115 107.67101) (end 91.553019 107.69849) (width 0.15) (layer "In2.Cu") (net 282))
  (segment (start 91.556115 102.227479) (end 91.565248 102.25358) (width 0.15) (layer "In2.Cu") (net 282))
  (segment (start 91.57996 104.821495) (end 91.565248 104.844909) (width 0.15) (layer "In2.Cu") (net 282))
  (segment (start 92.043885 108.178989) (end 92.034752 108.20509) (width 0.15) (layer "In2.Cu") (net 282))
  (segment (start 92.02004 103.071495) (end 92.034752 103.094909) (width 0.15) (layer "In2.Cu") (net 282))
  (segment (start 91.78777 101.90358) (end 91.773058 101.926994) (width 0.15) (layer "In2.Cu") (net 282))
  (segment (start 91.553019 109.90151) (end 91.556115 109.928989) (width 0.15) (layer "In2.Cu") (net 282))
  (segment (start 91.599514 104.398058) (end 91.622928 104.41277) (width 0.15) (layer "In2.Cu") (net 282))
  (segment (start 91.57996 107.178504) (end 91.599514 107.198058) (width 0.15) (layer "In2.Cu") (net 282))
  (segment (start 92.02004 104.471495) (end 92.034752 104.494909) (width 0.15) (layer "In2.Cu") (net 282))
  (segment (start 91.8 110.14849) (end 91.8 112.95) (width 0.15) (layer "In2.Cu") (net 282))
  (segment (start 91.649029 105.821903) (end 91.676509 105.825) (width 0.15) (layer "In2.Cu") (net 282))
  (segment (start 91.57996 109.978504) (end 91.599514 109.998058) (width 0.15) (layer "In2.Cu") (net 282))
  (segment (start 91.950971 109.671903) (end 91.923491 109.675) (width 0.15) (layer "In2.Cu") (net 282))
  (segment (start 92.046981 104.65151) (end 92.043885 104.678989) (width 0.15) (layer "In2.Cu") (net 282))
  (segment (start 92.000486 106.848058) (end 91.977072 106.86277) (width 0.15) (layer "In2.Cu") (net 282))
  (segment (start 92.034752 104.70509) (end 92.02004 104.728504) (width 0.15) (layer "In2.Cu") (net 282))
  (segment (start 92.034752 102.394909) (end 92.043885 102.42101) (width 0.15) (layer "In2.Cu") (net 282))
  (segment (start 92.043885 103.12101) (end 92.046981 103.14849) (width 0.15) (layer "In2.Cu") (net 282))
  (segment (start 91.950971 104.071903) (end 91.923491 104.075) (width 0.15) (layer "In2.Cu") (net 282))
  (segment (start 94 115.15) (end 94 115.75) (width 0.15) (layer "In2.Cu") (net 282))
  (segment (start 91.753504 101.946548) (end 91.73009 101.96126) (width 0.15) (layer "In2.Cu") (net 282))
  (segment (start 91.977072 106.537229) (end 92.000486 106.551941) (width 0.15) (layer "In2.Cu") (net 282))
  (segment (start 91.57996 102.276994) (end 91.599514 102.296548) (width 0.15) (layer "In2.Cu") (net 282))
  (segment (start 92.043885 107.32101) (end 92.046981 107.34849) (width 0.15) (layer "In2.Cu") (net 282))
  (segment (start 92.02004 107.971495) (end 92.034752 107.994909) (width 0.15) (layer "In2.Cu") (net 282))
  (segment (start 92.043885 103.82101) (end 92.046981 103.84849) (width 0.15) (layer "In2.Cu") (net 282))
  (segment (start 91.649029 106.521903) (end 91.676509 106.525) (width 0.15) (layer "In2.Cu") (net 282))
  (segment (start 92.046981 107.34849) (end 92.046981 107.45151) (width 0.15) (layer "In2.Cu") (net 282))
  (segment (start 92.000486 105.448058) (end 91.977072 105.46277) (width 0.15) (layer "In2.Cu") (net 282))
  (segment (start 91.649029 103.721903) (end 91.676509 103.725) (width 0.15) (layer "In2.Cu") (net 282))
  (segment (start 92.000486 104.748058) (end 91.977072 104.76277) (width 0.15) (layer "In2.Cu") (net 282))
  (segment (start 92.043885 104.52101) (end 92.046981 104.54849) (width 0.15) (layer "In2.Cu") (net 282))
  (segment (start 92.043885 109.42101) (end 92.046981 109.44849) (width 0.15) (layer "In2.Cu") (net 282))
  (segment (start 91.556115 104.17101) (end 91.553019 104.19849) (width 0.15) (layer "In2.Cu") (net 282))
  (segment (start 91.676509 107.575) (end 91.649029 107.578096) (width 0.15) (layer "In2.Cu") (net 282))
  (segment (start 92.043885 108.878989) (end 92.034752 108.90509) (width 0.15) (layer "In2.Cu") (net 282))
  (segment (start 91.556115 109.77101) (end 91.553019 109.79849) (width 0.15) (layer "In2.Cu") (net 282))
  (segment (start 91.950971 106.871903) (end 91.923491 106.875) (width 0.15) (layer "In2.Cu") (net 282))
  (segment (start 91.8 102.32349) (end 91.8 102.325) (width 0.15) (layer "In2.Cu") (net 282))
  (segment (start 92.046981 103.95151) (end 92.043885 103.978989) (width 0.15) (layer "In2.Cu") (net 282))
  (segment (start 91.977072 102.337229) (end 92.000486 102.351941) (width 0.15) (layer "In2.Cu") (net 282))
  (segment (start 91.622928 106.887229) (end 91.599514 106.901941) (width 0.15) (layer "In2.Cu") (net 282))
  (segment (start 91.565248 107.644909) (end 91.556115 107.67101) (width 0.15) (layer "In2.Cu") (net 282))
  (segment (start 91.553019 102.09698) (end 91.553019 102.2) (width 0.15) (layer "In2.Cu") (net 282))
  (segment (start 91.622928 103.71277) (end 91.649029 103.721903) (width 0.15) (layer "In2.Cu") (net 282))
  (segment (start 91.923491 102.675) (end 91.676509 102.675) (width 0.15) (layer "In2.Cu") (net 282))
  (segment (start 91.923491 104.775) (end 91.676509 104.775) (width 0.15) (layer "In2.Cu") (net 282))
  (segment (start 91.649029 102.678096) (end 91.622928 102.687229) (width 0.15) (layer "In2.Cu") (net 282))
  (segment (start 91.565248 109.25509) (end 91.57996 109.278504) (width 0.15) (layer "In2.Cu") (net 282))
  (segment (start 91.553019 104.30151) (end 91.556115 104.328989) (width 0.15) (layer "In2.Cu") (net 282))
  (segment (start 91.599514 103.698058) (end 91.622928 103.71277) (width 0.15) (layer "In2.Cu") (net 282))
  (segment (start 91.923491 105.125) (end 91.950971 105.128096) (width 0.15) (layer "In2.Cu") (net 282))
  (segment (start 91.57996 109.721495) (end 91.565248 109.744909) (width 0.15) (layer "In2.Cu") (net 282))
  (segment (start 91.553019 103.49849) (end 91.553019 103.60151) (width 0.15) (layer "In2.Cu") (net 282))
  (segment (start 92.043885 105.92101) (end 92.046981 105.94849) (width 0.15) (layer "In2.Cu") (net 282))
  (segment (start 91.977072 105.137229) (end 92.000486 105.151941) (width 0.15) (layer "In2.Cu") (net 282))
  (segment (start 91.950971 106.528096) (end 91.977072 106.537229) (width 0.15) (layer "In2.Cu") (net 282))
  (segment (start 92.02004 104.728504) (end 92.000486 104.748058) (width 0.15) (layer "In2.Cu") (net 282))
  (segment (start 91.565248 108.344909) (end 91.556115 108.37101) (width 0.15) (layer "In2.Cu") (net 282))
  (segment (start 92.000486 104.048058) (end 91.977072 104.06277) (width 0.15) (layer "In2.Cu") (net 282))
  (segment (start 91.622928 103.01277) (end 91.649029 103.021903) (width 0.15) (layer "In2.Cu") (net 282))
  (segment (start 91.565248 106.244909) (end 91.556115 106.27101) (width 0.15) (layer "In2.Cu") (net 282))
  (segment (start 91.57996 109.278504) (end 91.599514 109.298058) (width 0.15) (layer "In2.Cu") (net 282))
  (segment (start 91.977072 103.36277) (end 91.950971 103.371903) (width 0.15) (layer "In2.Cu") (net 282))
  (segment (start 91.649029 107.921903) (end 91.676509 107.925) (width 0.15) (layer "In2.Cu") (net 282))
  (segment (start 91.565248 105.544909) (end 91.556115 105.57101) (width 0.15) (layer "In2.Cu") (net 282))
  (segment (start 92.02004 106.828504) (end 92.000486 106.848058) (width 0.15) (layer "In2.Cu") (net 282))
  (segment (start 91.556115 104.87101) (end 91.553019 104.89849) (width 0.15) (layer "In2.Cu") (net 282))
  (segment (start 91.649029 104.421903) (end 91.676509 104.425) (width 0.15) (layer "In2.Cu") (net 282))
  (segment (start 91.923491 108.275) (end 91.676509 108.275) (width 0.15) (layer "In2.Cu") (net 282))
  (segment (start 91.599514 102.000431) (end 91.57996 102.019985) (width 0.15) (layer "In2.Cu") (net 282))
  (segment (start 91.622928 107.21277) (end 91.649029 107.221903) (width 0.15) (layer "In2.Cu") (net 282))
  (segment (start 92.02004 103.771495) (end 92.034752 103.794909) (width 0.15) (layer "In2.Cu") (net 282))
  (segment (start 92.02004 108.671495) (end 92.034752 108.694909) (width 0.15) (layer "In2.Cu") (net 282))
  (segment (start 91.923491 105.825) (end 91.950971 105.828096) (width 0.15) (layer "In2.Cu") (net 282))
  (segment (start 92.046981 103.14849) (end 92.046981 103.25151) (width 0.15) (layer "In2.Cu") (net 282))
  (segment (start 91.556115 106.97101) (end 91.553019 106.99849) (width 0.15) (layer "In2.Cu") (net 282))
  (segment (start 92.043885 105.22101) (end 92.046981 105.24849) (width 0.15) (layer "In2.Cu") (net 282))
  (segment (start 91.676509 107.225) (end 91.923491 107.225) (width 0.15) (layer "In2.Cu") (net 282))
  (segment (start 92.000486 108.248058) (end 91.977072 108.26277) (width 0.15) (layer "In2.Cu") (net 282))
  (segment (start 91.565248 109.744909) (end 91.556115 109.77101) (width 0.15) (layer "In2.Cu") (net 282))
  (segment (start 91.622928 106.187229) (end 91.599514 106.201941) (width 0.15) (layer "In2.Cu") (net 282))
  (segment (start 92.000486 107.548058) (end 91.977072 107.56277) (width 0.15) (layer "In2.Cu") (net 282))
  (segment (start 91.649029 109.321903) (end 91.676509 109.325) (width 0.15) (layer "In2.Cu") (net 282))
  (segment (start 92.02004 104.028504) (end 92.000486 104.048058) (width 0.15) (layer "In2.Cu") (net 282))
  (segment (start 91.57996 105.521495) (end 91.565248 105.544909) (width 0.15) (layer "In2.Cu") (net 282))
  (segment (start 91.73009 110.037229) (end 91.753504 110.051941) (width 0.15) (layer "In2.Cu") (net 282))
  (segment (start 91.599514 109.998058) (end 91.622928 110.01277) (width 0.15) (layer "In2.Cu") (net 282))
  (segment (start 91.8 101.85) (end 91.796903 101.877479) (width 0.15) (layer "In2.Cu") (net 282))
  (segment (start 91.649029 106.878096) (end 91.622928 106.887229) (width 0.15) (layer "In2.Cu") (net 282))
  (segment (start 91.950971 108.971903) (end 91.923491 108.975) (width 0.15) (layer "In2.Cu") (net 282))
  (segment (start 92.046981 106.64849) (end 92.046981 106.75151) (width 0.15) (layer "In2.Cu") (net 282))
  (segment (start 91.622928 104.41277) (end 91.649029 104.421903) (width 0.15) (layer "In2.Cu") (net 282))
  (segment (start 91.57996 106.478504) (end 91.599514 106.498058) (width 0.15) (layer "In2.Cu") (net 282))
  (segment (start 91.676509 107.925) (end 91.923491 107.925) (width 0.15) (layer "In2.Cu") (net 282))
  (segment (start 91.556115 105.728989) (end 91.565248 105.75509) (width 0.15) (layer "In2.Cu") (net 282))
  (segment (start 92.000486 107.951941) (end 92.02004 107.971495) (width 0.15) (layer "In2.Cu") (net 282))
  (segment (start 91.950971 108.628096) (end 91.977072 108.637229) (width 0.15) (layer "In2.Cu") (net 282))
  (segment (start 91.923491 107.925) (end 91.950971 107.928096) (width 0.15) (layer "In2.Cu") (net 282))
  (segment (start 91.977072 106.16277) (end 91.950971 106.171903) (width 0.15) (layer "In2.Cu") (net 282))
  (segment (start 92.000486 103.348058) (end 91.977072 103.36277) (width 0.15) (layer "In2.Cu") (net 282))
  (segment (start 91.977072 105.837229) (end 92.000486 105.851941) (width 0.15) (layer "In2.Cu") (net 282))
  (segment (start 92.043885 102.42101) (end 92.046981 102.44849) (width 0.15) (layer "In2.Cu") (net 282))
  (segment (start 91.565248 105.05509) (end 91.57996 105.078504) (width 0.15) (layer "In2.Cu") (net 282))
  (segment (start 91.773058 110.071495) (end 91.78777 110.094909) (width 0.15) (layer "In2.Cu") (net 282))
  (segment (start 92.043885 108.02101) (end 92.046981 108.04849) (width 0.15) (layer "In2.Cu") (net 282))
  (segment (start 91.57996 107.621495) (end 91.565248 107.644909) (width 0.15) (layer "In2.Cu") (net 282))
  (segment (start 92.043885 103.978989) (end 92.034752 104.00509) (width 0.15) (layer "In2.Cu") (net 282))
  (segment (start 91.923491 106.875) (end 91.676509 106.875) (width 0.15) (layer "In2.Cu") (net 282))
  (segment (start 92.000486 102.351941) (end 92.02004 102.371495) (width 0.15) (layer "In2.Cu") (net 282))
  (segment (start 91.57996 106.921495) (end 91.565248 106.944909) (width 0.15) (layer "In2.Cu") (net 282))
  (segment (start 92.000486 102.648058) (end 91.977072 102.66277) (width 0.15) (layer "In2.Cu") (net 282))
  (segment (start 91.599514 108.301941) (end 91.57996 108.321495) (width 0.15) (layer "In2.Cu") (net 282))
  (segment (start 91.565248 104.844909) (end 91.556115 104.87101) (width 0.15) (layer "In2.Cu") (net 282))
  (segment (start 91.57996 107.878504) (end 91.599514 107.898058) (width 0.15) (layer "In2.Cu") (net 282))
  (segment (start 91.553019 106.29849) (end 91.553019 106.40151) (width 0.15) (layer "In2.Cu") (net 282))
  (segment (start 91.923491 104.425) (end 91.950971 104.428096) (width 0.15) (layer "In2.Cu") (net 282))
  (segment (start 92.000486 109.648058) (end 91.977072 109.66277) (width 0.15) (layer "In2.Cu") (net 282))
  (segment (start 91.565248 102.043399) (end 91.556115 102.0695) (width 0.15) (layer "In2.Cu") (net 282))
  (segment (start 92.02004 108.228504) (end 92.000486 108.248058) (width 0.15) (layer "In2.Cu") (net 282))
  (segment (start 92.046981 102.44849) (end 92.046981 102.55151) (width 0.15) (layer "In2.Cu") (net 282))
  (segment (start 92.034752 109.394909) (end 92.043885 109.42101) (width 0.15) (layer "In2.Cu") (net 282))
  (segment (start 92.043885 106.62101) (end 92.046981 106.64849) (width 0.15) (layer "In2.Cu") (net 282))
  (segment (start 91.977072 104.437229) (end 92.000486 104.451941) (width 0.15) (layer "In2.Cu") (net 282))
  (segment (start 91.565248 104.35509) (end 91.57996 104.378504) (width 0.15) (layer "In2.Cu") (net 282))
  (segment (start 91.923491 104.075) (end 91.676509 104.075) (width 0.15) (layer "In2.Cu") (net 282))
  (segment (start 91.553019 107.10151) (end 91.556115 107.128989) (width 0.15) (layer "In2.Cu") (net 282))
  (segment (start 92.046981 103.25151) (end 92.043885 103.278989) (width 0.15) (layer "In2.Cu") (net 282))
  (segment (start 91.950971 105.471903) (end 91.923491 105.475) (width 0.15) (layer "In2.Cu") (net 282))
  (segment (start 91.703989 101.970393) (end 91.649029 101.976586) (width 0.15) (layer "In2.Cu") (net 282))
  (segment (start 91.676509 108.625) (end 91.923491 108.625) (width 0.15) (layer "In2.Cu") (net 282))
  (segment (start 91.556115 103.47101) (end 91.553019 103.49849) (width 0.15) (layer "In2.Cu") (net 282))
  (segment (start 91.556115 105.57101) (end 91.553019 105.59849) (width 0.15) (layer "In2.Cu") (net 282))
  (segment (start 91.622928 106.51277) (end 91.649029 106.521903) (width 0.15) (layer "In2.Cu") (net 282))
  (segment (start 91.977072 105.46277) (end 91.950971 105.471903) (width 0.15) (layer "In2.Cu") (net 282))
  (segment (start 91.556115 107.128989) (end 91.565248 107.15509) (width 0.15) (layer "In2.Cu") (net 282))
  (segment (start 92.034752 106.10509) (end 92.02004 106.128504) (width 0.15) (layer "In2.Cu") (net 282))
  (segment (start 91.57996 102.978504) (end 91.599514 102.998058) (width 0.15) (layer "In2.Cu") (net 282))
  (segment (start 91.553019 105.00151) (end 91.556115 105.028989) (width 0.15) (layer "In2.Cu") (net 282))
  (segment (start 91.599514 102.998058) (end 91.622928 103.01277) (width 0.15) (layer "In2.Cu") (net 282))
  (segment (start 91.923491 106.175) (end 91.676509 106.175) (width 0.15) (layer "In2.Cu") (net 282))
  (segment (start 91.676509 109.675) (end 91.649029 109.678096) (width 0.15) (layer "In2.Cu") (net 282))
  (segment (start 91.599514 105.798058) (end 91.622928 105.81277) (width 0.15) (layer "In2.Cu") (net 282))
  (segment (start 91.649029 104.778096) (end 91.622928 104.787229) (width 0.15) (layer "In2.Cu") (net 282))
  (segment (start 91.950971 108.271903) (end 91.923491 108.275) (width 0.15) (layer "In2.Cu") (net 282))
  (segment (start 91.977072 109.337229) (end 92.000486 109.351941) (width 0.15) (layer "In2.Cu") (net 282))
  (segment (start 92.034752 103.30509) (end 92.02004 103.328504) (width 0.15) (layer "In2.Cu") (net 282))
  (segment (start 91.622928 105.81277) (end 91.649029 105.821903) (width 0.15) (layer "In2.Cu") (net 282))
  (segment (start 92.000486 108.948058) (end 91.977072 108.96277) (width 0.15) (layer "In2.Cu") (net 282))
  (segment (start 92.02004 105.428504) (end 92.000486 105.448058) (width 0.15) (layer "In2.Cu") (net 282))
  (segment (start 91.556115 105.028989) (end 91.565248 105.05509) (width 0.15) (layer "In2.Cu") (net 282))
  (segment (start 91.649029 104.078096) (end 91.622928 104.087229) (width 0.15) (layer "In2.Cu") (net 282))
  (segment (start 91.950971 104.771903) (end 91.923491 104.775) (width 0.15) (layer "In2.Cu") (net 282))
  (segment (start 91.649029 108.278096) (end 91.622928 108.287229) (width 0.15) (layer "In2.Cu") (net 282))
  (segment (start 92.046981 107.45151) (end 92.043885 107.478989) (width 0.15) (layer "In2.Cu") (net 282))
  (segment (start 92.046981 108.85151) (end 92.043885 108.878989) (width 0.15) (layer "In2.Cu") (net 282))
  (segment (start 92.034752 106.594909) (end 92.043885 106.62101) (width 0.15) (layer "In2.Cu") (net 282))
  (segment (start 91.8 112.95) (end 94 115.15) (width 0.15) (layer "In2.Cu") (net 282))
  (segment (start 91.977072 104.76277) (end 91.950971 104.771903) (width 0.15) (layer "In2.Cu") (net 282))
  (segment (start 92.000486 105.851941) (end 92.02004 105.871495) (width 0.15) (layer "In2.Cu") (net 282))
  (segment (start 91.553019 104.89849) (end 91.553019 105.00151) (width 0.15) (layer "In2.Cu") (net 282))
  (segment (start 92.000486 107.251941) (end 92.02004 107.271495) (width 0.15) (layer "In2.Cu") (net 282))
  (segment (start 91.676509 103.725) (end 91.923491 103.725) (width 0.15) (layer "In2.Cu") (net 282))
  (segment (start 91.57996 103.421495) (end 91.565248 103.444909) (width 0.15) (layer "In2.Cu") (net 282))
  (segment (start 91.676509 108.275) (end 91.649029 108.278096) (width 0.15) (layer "In2.Cu") (net 282))
  (segment (start 91.676509 106.875) (end 91.649029 106.878096) (width 0.15) (layer "In2.Cu") (net 282))
  (segment (start 92.034752 107.994909) (end 92.043885 108.02101) (width 0.15) (layer "In2.Cu") (net 282))
  (segment (start 91.599514 106.901941) (end 91.57996 106.921495) (width 0.15) (layer "In2.Cu") (net 282))
  (segment (start 91.599514 109.701941) (end 91.57996 109.721495) (width 0.15) (layer "In2.Cu") (net 282))
  (segment (start 91.553019 107.69849) (end 91.553019 107.80151) (width 0.15) (layer "In2.Cu") (net 282))
  (segment (start 91.565248 105.75509) (end 91.57996 105.778504) (width 0.15) (layer "In2.Cu") (net 282))
  (segment (start 92.034752 104.00509) (end 92.02004 104.028504) (width 0.15) (layer "In2.Cu") (net 282))
  (segment (start 91.923491 107.575) (end 91.676509 107.575) (width 0.15) (layer "In2.Cu") (net 282))
  (segment (start 91.923491 107.225) (end 91.950971 107.228096) (width 0.15) (layer "In2.Cu") (net 282))
  (segment (start 92.02004 106.571495) (end 92.034752 106.594909) (width 0.15) (layer "In2.Cu") (net 282))
  (segment (start 91.977072 109.66277) (end 91.950971 109.671903) (width 0.15) (layer "In2.Cu") (net 282))
  (segment (start 92.043885 106.778989) (end 92.034752 106.80509) (width 0.15) (layer "In2.Cu") (net 282))
  (segment (start 92.034752 109.60509) (end 92.02004 109.628504) (width 0.15) (layer "In2.Cu") (net 282))
  (segment (start 92.02004 102.628504) (end 92.000486 102.648058) (width 0.15) (layer "In2.Cu") (net 282))
  (segment (start 91.556115 104.328989) (end 91.565248 104.35509) (width 0.15) (layer "In2.Cu") (net 282))
  (segment (start 91.923491 102.325) (end 91.950971 102.328096) (width 0.15) (layer "In2.Cu") (net 282))
  (segment (start 91.553019 106.40151) (end 91.556115 106.428989) (width 0.15) (layer "In2.Cu") (net 282))
  (segment (start 91.599514 106.201941) (end 91.57996 106.221495) (width 0.15) (layer "In2.Cu") (net 282))
  (segment (start 91.649029 108.978096) (end 91.622928 108.987229) (width 0.15) (layer "In2.Cu") (net 282))
  (segment (start 92.034752 108.694909) (end 92.043885 108.72101) (width 0.15) (layer "In2.Cu") (net 282))
  (segment (start 91.977072 106.86277) (end 91.950971 106.871903) (width 0.15) (layer "In2.Cu") (net 282))
  (segment (start 92.034752 105.894909) (end 92.043885 105.92101) (width 0.15) (layer "In2.Cu") (net 282))
  (segment (start 92.043885 102.578989) (end 92.034752 102.60509) (width 0.15) (layer "In2.Cu") (net 282))
  (segment (start 91.599514 103.401941) (end 91.57996 103.421495) (width 0.15) (layer "In2.Cu") (net 282))
  (segment (start 92.02004 108.928504) (end 92.000486 108.948058) (width 0.15) (layer "In2.Cu") (net 282))
  (segment (start 91.622928 102.31126) (end 91.649029 102.320393) (width 0.15) (layer "In2.Cu") (net 282))
  (segment (start 91.649029 106.178096) (end 91.622928 106.187229) (width 0.15) (layer "In2.Cu") (net 282))
  (segment (start 92.046981 106.05151) (end 92.043885 106.078989) (width 0.15) (layer "In2.Cu") (net 282))
  (segment (start 91.950971 104.428096) (end 91.977072 104.437229) (width 0.15) (layer "In2.Cu") (net 282))
  (segment (start 91.599514 102.296548) (end 91.622928 102.31126) (width 0.15) (layer "In2.Cu") (net 282))
  (segment (start 92.046981 102.55151) (end 92.043885 102.578989) (width 0.15) (layer "In2.Cu") (net 282))
  (segment (start 91.676509 109.325) (end 91.923491 109.325) (width 0.15) (layer "In2.Cu") (net 282))
  (segment (start 91.649029 105.478096) (end 91.622928 105.487229) (width 0.15) (layer "In2.Cu") (net 282))
  (segment (start 91.8 102.325) (end 91.923491 102.325) (width 0.15) (layer "In2.Cu") (net 282))
  (segment (start 92.02004 109.628504) (end 92.000486 109.648058) (width 0.15) (layer "In2.Cu") (net 282))
  (segment (start 91.553019 108.39849) (end 91.553019 108.50151) (width 0.15) (layer "In2.Cu") (net 282))
  (segment (start 91.950971 109.328096) (end 91.977072 109.337229) (width 0.15) (layer "In2.Cu") (net 282))
  (segment (start 91.553019 104.19849) (end 91.553019 104.30151) (width 0.15) (layer "In2.Cu") (net 282))
  (segment (start 91.649029 107.578096) (end 91.622928 107.587229) (width 0.15) (layer "In2.Cu") (net 282))
  (segment (start 91.950971 103.028096) (end 91.977072 103.037229) (width 0.15) (layer "In2.Cu") (net 282))
  (segment (start 91.923491 108.625) (end 91.950971 108.628096) (width 0.15) (layer "In2.Cu") (net 282))
  (segment (start 91.57996 105.778504) (end 91.599514 105.798058) (width 0.15) (layer "In2.Cu") (net 282))
  (segment (start 92.02004 105.871495) (end 92.034752 105.894909) (width 0.15) (layer "In2.Cu") (net 282))
  (segment (start 92.02004 107.271495) (end 92.034752 107.294909) (width 0.15) (layer "In2.Cu") (net 282))
  (segment (start 91.622928 108.61277) (end 91.649029 108.621903) (width 0.15) (layer "In2.Cu") (net 282))
  (segment (start 91.599514 108.598058) (end 91.622928 108.61277) (width 0.15) (layer "In2.Cu") (net 282))
  (segment (start 91.649029 109.678096) (end 91.622928 109.687229) (width 0.15) (layer "In2.Cu") (net 282))
  (segment (start 91.553019 107.80151) (end 91.556115 107.828989) (width 0.15) (layer "In2.Cu") (net 282))
  (segment (start 91.649029 103.021903) (end 91.676509 103.025) (width 0.15) (layer "In2.Cu") (net 282))
  (segment (start 91.622928 108.987229) (end 91.599514 109.001941) (width 0.15) (layer "In2.Cu") (net 282))
  (segment (start 91.649029 101.976586) (end 91.622928 101.985719) (width 0.15) (layer "In2.Cu") (net 282))
  (segment (start 92.000486 103.051941) (end 92.02004 103.071495) (width 0.15) (layer "In2.Cu") (net 282))
  (segment (start 92.046981 109.44849) (end 92.046981 109.55151) (width 0.15) (layer "In2.Cu") (net 282))
  (segment (start 92.02004 103.328504) (end 92.000486 103.348058) (width 0.15) (layer "In2.Cu") (net 282))
  (segment (start 91.599514 107.898058) (end 91.622928 107.91277) (width 0.15) (layer "In2.Cu") (net 282))
  (segment (start 91.676509 105.475) (end 91.649029 105.478096) (width 0.15) (layer "In2.Cu") (net 282))
  (segment (start 91.73009 101.96126) (end 91.703989 101.970393) (width 0.15) (layer "In2.Cu") (net 282))
  (segment (start 92.000486 106.551941) (end 92.02004 106.571495) (width 0.15) (layer "In2.Cu") (net 282))
  (segment (start 91.676509 106.525) (end 91.923491 106.525) (width 0.15) (layer "In2.Cu") (net 282))
  (segment (start 92.043885 104.678989) (end 92.034752 104.70509) (width 0.15) (layer "In2.Cu") (net 282))
  (segment (start 91.923491 109.325) (end 91.950971 109.328096) (width 0.15) (layer "In2.Cu") (net 282))
  (segment (start 91.977072 108.26277) (end 91.950971 108.271903) (width 0.15) (layer "In2.Cu") (net 282))
  (segment (start 92.046981 105.94849) (end 92.046981 106.05151) (width 0.15) (layer "In2.Cu") (net 282))
  (segment (start 91.923491 106.525) (end 91.950971 106.528096) (width 0.15) (layer "In2.Cu") (net 282))
  (segment (start 91.676509 105.825) (end 91.923491 105.825) (width 0.15) (layer "In2.Cu") (net 282))
  (segment (start 91.565248 102.95509) (end 91.57996 102.978504) (width 0.15) (layer "In2.Cu") (net 282))
  (segment (start 91.622928 110.01277) (end 91.649029 110.021903) (width 0.15) (layer "In2.Cu") (net 282))
  (segment (start 91.950971 103.728096) (end 91.977072 103.737229) (width 0.15) (layer "In2.Cu") (net 282))
  (segment (start 92.034752 105.194909) (end 92.043885 105.22101) (width 0.15) (layer "In2.Cu") (net 282))
  (segment (start 91.649029 107.221903) (end 91.676509 107.225) (width 0.15) (layer "In2.Cu") (net 282))
  (segment (start 92.043885 103.278989) (end 92.034752 103.30509) (width 0.15) (layer "In2.Cu") (net 282))
  (segment (start 91.649029 110.021903) (end 91.703989 110.028096) (width 0.15) (layer "In2.Cu") (net 282))
  (segment (start 91.57996 103.678504) (end 91.599514 103.698058) (width 0.15) (layer "In2.Cu") (net 282))
  (segment (start 92.000486 106.148058) (end 91.977072 106.16277) (width 0.15) (layer "In2.Cu") (net 282))
  (segment (start 91.950971 105.128096) (end 91.977072 105.137229) (width 0.15) (layer "In2.Cu") (net 282))
  (segment (start 92.043885 105.378989) (end 92.034752 105.40509) (width 0.15) (layer "In2.Cu") (net 282))
  (segment (start 92.000486 103.751941) (end 92.02004 103.771495) (width 0.15) (layer "In2.Cu") (net 282))
  (segment (start 91.622928 104.087229) (end 91.599514 104.101941) (width 0.15) (layer "In2.Cu") (net 282))
  (segment (start 91.57996 106.221495) (end 91.565248 106.244909) (width 0.15) (layer "In2.Cu") (net 282))
  (segment (start 91.599514 104.101941) (end 91.57996 104.121495) (width 0.15) (layer "In2.Cu") (net 282))
  (segment (start 91.676509 102.675) (end 91.649029 102.678096) (width 0.15) (layer "In2.Cu") (net 282))
  (segment (start 92.034752 108.20509) (end 92.02004 108.228504) (width 0.15) (layer "In2.Cu") (net 282))
  (segment (start 91.556115 102.928989) (end 91.565248 102.95509) (width 0.15) (layer "In2.Cu") (net 282))
  (segment (start 91.622928 105.487229) (end 91.599514 105.501941) (width 0.15) (layer "In2.Cu") (net 282))
  (segment (start 92.043885 108.72101) (end 92.046981 108.74849) (width 0.15) (layer "In2.Cu") (net 282))
  (segment (start 91.676509 104.075) (end 91.649029 104.078096) (width 0.15) (layer "In2.Cu") (net 282))
  (segment (start 91.599514 107.601941) (end 91.57996 107.621495) (width 0.15) (layer "In2.Cu") (net 282))
  (segment (start 91.622928 107.91277) (end 91.649029 107.921903) (width 0.15) (layer "In2.Cu") (net 282))
  (segment (start 91.977072 102.66277) (end 91.950971 102.671903) (width 0.15) (layer "In2.Cu") (net 282))
  (segment (start 92.034752 104.494909) (end 92.043885 104.52101) (width 0.15) (layer "In2.Cu") (net 282))
  (segment (start 92.000486 104.451941) (end 92.02004 104.471495) (width 0.15) (layer "In2.Cu") (net 282))
  (segment (start 92.043885 106.078989) (end 92.034752 106.10509) (width 0.15) (layer "In2.Cu") (net 282))
  (segment (start 91.556115 102.0695) (end 91.553019 102.09698) (width 0.15) (layer "In2.Cu") (net 282))
  (segment (start 91.923491 108.975) (end 91.676509 108.975) (width 0.15) (layer "In2.Cu") (net 282))
  (segment (start 92.046981 104.54849) (end 92.046981 104.65151) (width 0.15) (layer "In2.Cu") (net 282))
  (segment (start 91.923491 103.025) (end 91.950971 103.028096) (width 0.15) (layer "In2.Cu") (net 282))
  (segment (start 92.034752 107.294909) (end 92.043885 107.32101) (width 0.15) (layer "In2.Cu") (net 282))
  (segment (start 91.622928 105.11277) (end 91.649029 105.121903) (width 0.15) (layer "In2.Cu") (net 282))
  (segment (start 91.950971 107.571903) (end 91.923491 107.575) (width 0.15) (layer "In2.Cu") (net 282))
  (segment (start 91.599514 105.501941) (end 91.57996 105.521495) (width 0.15) (layer "In2.Cu") (net 282))
  (segment (start 91.553019 109.79849) (end 91.553019 109.90151) (width 0.15) (layer "In2.Cu") (net 282))
  (segment (start 92.046981 105.35151) (end 92.043885 105.378989) (width 0.15) (layer "In2.Cu") (net 282))
  (segment (start 91.950971 102.671903) (end 91.923491 102.675) (width 0.15) (layer "In2.Cu") (net 282))
  (segment (start 91.556115 109.07101) (end 91.553019 109.09849) (width 0.15) (layer "In2.Cu") (net 282))
  (segment (start 91.556115 109.228989) (end 91.565248 109.25509) (width 0.15) (layer "In2.Cu") (net 282))
  (segment (start 91.553019 106.99849) (end 91.553019 107.10151) (width 0.15) (layer "In2.Cu") (net 282))
  (segment (start 91.622928 109.687229) (end 91.599514 109.701941) (width 0.15) (layer "In2.Cu") (net 282))
  (segment (start 91.599514 104.801941) (end 91.57996 104.821495) (width 0.15) (layer "In2.Cu") (net 282))
  (segment (start 91.977072 107.937229) (end 92.000486 107.951941) (width 0.15) (layer "In2.Cu") (net 282))
  (segment (start 91.676509 104.425) (end 91.923491 104.425) (width 0.15) (layer "In2.Cu") (net 282))
  (segment (start 91.565248 106.45509) (end 91.57996 106.478504) (width 0.15) (layer "In2.Cu") (net 282))
  (segment (start 92.02004 105.171495) (end 92.034752 105.194909) (width 0.15) (layer "In2.Cu") (net 282))
  (segment (start 91.556115 108.528989) (end 91.565248 108.55509) (width 0.15) (layer "In2.Cu") (net 282))
  (segment (start 91.8 101.1) (end 91.8 101.85) (width 0.15) (layer "In2.Cu") (net 282))
  (segment (start 91.556115 107.828989) (end 91.565248 107.85509) (width 0.15) (layer "In2.Cu") (net 282))
  (segment (start 92.046981 109.55151) (end 92.043885 109.578989) (width 0.15) (layer "In2.Cu") (net 282))
  (segment (start 92.02004 102.371495) (end 92.034752 102.394909) (width 0.15) (layer "In2.Cu") (net 282))
  (segment (start 92.046981 108.04849) (end 92.046981 108.15151) (width 0.15) (layer "In2.Cu") (net 282))
  (segment (start 92.046981 108.74849) (end 92.046981 108.85151) (width 0.15) (layer "In2.Cu") (net 282))
  (segment (start 92.034752 106.80509) (end 92.02004 106.828504) (width 0.15) (layer "In2.Cu") (net 282))
  (segment (start 91.796903 101.877479) (end 91.78777 101.90358) (width 0.15) (layer "In2.Cu") (net 282))
  (segment (start 91.649029 108.621903) (end 91.676509 108.625) (width 0.15) (layer "In2.Cu") (net 282))
  (segment (start 91.977072 107.56277) (end 91.950971 107.571903) (width 0.15) (layer "In2.Cu") (net 282))
  (segment (start 91.977072 108.637229) (end 92.000486 108.651941) (width 0.15) (layer "In2.Cu") (net 282))
  (segment (start 91.556115 103.628989) (end 91.565248 103.65509) (width 0.15) (layer "In2.Cu") (net 282))
  (segment (start 92.034752 105.40509) (end 92.02004 105.428504) (width 0.15) (layer "In2.Cu") (net 282))
  (segment (start 91.923491 103.725) (end 91.950971 103.728096) (width 0.15) (layer "In2.Cu") (net 282))
  (segment (start 92.034752 108.90509) (end 92.02004 108.928504) (width 0.15) (layer "In2.Cu") (net 282))
  (segment (start 91.556115 106.428989) (end 91.565248 106.45509) (width 0.15) (layer "In2.Cu") (net 282))
  (segment (start 92.000486 109.351941) (end 92.02004 109.371495) (width 0.15) (layer "In2.Cu") (net 282))
  (segment (start 91.565248 107.15509) (end 91.57996 107.178504) (width 0.15) (layer "In2.Cu") (net 282))
  (segment (start 91.57996 102.019985) (end 91.565248 102.043399) (width 0.15) (layer "In2.Cu") (net 282))
  (segment (start 91.556115 102.77101) (end 91.553019 102.79849) (width 0.15) (layer "In2.Cu") (net 282))
  (segment (start 91.599514 105.098058) (end 91.622928 105.11277) (width 0.15) (layer "In2.Cu") (net 282))
  (segment (start 91.565248 109.044909) (end 91.556115 109.07101) (width 0.15) (layer "In2.Cu") (net 282))
  (segment (start 91.67651 102.32349) (end 91.8 102.32349) (width 0.15) (layer "In2.Cu") (net 282))
  (segment (start 91.950971 107.228096) (end 91.977072 107.237229) (width 0.15) (layer "In2.Cu") (net 282))
  (segment (start 91.565248 102.744909) (end 91.556115 102.77101) (width 0.15) (layer "In2.Cu") (net 282))
  (segment (start 91.78777 110.094909) (end 91.796903 110.12101) (width 0.15) (layer "In2.Cu") (net 282))
  (segment (start 92.046981 105.24849) (end 92.046981 105.35151) (width 0.15) (layer "In2.Cu") (net 282))
  (segment (start 92.02004 109.371495) (end 92.034752 109.394909) (width 0.15) (layer "In2.Cu") (net 282))
  (segment (start 92.043885 109.578989) (end 92.034752 109.60509) (width 0.15) (layer "In2.Cu") (net 282))
  (segment (start 91.796903 110.12101) (end 91.8 110.14849) (width 0.15) (layer "In2.Cu") (net 282))
  (segment (start 91.553019 103.60151) (end 91.556115 103.628989) (width 0.15) (layer "In2.Cu") (net 282))
  (segment (start 91.553019 102.79849) (end 91.553019 102.90151) (width 0.15) (layer "In2.Cu") (net 282))
  (segment (start 91.565248 103.444909) (end 91.556115 103.47101) (width 0.15) (layer "In2.Cu") (net 282))
  (segment (start 91.676509 105.125) (end 91.923491 105.125) (width 0.15) (layer "In2.Cu") (net 282))
  (segment (start 91.622928 107.587229) (end 91.599514 107.601941) (width 0.15) (layer "In2.Cu") (net 282))
  (segment (start 91.977072 103.737229) (end 92.000486 103.751941) (width 0.15) (layer "In2.Cu") (net 282))
  (segment (start 92.034752 103.094909) (end 92.043885 103.12101) (width 0.15) (layer "In2.Cu") (net 282))
  (segment (start 92.034752 107.50509) (end 92.02004 107.528504) (width 0.15) (layer "In2.Cu") (net 282))
  (segment (start 91.950971 103.371903) (end 91.923491 103.375) (width 0.15) (layer "In2.Cu") (net 282))
  (segment (start 91.599514 109.298058) (end 91.622928 109.31277) (width 0.15) (layer "In2.Cu") (net 282))
  (segment (start 91.923491 103.375) (end 91.676509 103.375) (width 0.15) (layer "In2.Cu") (net 282))
  (segment (start 91.649029 103.378096) (end 91.622928 103.387229) (width 0.15) (layer "In2.Cu") (net 282))
  (segment (start 92.000486 108.651941) (end 92.02004 108.671495) (width 0.15) (layer "In2.Cu") (net 282))
  (segment (start 91.977072 103.037229) (end 92.000486 103.051941) (width 0.15) (layer "In2.Cu") (net 282))
  (segment (start 91.649029 105.121903) (end 91.676509 105.125) (width 0.15) (layer "In2.Cu") (net 282))
  (segment (start 91.950971 102.328096) (end 91.977072 102.337229) (width 0.15) (layer "In2.Cu") (net 282))
  (segment (start 91.565248 109.95509) (end 91.57996 109.978504) (width 0.15) (layer "In2.Cu") (net 282))
  (segment (start 92.046981 103.84849) (end 92.046981 103.95151) (width 0.15) (layer "In2.Cu") (net 282))
  (segment (start 91.622928 104.787229) (end 91.599514 104.801941) (width 0.15) (layer "In2.Cu") (net 282))
  (segment (start 91.553019 105.70151) (end 91.556115 105.728989) (width 0.15) (layer "In2.Cu") (net 282))
  (segment (start 91.676509 108.975) (end 91.649029 108.978096) (width 0.15) (layer "In2.Cu") (net 282))
  (segment (start 91.565248 104.144909) (end 91.556115 104.17101) (width 0.15) (layer "In2.Cu") (net 282))
  (segment (start 91.565248 102.25358) (end 91.57996 102.276994) (width 0.15) (layer "In2.Cu") (net 282))
  (segment (start 91.622928 101.985719) (end 91.599514 102.000431) (width 0.15) (layer "In2.Cu") (net 282))
  (segment (start 91.649029 102.320393) (end 91.67651 102.32349) (width 0.15) (layer "In2.Cu") (net 282))
  (segment (start 91.556115 108.37101) (end 91.553019 108.39849) (width 0.15) (layer "In2.Cu") (net 282))
  (segment (start 91.553019 109.09849) (end 91.553019 109.20151) (width 0.15) (layer "In2.Cu") (net 282))
  (segment (start 91.565248 108.55509) (end 91.57996 108.578504) (width 0.15) (layer "In2.Cu") (net 282))
  (segment (start 91.622928 109.31277) (end 91.649029 109.321903) (width 0.15) (layer "In2.Cu") (net 282))
  (segment (start 91.57996 105.078504) (end 91.599514 105.098058) (width 0.15) (layer "In2.Cu") (net 282))
  (segment (start 91.556115 109.928989) (end 91.565248 109.95509) (width 0.15) (layer "In2.Cu") (net 282))
  (segment (start 91.977072 108.96277) (end 91.950971 108.971903) (width 0.15) (layer "In2.Cu") (net 282))
  (segment (start 91.57996 108.321495) (end 91.565248 108.344909) (width 0.15) (layer "In2.Cu") (net 282))
  (segment (start 91.556115 106.27101) (end 91.553019 106.29849) (width 0.15) (layer "In2.Cu") (net 282))
  (segment (start 91.553019 102.2) (end 91.556115 102.227479) (width 0.15) (layer "In2.Cu") (net 282))
  (segment (start 91.565248 107.85509) (end 91.57996 107.878504) (width 0.15) (layer "In2.Cu") (net 282))
  (segment (start 92.02004 106.128504) (end 92.000486 106.148058) (width 0.15) (layer "In2.Cu") (net 282))
  (segment (start 91.622928 103.387229) (end 91.599514 103.401941) (width 0.15) (layer "In2.Cu") (net 282))
  (segment (start 92.046981 106.75151) (end 92.043885 106.778989) (width 0.15) (layer "In2.Cu") (net 282))
  (segment (start 91.599514 106.498058) (end 91.622928 106.51277) (width 0.15) (layer "In2.Cu") (net 282))
  (segment (start 91.622928 102.687229) (end 91.599514 102.701941) (width 0.15) (layer "In2.Cu") (net 282))
  (segment (start 91.553019 109.20151) (end 91.556115 109.228989) (width 0.15) (layer "In2.Cu") (net 282))
  (segment (start 91.703989 110.028096) (end 91.73009 110.037229) (width 0.15) (layer "In2.Cu") (net 282))
  (segment (start 91.553019 105.59849) (end 91.553019 105.70151) (width 0.15) (layer "In2.Cu") (net 282))
  (segment (start 91.553019 108.50151) (end 91.556115 108.528989) (width 0.15) (layer "In2.Cu") (net 282))
  (segment (start 91.57996 104.378504) (end 91.599514 104.398058) (width 0.15) (layer "In2.Cu") (net 282))
  (segment (start 91.565248 103.65509) (end 91.57996 103.678504) (width 0.15) (layer "In2.Cu") (net 282))
  (segment (start 91.57996 102.721495) (end 91.565248 102.744909) (width 0.15) (layer "In2.Cu") (net 282))
  (segment (start 91.950971 105.828096) (end 91.977072 105.837229) (width 0.15) (layer "In2.Cu") (net 282))
  (segment (start 91.977072 107.237229) (end 92.000486 107.251941) (width 0.15) (layer "In2.Cu") (net 282))
  (segment (start 91.950971 106.171903) (end 91.923491 106.175) (width 0.15) (layer "In2.Cu") (net 282))
  (segment (start 91.599514 109.001941) (end 91.57996 109.021495) (width 0.15) (layer "In2.Cu") (net 282))
  (segment (start 92.034752 102.60509) (end 92.02004 102.628504) (width 0.15) (layer "In2.Cu") (net 282))
  (segment (start 92.043885 107.478989) (end 92.034752 107.50509) (width 0.15) (layer "In2.Cu") (net 282))
  (segment (start 91.753504 110.051941) (end 91.773058 110.071495) (width 0.15) (layer "In2.Cu") (net 282))
  (segment (start 92.02004 107.528504) (end 92.000486 107.548058) (width 0.15) (layer "In2.Cu") (net 282))
  (segment (start 91.950971 107.928096) (end 91.977072 107.937229) (width 0.15) (layer "In2.Cu") (net 282))
  (segment (start 91.773058 101.926994) (end 91.753504 101.946548) (width 0.15) (layer "In2.Cu") (net 282))
  (segment (start 91.676509 106.175) (end 91.649029 106.178096) (width 0.15) (layer "In2.Cu") (net 282))
  (segment (start 92.000486 105.151941) (end 92.02004 105.171495) (width 0.15) (layer "In2.Cu") (net 282))
  (segment (start 92.3 100.6) (end 93.85 100.6) (width 0.15) (layer "B.Cu") (net 282))
  (segment (start 92.3 100.6) (end 91.8 101.1) (width 0.15) (layer "B.Cu") (net 282))
  (segment (start 96.8 115.35) (end 96.4 114.95) (width 0.15) (layer "F.Cu") (net 283))
  (segment (start 92.26 95.66) (end 92.76 96.16) (width 0.15) (layer "F.Cu") (net 283))
  (via (at 92.76 96.16) (size 0.5) (drill 0.2) (layers "F.Cu" "B.Cu") (net 283))
  (via (at 96.4 114.95) (size 0.5) (drill 0.2) (layers "F.Cu" "B.Cu") (net 283))
  (segment (start 93.531593 97.954362) (end 93.557854 97.975304) (width 0.15) (layer "In2.Cu") (net 283))
  (segment (start 93.588117 97.989878) (end 93.620864 97.997352) (width 0.15) (layer "In2.Cu") (net 283))
  (segment (start 93.111008 96.751633) (end 93.135613 96.763483) (width 0.15) (layer "In2.Cu") (net 283))
  (segment (start 93.275014 97.40962) (end 93.305277 97.424194) (width 0.15) (layer "In2.Cu") (net 283))
  (segment (start 94.237733 96.956221) (end 94.237732 96.989809) (width 0.15) (layer "In2.Cu") (net 283))
  (segment (start 94.119238 97.584167) (end 94.149501 97.569593) (width 0.15) (layer "In2.Cu") (net 283))
  (segment (start 93.015045 96.595057) (end 93.015045 96.622366) (width 0.15) (layer "In2.Cu") (net 283))
  (segment (start 93.216173 96.763483) (end 93.240779 96.751633) (width 0.15) (layer "In2.Cu") (net 283))
  (segment (start 93.496077 97.798754) (end 93.488603 97.831501) (width 0.15) (layer "In2.Cu") (net 283))
  (segment (start 93.338024 97.431668) (end 93.371613 97.431668) (width 0.15) (layer "In2.Cu") (net 283))
  (segment (start 92.81 96.11) (end 93.05 96.35) (width 0.15) (layer "In2.Cu") (net 283))
  (segment (start 93.717463 97.975304) (end 93.743725 97.954362) (width 0.15) (layer "In2.Cu") (net 283))
  (segment (start 94.215684 97.052819) (end 94.194742 97.079081) (width 0.15) (layer "In2.Cu") (net 283))
  (segment (start 93.77048 96.654819) (end 93.248753 97.176546) (width 0.15) (layer "In2.Cu") (net 283))
  (segment (start 93.791423 96.468949) (end 93.805996 96.499211) (width 0.15) (layer "In2.Cu") (net 283))
  (segment (start 93.248753 97.176546) (end 93.22781 97.202807) (width 0.15) (layer "In2.Cu") (net 283))
  (segment (start 93.032971 96.673597) (end 93.049999 96.694949) (width 0.15) (layer "In2.Cu") (net 283))
  (segment (start 93.084953 96.449892) (end 93.078876 96.476517) (width 0.15) (layer "In2.Cu") (net 283))
  (segment (start 93.262131 96.734605) (end 93.348369 96.648367) (width 0.15) (layer "In2.Cu") (net 283))
  (segment (start 93.021122 96.648992) (end 93.032971 96.673597) (width 0.15) (layer "In2.Cu") (net 283))
  (segment (start 93.40436 97.424194) (end 93.434623 97.40962) (width 0.15) (layer "In2.Cu") (net 283))
  (segment (start 94.092977 97.605109) (end 94.119238 97.584167) (width 0.15) (layer "In2.Cu") (net 283))
  (segment (start 93.77048 96.442687) (end 93.791423 96.468949) (width 0.15) (layer "In2.Cu") (net 283))
  (segment (start 94.237732 96.989809) (end 94.230259 97.022557) (width 0.15) (layer "In2.Cu") (net 283))
  (segment (start 93.510651 97.768491) (end 93.496077 97.798754) (width 0.15) (layer "In2.Cu") (net 283))
  (segment (start 94.248584 97.569593) (end 94.278847 97.584167) (width 0.15) (layer "In2.Cu") (net 283))
  (segment (start 94.149501 97.569593) (end 94.182248 97.562119) (width 0.15) (layer "In2.Cu") (net 283))
  (segment (start 93.032971 96.543826) (end 93.021122 96.568431) (width 0.15) (layer "In2.Cu") (net 283))
  (segment (start 93.813471 96.531959) (end 93.81347 96.565547) (width 0.15) (layer "In2.Cu") (net 283))
  (segment (start 94.215837 97.562119) (end 94.248584 97.569593) (width 0.15) (layer "In2.Cu") (net 283))
  (segment (start 93.22781 97.362417) (end 93.248753 97.388678) (width 0.15) (layer "In2.Cu") (net 283))
  (segment (start 93.6872 97.989878) (end 93.717463 97.975304) (width 0.15) (layer "In2.Cu") (net 283))
  (segment (start 93.213236 97.23307) (end 93.205762 97.265818) (width 0.15) (layer "In2.Cu") (net 283))
  (segment (start 93.496077 97.897837) (end 93.510651 97.9281) (width 0.15) (layer "In2.Cu") (net 283))
  (segment (start 93.647621 96.399697) (end 93.681209 96.399696) (width 0.15) (layer "In2.Cu") (net 283))
  (segment (start 93.350519 96.650519) (end 93.55835 96.442689) (width 0.15) (layer "In2.Cu") (net 283))
  (segment (start 93.81347 96.565547) (end 93.805997 96.598295) (width 0.15) (layer "In2.Cu") (net 283))
  (segment (start 94.215685 96.893211) (end 94.230258 96.923473) (width 0.15) (layer "In2.Cu") (net 283))
  (segment (start 93.371613 97.431668) (end 93.40436 97.424194) (width 0.15) (layer "In2.Cu") (net 283))
  (segment (start 93.22781 97.202807) (end 93.213236 97.23307) (width 0.15) (layer "In2.Cu") (net 283))
  (segment (start 94.105471 96.823958) (end 94.138219 96.831433) (width 0.15) (layer "In2.Cu") (net 283))
  (segment (start 93.531593 97.74223) (end 93.510651 97.768491) (width 0.15) (layer "In2.Cu") (net 283))
  (segment (start 94.305109 97.605109) (end 94.6 97.9) (width 0.15) (layer "In2.Cu") (net 283))
  (segment (start 93.240779 96.751633) (end 93.262131 96.734605) (width 0.15) (layer "In2.Cu") (net 283))
  (segment (start 94.6 97.9) (end 94.6 111.7) (width 0.15) (layer "In2.Cu") (net 283))
  (segment (start 93.620864 97.997352) (end 93.654453 97.997352) (width 0.15) (layer "In2.Cu") (net 283))
  (segment (start 93.460885 97.388678) (end 93.982612 96.866951) (width 0.15) (layer "In2.Cu") (net 283))
  (segment (start 93.584609 96.421744) (end 93.614873 96.407171) (width 0.15) (layer "In2.Cu") (net 283))
  (segment (start 93.982612 96.866951) (end 94.008871 96.846006) (width 0.15) (layer "In2.Cu") (net 283))
  (segment (start 93.614873 96.407171) (end 93.647621 96.399697) (width 0.15) (layer "In2.Cu") (net 283))
  (segment (start 93.531593 97.74223) (end 94.194742 97.079081) (width 0.15) (layer "In2.Cu") (net 283))
  (segment (start 93.791422 96.628557) (end 93.77048 96.654819) (width 0.15) (layer "In2.Cu") (net 283))
  (segment (start 93.248753 97.388678) (end 93.275014 97.40962) (width 0.15) (layer "In2.Cu") (net 283))
  (segment (start 93.557854 97.975304) (end 93.588117 97.989878) (width 0.15) (layer "In2.Cu") (net 283))
  (segment (start 93.213236 97.332154) (end 93.22781 97.362417) (width 0.15) (layer "In2.Cu") (net 283))
  (segment (start 93.205762 97.299407) (end 93.213236 97.332154) (width 0.15) (layer "In2.Cu") (net 283))
  (segment (start 93.021122 96.568431) (end 93.015045 96.595057) (width 0.15) (layer "In2.Cu") (net 283))
  (segment (start 93.55835 96.442689) (end 93.584609 96.421744) (width 0.15) (layer "In2.Cu") (net 283))
  (segment (start 93.488603 97.86509) (end 93.496077 97.897837) (width 0.15) (layer "In2.Cu") (net 283))
  (segment (start 93.305277 97.424194) (end 93.338024 97.431668) (width 0.15) (layer "In2.Cu") (net 283))
  (segment (start 93.743725 97.954362) (end 94.092977 97.605109) (width 0.15) (layer "In2.Cu") (net 283))
  (segment (start 93.434623 97.40962) (end 93.460885 97.388678) (width 0.15) (layer "In2.Cu") (net 283))
  (segment (start 93.089656 96.734606) (end 93.111008 96.751633) (width 0.15) (layer "In2.Cu") (net 283))
  (segment (start 93.681209 96.399696) (end 93.713957 96.407171) (width 0.15) (layer "In2.Cu") (net 283))
  (segment (start 93.084953 96.422582) (end 93.084953 96.449892) (width 0.15) (layer "In2.Cu") (net 283))
  (segment (start 94.138219 96.831433) (end 94.168481 96.846006) (width 0.15) (layer "In2.Cu") (net 283))
  (segment (start 93.135613 96.763483) (end 93.162238 96.76956) (width 0.15) (layer "In2.Cu") (net 283))
  (segment (start 94.194742 96.866949) (end 94.215685 96.893211) (width 0.15) (layer "In2.Cu") (net 283))
  (segment (start 93.067027 96.501122) (end 93.032971 96.543826) (width 0.15) (layer "In2.Cu") (net 283))
  (segment (start 93.744219 96.421744) (end 93.77048 96.442687) (width 0.15) (layer "In2.Cu") (net 283))
  (segment (start 93.654453 97.997352) (end 93.6872 97.989878) (width 0.15) (layer "In2.Cu") (net 283))
  (segment (start 94.008871 96.846006) (end 94.039135 96.831433) (width 0.15) (layer "In2.Cu") (net 283))
  (segment (start 94.6 111.7) (end 96.9 114) (width 0.15) (layer "In2.Cu") (net 283))
  (segment (start 94.168481 96.846006) (end 94.194742 96.866949) (width 0.15) (layer "In2.Cu") (net 283))
  (segment (start 93.713957 96.407171) (end 93.744219 96.421744) (width 0.15) (layer "In2.Cu") (net 283))
  (segment (start 94.278847 97.584167) (end 94.305109 97.605109) (width 0.15) (layer "In2.Cu") (net 283))
  (segment (start 93.805997 96.598295) (end 93.791422 96.628557) (width 0.15) (layer "In2.Cu") (net 283))
  (segment (start 93.488603 97.831501) (end 93.488603 97.86509) (width 0.15) (layer "In2.Cu") (net 283))
  (segment (start 94.182248 97.562119) (end 94.215837 97.562119) (width 0.15) (layer "In2.Cu") (net 283))
  (segment (start 93.049999 96.694949) (end 93.089656 96.734606) (width 0.15) (layer "In2.Cu") (net 283))
  (segment (start 93.189548 96.76956) (end 93.216173 96.763483) (width 0.15) (layer "In2.Cu") (net 283))
  (segment (start 93.348369 96.648367) (end 93.350519 96.650519) (width 0.15) (layer "In2.Cu") (net 283))
  (segment (start 93.05 96.35) (end 93.067027 96.371351) (width 0.15) (layer "In2.Cu") (net 283))
  (segment (start 96.9 114.45) (end 96.4 114.95) (width 0.15) (layer "In2.Cu") (net 283))
  (segment (start 93.805996 96.499211) (end 93.813471 96.531959) (width 0.15) (layer "In2.Cu") (net 283))
  (segment (start 94.071883 96.823959) (end 94.105471 96.823958) (width 0.15) (layer "In2.Cu") (net 283))
  (segment (start 93.205762 97.265818) (end 93.205762 97.299407) (width 0.15) (layer "In2.Cu") (net 283))
  (segment (start 94.230259 97.022557) (end 94.215684 97.052819) (width 0.15) (layer "In2.Cu") (net 283))
  (segment (start 96.9 114) (end 96.9 114.45) (width 0.15) (layer "In2.Cu") (net 283))
  (segment (start 93.067027 96.371351) (end 93.078876 96.395957) (width 0.15) (layer "In2.Cu") (net 283))
  (segment (start 94.230258 96.923473) (end 94.237733 96.956221) (width 0.15) (layer "In2.Cu") (net 283))
  (segment (start 94.039135 96.831433) (end 94.071883 96.823959) (width 0.15) (layer "In2.Cu") (net 283))
  (segment (start 93.078876 96.395957) (end 93.084953 96.422582) (width 0.15) (layer "In2.Cu") (net 283))
  (segment (start 93.510651 97.9281) (end 93.531593 97.954362) (width 0.15) (layer "In2.Cu") (net 283))
  (segment (start 93.162238 96.76956) (end 93.189548 96.76956) (width 0.15) (layer "In2.Cu") (net 283))
  (segment (start 93.015045 96.622366) (end 93.021122 96.648992) (width 0.15) (layer "In2.Cu") (net 283))
  (segment (start 93.078876 96.476517) (end 93.067027 96.501122) (width 0.15) (layer "In2.Cu") (net 283))
  (segment (start 92.845 96.075) (end 92.76 96.16) (width 0.15) (layer "B.Cu") (net 283))
  (segment (start 94.09 96.075) (end 92.845 96.075) (width 0.15) (layer "B.Cu") (net 283))
  (segment (start 89.3 95.6) (end 89.8 96.1) (width 0.15) (layer "F.Cu") (net 284))
  (segment (start 95.2 115.35) (end 94.8 115.75) (width 0.15) (layer "F.Cu") (net 284))
  (via (at 89.8 96.1) (size 0.5) (drill 0.2) (layers "F.Cu" "B.Cu") (net 284))
  (via (at 94.8 115.75) (size 0.5) (drill 0.2) (layers "F.Cu" "B.Cu") (net 284))
  (segment (start 90.794096 97.198365) (end 90.815849 97.181014) (width 0.15) (layer "In2.Cu") (net 284))
  (segment (start 90.581613 98.307609) (end 90.620801 98.307609) (width 0.15) (layer "In2.Cu") (net 284))
  (segment (start 90.436028 98.191509) (end 90.453031 98.226816) (width 0.15) (layer "In2.Cu") (net 284))
  (segment (start 90.225213 97.62714) (end 90.263418 97.63586) (width 0.15) (layer "In2.Cu") (net 284))
  (segment (start 91.411763 97.711012) (end 91.518875 97.818124) (width 0.15) (layer "In2.Cu") (net 284))
  (segment (start 90.543408 98.298889) (end 90.581613 98.307609) (width 0.15) (layer "In2.Cu") (net 284))
  (segment (start 90.134836 97.555067) (end 90.159269 97.585705) (width 0.15) (layer "In2.Cu") (net 284))
  (segment (start 91.542378 97.921096) (end 91.532734 97.941122) (width 0.15) (layer "In2.Cu") (net 284))
  (segment (start 90.427308 98.153304) (end 90.436028 98.191509) (width 0.15) (layer "In2.Cu") (net 284))
  (segment (start 91.490426 98.017574) (end 91.490425 98.0398) (width 0.15) (layer "In2.Cu") (net 284))
  (segment (start 90.302606 97.63586) (end 90.340811 97.62714) (width 0.15) (layer "In2.Cu") (net 284))
  (segment (start 90.406756 97.585705) (end 90.794096 97.198365) (width 0.15) (layer "In2.Cu") (net 284))
  (segment (start 90.724951 98.257454) (end 91.271391 97.711014) (width 0.15) (layer "In2.Cu") (net 284))
  (segment (start 91.495371 98.06147) (end 91.505015 98.081496) (width 0.15) (layer "In2.Cu") (net 284))
  (segment (start 91.077195 97.344073) (end 91.077194 97.371897) (width 0.15) (layer "In2.Cu") (net 284))
  (segment (start 89.8 96.1) (end 89.8 96.38) (width 0.15) (layer "In2.Cu") (net 284))
  (segment (start 91.532733 97.835502) (end 91.542377 97.855528) (width 0.15) (layer "In2.Cu") (net 284))
  (segment (start 90.109113 97.442367) (end 90.109113 97.481555) (width 0.15) (layer "In2.Cu") (net 284))
  (segment (start 90.453031 98.226816) (end 90.477464 98.257454) (width 0.15) (layer "In2.Cu") (net 284))
  (segment (start 90.477464 98.009967) (end 90.453031 98.040605) (width 0.15) (layer "In2.Cu") (net 284))
  (segment (start 90.923 97.168941) (end 90.948071 97.181015) (width 0.15) (layer "In2.Cu") (net 284))
  (segment (start 91.490425 98.0398) (end 91.495371 98.06147) (width 0.15) (layer "In2.Cu") (net 284))
  (segment (start 91.505015 98.081496) (end 91.518875 98.098875) (width 0.15) (layer "In2.Cu") (net 284))
  (segment (start 90.815849 97.181014) (end 90.84092 97.168942) (width 0.15) (layer "In2.Cu") (net 284))
  (segment (start 90.385155 97.058337) (end 90.376435 97.096542) (width 0.15) (layer "In2.Cu") (net 284))
  (segment (start 91.518876 97.9585) (end 91.518874 97.958499) (width 0.15) (layer "In2.Cu") (net 284))
  (segment (start 90.134836 97.368855) (end 90.117833 97.404162) (width 0.15) (layer "In2.Cu") (net 284))
  (segment (start 90.436028 98.075912) (end 90.427308 98.114117) (width 0.15) (layer "In2.Cu") (net 284))
  (segment (start 90.508102 98.281887) (end 90.543408 98.298889) (width 0.15) (layer "In2.Cu") (net 284))
  (segment (start 92.85 110.9) (end 92.85 113.45) (width 0.15) (layer "In2.Cu") (net 284))
  (segment (start 91.518875 97.818124) (end 91.532733 97.835502) (width 0.15) (layer "In2.Cu") (net 284))
  (segment (start 90.868048 97.16275) (end 90.895872 97.162749) (width 0.15) (layer "In2.Cu") (net 284))
  (segment (start 90.453031 98.040605) (end 90.436028 98.075912) (width 0.15) (layer "In2.Cu") (net 284))
  (segment (start 90.376435 97.096542) (end 90.359433 97.131849) (width 0.15) (layer "In2.Cu") (net 284))
  (segment (start 90.263418 97.63586) (end 90.302606 97.63586) (width 0.15) (layer "In2.Cu") (net 284))
  (segment (start 90.117833 97.404162) (end 90.109113 97.442367) (width 0.15) (layer "In2.Cu") (net 284))
  (segment (start 91.374361 97.687511) (end 91.394387 97.697155) (width 0.15) (layer "In2.Cu") (net 284))
  (segment (start 94.8 115.4) (end 94.8 115.75) (width 0.15) (layer "In2.Cu") (net 284))
  (segment (start 91.288767 97.697154) (end 91.308793 97.68751) (width 0.15) (layer "In2.Cu") (net 284))
  (segment (start 90.376435 96.980944) (end 90.385155 97.019149) (width 0.15) (layer "In2.Cu") (net 284))
  (segment (start 91.542377 97.855528) (end 91.547323 97.877198) (width 0.15) (layer "In2.Cu") (net 284))
  (segment (start 90.969824 97.198363) (end 91.041581 97.27012) (width 0.15) (layer "In2.Cu") (net 284))
  (segment (start 90.385155 97.019149) (end 90.385155 97.058337) (width 0.15) (layer "In2.Cu") (net 284))
  (segment (start 91.308793 97.68751) (end 91.330463 97.682565) (width 0.15) (layer "In2.Cu") (net 284))
  (segment (start 90.659006 98.298889) (end 90.694313 98.281887) (width 0.15) (layer "In2.Cu") (net 284))
  (segment (start 91.330463 97.682565) (end 91.352691 97.682565) (width 0.15) (layer "In2.Cu") (net 284))
  (segment (start 91.394387 97.697155) (end 91.411763 97.711012) (width 0.15) (layer "In2.Cu") (net 284))
  (segment (start 91.071004 97.399026) (end 91.05893 97.424095) (width 0.15) (layer "In2.Cu") (net 284))
  (segment (start 90.189907 97.610138) (end 90.225213 97.62714) (width 0.15) (layer "In2.Cu") (net 284))
  (segment (start 91.518875 98.098875) (end 92.3 98.88) (width 0.15) (layer "In2.Cu") (net 284))
  (segment (start 90.895872 97.162749) (end 90.923 97.168941) (width 0.15) (layer "In2.Cu") (net 284))
  (segment (start 91.05893 97.424095) (end 91.041581 97.44585) (width 0.15) (layer "In2.Cu") (net 284))
  (segment (start 91.352691 97.682565) (end 91.374361 97.687511) (width 0.15) (layer "In2.Cu") (net 284))
  (segment (start 91.547323 97.877198) (end 91.547324 97.899426) (width 0.15) (layer "In2.Cu") (net 284))
  (segment (start 90.335 96.915) (end 90.359433 96.945638) (width 0.15) (layer "In2.Cu") (net 284))
  (segment (start 92.3 98.88) (end 92.3 110.35) (width 0.15) (layer "In2.Cu") (net 284))
  (segment (start 91.518874 97.958499) (end 91.505016 97.975878) (width 0.15) (layer "In2.Cu") (net 284))
  (segment (start 90.109113 97.481555) (end 90.117833 97.51976) (width 0.15) (layer "In2.Cu") (net 284))
  (segment (start 91.271391 97.711014) (end 91.288767 97.697154) (width 0.15) (layer "In2.Cu") (net 284))
  (segment (start 90.159269 97.585705) (end 90.189907 97.610138) (width 0.15) (layer "In2.Cu") (net 284))
  (segment (start 92.3 110.35) (end 92.85 110.9) (width 0.15) (layer "In2.Cu") (net 284))
  (segment (start 90.948071 97.181015) (end 90.969824 97.198363) (width 0.15) (layer "In2.Cu") (net 284))
  (segment (start 91.505016 97.975878) (end 91.495372 97.995904) (width 0.15) (layer "In2.Cu") (net 284))
  (segment (start 90.477464 98.257454) (end 90.508102 98.281887) (width 0.15) (layer "In2.Cu") (net 284))
  (segment (start 89.8 96.38) (end 90.335 96.915) (width 0.15) (layer "In2.Cu") (net 284))
  (segment (start 90.359433 97.131849) (end 90.335 97.162487) (width 0.15) (layer "In2.Cu") (net 284))
  (segment (start 90.84092 97.168942) (end 90.868048 97.16275) (width 0.15) (layer "In2.Cu") (net 284))
  (segment (start 91.058931 97.291875) (end 91.071003 97.316944) (width 0.15) (layer "In2.Cu") (net 284))
  (segment (start 90.694313 98.281887) (end 90.724951 98.257454) (width 0.15) (layer "In2.Cu") (net 284))
  (segment (start 91.041581 97.27012) (end 91.058931 97.291875) (width 0.15) (layer "In2.Cu") (net 284))
  (segment (start 92.85 113.45) (end 94.8 115.4) (width 0.15) (layer "In2.Cu") (net 284))
  (segment (start 90.335 97.162487) (end 90.159269 97.338217) (width 0.15) (layer "In2.Cu") (net 284))
  (segment (start 90.117833 97.51976) (end 90.134836 97.555067) (width 0.15) (layer "In2.Cu") (net 284))
  (segment (start 90.159269 97.338217) (end 90.134836 97.368855) (width 0.15) (layer "In2.Cu") (net 284))
  (segment (start 90.359433 96.945638) (end 90.376435 96.980944) (width 0.15) (layer "In2.Cu") (net 284))
  (segment (start 91.071003 97.316944) (end 91.077195 97.344073) (width 0.15) (layer "In2.Cu") (net 284))
  (segment (start 90.620801 98.307609) (end 90.659006 98.298889) (width 0.15) (layer "In2.Cu") (net 284))
  (segment (start 90.376118 97.610138) (end 90.406756 97.585705) (width 0.15) (layer "In2.Cu") (net 284))
  (segment (start 90.477464 98.009967) (end 91.041581 97.44585) (width 0.15) (layer "In2.Cu") (net 284))
  (segment (start 90.427308 98.114117) (end 90.427308 98.153304) (width 0.15) (layer "In2.Cu") (net 284))
  (segment (start 91.532734 97.941122) (end 91.518876 97.9585) (width 0.15) (layer "In2.Cu") (net 284))
  (segment (start 91.495372 97.995904) (end 91.490426 98.017574) (width 0.15) (layer "In2.Cu") (net 284))
  (segment (start 90.340811 97.62714) (end 90.376118 97.610138) (width 0.15) (layer "In2.Cu") (net 284))
  (segment (start 91.547324 97.899426) (end 91.542378 97.921096) (width 0.15) (layer "In2.Cu") (net 284))
  (segment (start 91.077194 97.371897) (end 91.071004 97.399026) (width 0.15) (layer "In2.Cu") (net 284))
  (segment (start 89.2 96.7) (end 89.8 96.1) (width 0.15) (layer "B.Cu") (net 284))
  (segment (start 92.3 94.6) (end 92.8 95.1) (width 0.15) (layer "F.Cu") (net 285))
  (segment (start 96 115.35) (end 96.4 115.75) (width 0.15) (layer "F.Cu") (net 285))
  (via (at 92.8 95.1) (size 0.5) (drill 0.2) (layers "F.Cu" "B.Cu") (net 285))
  (via (at 96.4 115.75) (size 0.5) (drill 0.2) (layers "F.Cu" "B.Cu") (net 285))
  (segment (start 93.185708 95.829678) (end 93.215971 95.815104) (width 0.15) (layer "In2.Cu") (net 285))
  (segment (start 93.09299 95.47286) (end 93.085516 95.505607) (width 0.15) (layer "In2.Cu") (net 285))
  (segment (start 93.762817 95.294583) (end 93.795565 95.287109) (width 0.15) (layer "In2.Cu") (net 285))
  (segment (start 92.8 95.1) (end 93.05 95.35) (width 0.15) (layer "In2.Cu") (net 285))
  (segment (start 92.994584 95.638554) (end 92.98711 95.671302) (width 0.15) (layer "In2.Cu") (net 285))
  (segment (start 97.2 113.75) (end 97.2 114.95) (width 0.15) (layer "In2.Cu") (net 285))
  (segment (start 93.961415 95.419371) (end 93.961414 95.452959) (width 0.15) (layer "In2.Cu") (net 285))
  (segment (start 95.15 97.45) (end 95.15 111.7) (width 0.15) (layer "In2.Cu") (net 285))
  (segment (start 93.070942 95.376261) (end 93.085516 95.406524) (width 0.15) (layer "In2.Cu") (net 285))
  (segment (start 93.861901 95.294583) (end 93.892163 95.309156) (width 0.15) (layer "In2.Cu") (net 285))
  (segment (start 93.650876 95.929869) (end 93.665451 95.960133) (width 0.15) (layer "In2.Cu") (net 285))
  (segment (start 93.643402 95.863533) (end 93.643403 95.897123) (width 0.15) (layer "In2.Cu") (net 285))
  (segment (start 93.892163 95.309156) (end 93.918424 95.330099) (width 0.15) (layer "In2.Cu") (net 285))
  (segment (start 93.643403 95.897123) (end 93.650876 95.929869) (width 0.15) (layer "In2.Cu") (net 285))
  (segment (start 93.686394 95.774262) (end 93.665451 95.800523) (width 0.15) (layer "In2.Cu") (net 285))
  (segment (start 93.650876 95.830785) (end 93.643402 95.863533) (width 0.15) (layer "In2.Cu") (net 285))
  (segment (start 93.215971 95.815104) (end 93.242233 95.794162) (width 0.15) (layer "In2.Cu") (net 285))
  (segment (start 93.086625 95.829678) (end 93.119372 95.837152) (width 0.15) (layer "In2.Cu") (net 285))
  (segment (start 93.009158 95.767901) (end 93.030101 95.794162) (width 0.15) (layer "In2.Cu") (net 285))
  (segment (start 93.262131 95.774263) (end 93.706294 95.330101) (width 0.15) (layer "In2.Cu") (net 285))
  (segment (start 92.98711 95.704891) (end 92.994584 95.737638) (width 0.15) (layer "In2.Cu") (net 285))
  (segment (start 95.15 111.7) (end 97.2 113.75) (width 0.15) (layer "In2.Cu") (net 285))
  (segment (start 93.119372 95.837152) (end 93.152961 95.837152) (width 0.15) (layer "In2.Cu") (net 285))
  (segment (start 93.05 95.562132) (end 93.030101 95.58203) (width 0.15) (layer "In2.Cu") (net 285))
  (segment (start 93.085516 95.505607) (end 93.070942 95.53587) (width 0.15) (layer "In2.Cu") (net 285))
  (segment (start 93.732553 95.309156) (end 93.762817 95.294583) (width 0.15) (layer "In2.Cu") (net 285))
  (segment (start 93.686394 95.986394) (end 95.15 97.45) (width 0.15) (layer "In2.Cu") (net 285))
  (segment (start 93.056362 95.815104) (end 93.086625 95.829678) (width 0.15) (layer "In2.Cu") (net 285))
  (segment (start 93.030101 95.58203) (end 93.009158 95.608291) (width 0.15) (layer "In2.Cu") (net 285))
  (segment (start 93.085516 95.406524) (end 93.09299 95.439271) (width 0.15) (layer "In2.Cu") (net 285))
  (segment (start 93.795565 95.287109) (end 93.829153 95.287108) (width 0.15) (layer "In2.Cu") (net 285))
  (segment (start 93.918424 95.330099) (end 93.939367 95.356361) (width 0.15) (layer "In2.Cu") (net 285))
  (segment (start 93.09299 95.439271) (end 93.09299 95.47286) (width 0.15) (layer "In2.Cu") (net 285))
  (segment (start 93.953941 95.485707) (end 93.939366 95.515969) (width 0.15) (layer "In2.Cu") (net 285))
  (segment (start 93.918424 95.542231) (end 93.686394 95.774262) (width 0.15) (layer "In2.Cu") (net 285))
  (segment (start 93.939366 95.515969) (end 93.918424 95.542231) (width 0.15) (layer "In2.Cu") (net 285))
  (segment (start 93.829153 95.287108) (end 93.861901 95.294583) (width 0.15) (layer "In2.Cu") (net 285))
  (segment (start 93.009158 95.608291) (end 92.994584 95.638554) (width 0.15) (layer "In2.Cu") (net 285))
  (segment (start 93.665451 95.960133) (end 93.686394 95.986394) (width 0.15) (layer "In2.Cu") (net 285))
  (segment (start 93.939367 95.356361) (end 93.95394 95.386623) (width 0.15) (layer "In2.Cu") (net 285))
  (segment (start 93.152961 95.837152) (end 93.185708 95.829678) (width 0.15) (layer "In2.Cu") (net 285))
  (segment (start 93.242233 95.794162) (end 93.262131 95.774263) (width 0.15) (layer "In2.Cu") (net 285))
  (segment (start 93.706294 95.330101) (end 93.732553 95.309156) (width 0.15) (layer "In2.Cu") (net 285))
  (segment (start 93.070942 95.53587) (end 93.05 95.562132) (width 0.15) (layer "In2.Cu") (net 285))
  (segment (start 97.2 114.95) (end 96.4 115.75) (width 0.15) (layer "In2.Cu") (net 285))
  (segment (start 92.98711 95.671302) (end 92.98711 95.704891) (width 0.15) (layer "In2.Cu") (net 285))
  (segment (start 93.961414 95.452959) (end 93.953941 95.485707) (width 0.15) (layer "In2.Cu") (net 285))
  (segment (start 93.030101 95.794162) (end 93.056362 95.815104) (width 0.15) (layer "In2.Cu") (net 285))
  (segment (start 92.994584 95.737638) (end 93.009158 95.767901) (width 0.15) (layer "In2.Cu") (net 285))
  (segment (start 93.95394 95.386623) (end 93.961415 95.419371) (width 0.15) (layer "In2.Cu") (net 285))
  (segment (start 93.05 95.35) (end 93.070942 95.376261) (width 0.15) (layer "In2.Cu") (net 285))
  (segment (start 93.665451 95.800523) (end 93.650876 95.830785) (width 0.15) (layer "In2.Cu") (net 285))
  (segment (start 92.85 95.05) (end 92.8 95.1) (width 0.15) (layer "B.Cu") (net 285))
  (segment (start 94.09 95.05) (end 92.85 95.05) (width 0.15) (layer "B.Cu") (net 285))
  (segment (start 96 114.55) (end 95.6 114.15) (width 0.15) (layer "F.Cu") (net 286))
  (segment (start 89.3 94.6) (end 89.8 95.1) (width 0.15) (layer "F.Cu") (net 286))
  (via (at 95.6 114.15) (size 0.5) (drill 0.2) (layers "F.Cu" "B.Cu") (net 286))
  (via (at 89.8 95.1) (size 0.5) (drill 0.2) (layers "F.Cu" "B.Cu") (net 286))
  (segment (start 90.718185 95.547778) (end 90.744446 95.568721) (width 0.15) (layer "In2.Cu") (net 286))
  (segment (start 90.072013 95.689764) (end 90.083497 95.71361) (width 0.15) (layer "In2.Cu") (net 286))
  (segment (start 90.588839 95.533204) (end 90.621587 95.525731) (width 0.15) (layer "In2.Cu") (net 286))
  (segment (start 93.65 112.2) (end 95.6 114.15) (width 0.15) (layer "In2.Cu") (net 286))
  (segment (start 91.099987 96.353707) (end 91.10746 96.386453) (width 0.15) (layer "In2.Cu") (net 286))
  (segment (start 90.283133 96.407094) (end 90.304076 96.433355) (width 0.15) (layer "In2.Cu") (net 286))
  (segment (start 90.779963 95.724329) (end 90.765388 95.754591) (width 0.15) (layer "In2.Cu") (net 286))
  (segment (start 91.122035 96.257107) (end 91.10746 96.287369) (width 0.15) (layer "In2.Cu") (net 286))
  (segment (start 91.345485 95.816206) (end 91.366428 95.842468) (width 0.15) (layer "In2.Cu") (net 286))
  (segment (start 90.066124 95.637493) (end 90.066124 95.663961) (width 0.15) (layer "In2.Cu") (net 286))
  (segment (start 91.10746 96.386453) (end 91.122035 96.416717) (width 0.15) (layer "In2.Cu") (net 286))
  (segment (start 90.127985 95.444538) (end 90.133875 95.470342) (width 0.15) (layer "In2.Cu") (net 286))
  (segment (start 91.3 96.6) (end 91.3 97.21) (width 0.15) (layer "In2.Cu") (net 286))
  (segment (start 90.532316 95.568723) (end 90.558577 95.547779) (width 0.15) (layer "In2.Cu") (net 286))
  (segment (start 90.744446 95.568721) (end 90.765389 95.594983) (width 0.15) (layer "In2.Cu") (net 286))
  (segment (start 90.779962 95.625245) (end 90.787437 95.657993) (width 0.15) (layer "In2.Cu") (net 286))
  (segment (start 90.283133 96.247484) (end 90.268559 96.277747) (width 0.15) (layer "In2.Cu") (net 286))
  (segment (start 90.083497 95.587844) (end 90.072013 95.61169) (width 0.15) (layer "In2.Cu") (net 286))
  (segment (start 91.10746 96.287369) (end 91.099987 96.320117) (width 0.15) (layer "In2.Cu") (net 286))
  (segment (start 91.159614 95.795263) (end 91.189878 95.78069) (width 0.15) (layer "In2.Cu") (net 286))
  (segment (start 90.400519 95.700519) (end 90.532316 95.568723) (width 0.15) (layer "In2.Cu") (net 286))
  (segment (start 91.256214 95.773215) (end 91.288962 95.78069) (width 0.15) (layer "In2.Cu") (net 286))
  (segment (start 90.787437 95.657993) (end 90.787436 95.691581) (width 0.15) (layer "In2.Cu") (net 286))
  (segment (start 89.8 95.1) (end 90.1 95.4) (width 0.15) (layer "In2.Cu") (net 286))
  (segment (start 90.621587 95.525731) (end 90.655175 95.52573) (width 0.15) (layer "In2.Cu") (net 286))
  (segment (start 90.765389 95.594983) (end 90.779962 95.625245) (width 0.15) (layer "In2.Cu") (net 286))
  (segment (start 90.3606 96.468871) (end 90.393347 96.476345) (width 0.15) (layer "In2.Cu") (net 286))
  (segment (start 90.765388 95.754591) (end 90.744446 95.780853) (width 0.15) (layer "In2.Cu") (net 286))
  (segment (start 91.122035 96.416717) (end 91.142978 96.442978) (width 0.15) (layer "In2.Cu") (net 286))
  (segment (start 93.35 107.9) (end 93.65 108.2) (width 0.15) (layer "In2.Cu") (net 286))
  (segment (start 90.291438 95.795785) (end 90.312131 95.779282) (width 0.15) (layer "In2.Cu") (net 286))
  (segment (start 90.261085 96.344084) (end 90.268559 96.376831) (width 0.15) (layer "In2.Cu") (net 286))
  (segment (start 90.516208 96.433355) (end 91.133355 95.816208) (width 0.15) (layer "In2.Cu") (net 286))
  (segment (start 90.393347 96.476345) (end 90.426936 96.476345) (width 0.15) (layer "In2.Cu") (net 286))
  (segment (start 91.189878 95.78069) (end 91.222624 95.773215) (width 0.15) (layer "In2.Cu") (net 286))
  (segment (start 90.215321 95.813158) (end 90.241788 95.813158) (width 0.15) (layer "In2.Cu") (net 286))
  (segment (start 91.133355 95.816208) (end 91.159614 95.795263) (width 0.15) (layer "In2.Cu") (net 286))
  (segment (start 90.395707 95.695706) (end 90.400519 95.700519) (width 0.15) (layer "In2.Cu") (net 286))
  (segment (start 90.133875 95.470342) (end 90.133875 95.496809) (width 0.15) (layer "In2.Cu") (net 286))
  (segment (start 90.116501 95.420692) (end 90.127985 95.444538) (width 0.15) (layer "In2.Cu") (net 286))
  (segment (start 91.388475 95.939066) (end 91.381002 95.971814) (width 0.15) (layer "In2.Cu") (net 286))
  (segment (start 91.381002 95.971814) (end 91.366427 96.002076) (width 0.15) (layer "In2.Cu") (net 286))
  (segment (start 91.388476 95.905478) (end 91.388475 95.939066) (width 0.15) (layer "In2.Cu") (net 286))
  (segment (start 90.558577 95.547779) (end 90.588839 95.533204) (width 0.15) (layer "In2.Cu") (net 286))
  (segment (start 90.066124 95.663961) (end 90.072013 95.689764) (width 0.15) (layer "In2.Cu") (net 286))
  (segment (start 90.426936 96.476345) (end 90.459683 96.468871) (width 0.15) (layer "In2.Cu") (net 286))
  (segment (start 91.3 97.21) (end 93.35 99.26) (width 0.15) (layer "In2.Cu") (net 286))
  (segment (start 90.787436 95.691581) (end 90.779963 95.724329) (width 0.15) (layer "In2.Cu") (net 286))
  (segment (start 90.304076 96.221223) (end 90.744446 95.780853) (width 0.15) (layer "In2.Cu") (net 286))
  (segment (start 91.366427 96.002076) (end 91.345485 96.028338) (width 0.15) (layer "In2.Cu") (net 286))
  (segment (start 91.345485 96.028338) (end 91.142978 96.230846) (width 0.15) (layer "In2.Cu") (net 286))
  (segment (start 90.133875 95.496809) (end 90.127985 95.522612) (width 0.15) (layer "In2.Cu") (net 286))
  (segment (start 90.687923 95.533205) (end 90.718185 95.547778) (width 0.15) (layer "In2.Cu") (net 286))
  (segment (start 91.142978 96.442978) (end 91.3 96.6) (width 0.15) (layer "In2.Cu") (net 286))
  (segment (start 90.189518 95.807269) (end 90.215321 95.813158) (width 0.15) (layer "In2.Cu") (net 286))
  (segment (start 90.116501 95.546458) (end 90.083497 95.587844) (width 0.15) (layer "In2.Cu") (net 286))
  (segment (start 91.288962 95.78069) (end 91.319224 95.795263) (width 0.15) (layer "In2.Cu") (net 286))
  (segment (start 90.099999 95.734303) (end 90.144979 95.779283) (width 0.15) (layer "In2.Cu") (net 286))
  (segment (start 90.304076 96.221223) (end 90.283133 96.247484) (width 0.15) (layer "In2.Cu") (net 286))
  (segment (start 90.261085 96.310494) (end 90.261085 96.344084) (width 0.15) (layer "In2.Cu") (net 286))
  (segment (start 90.489946 96.454297) (end 90.516208 96.433355) (width 0.15) (layer "In2.Cu") (net 286))
  (segment (start 90.330337 96.454297) (end 90.3606 96.468871) (width 0.15) (layer "In2.Cu") (net 286))
  (segment (start 93.65 108.2) (end 93.65 112.2) (width 0.15) (layer "In2.Cu") (net 286))
  (segment (start 90.459683 96.468871) (end 90.489946 96.454297) (width 0.15) (layer "In2.Cu") (net 286))
  (segment (start 90.312131 95.779282) (end 90.395707 95.695706) (width 0.15) (layer "In2.Cu") (net 286))
  (segment (start 90.268559 96.376831) (end 90.283133 96.407094) (width 0.15) (layer "In2.Cu") (net 286))
  (segment (start 91.099987 96.320117) (end 91.099987 96.353707) (width 0.15) (layer "In2.Cu") (net 286))
  (segment (start 91.142978 96.230846) (end 91.122035 96.257107) (width 0.15) (layer "In2.Cu") (net 286))
  (segment (start 90.165672 95.795785) (end 90.189518 95.807269) (width 0.15) (layer "In2.Cu") (net 286))
  (segment (start 90.1 95.4) (end 90.116501 95.420692) (width 0.15) (layer "In2.Cu") (net 286))
  (segment (start 90.127985 95.522612) (end 90.116501 95.546458) (width 0.15) (layer "In2.Cu") (net 286))
  (segment (start 91.222624 95.773215) (end 91.256214 95.773215) (width 0.15) (layer "In2.Cu") (net 286))
  (segment (start 91.319224 95.795263) (end 91.345485 95.816206) (width 0.15) (layer "In2.Cu") (net 286))
  (segment (start 90.083497 95.71361) (end 90.099999 95.734303) (width 0.15) (layer "In2.Cu") (net 286))
  (segment (start 90.144979 95.779283) (end 90.165672 95.795785) (width 0.15) (layer "In2.Cu") (net 286))
  (segment (start 93.35 99.26) (end 93.35 107.9) (width 0.15) (layer "In2.Cu") (net 286))
  (segment (start 91.366428 95.842468) (end 91.381001 95.87273) (width 0.15) (layer "In2.Cu") (net 286))
  (segment (start 90.655175 95.52573) (end 90.687923 95.533205) (width 0.15) (layer "In2.Cu") (net 286))
  (segment (start 91.381001 95.87273) (end 91.388476 95.905478) (width 0.15) (layer "In2.Cu") (net 286))
  (segment (start 90.072013 95.61169) (end 90.066124 95.637493) (width 0.15) (layer "In2.Cu") (net 286))
  (segment (start 90.241788 95.813158) (end 90.267592 95.807269) (width 0.15) (layer "In2.Cu") (net 286))
  (segment (start 90.268559 96.277747) (end 90.261085 96.310494) (width 0.15) (layer "In2.Cu") (net 286))
  (segment (start 90.267592 95.807269) (end 90.291438 95.795785) (width 0.15) (layer "In2.Cu") (net 286))
  (segment (start 90.304076 96.433355) (end 90.330337 96.454297) (width 0.15) (layer "In2.Cu") (net 286))
  (segment (start 89.5 95.4) (end 89.8 95.1) (width 0.15) (layer "B.Cu") (net 286))
  (segment (start 89.5 95.4) (end 89.2 95.7) (width 0.15) (layer "B.Cu") (net 286))
  (segment (start 93.29 98.58) (end 92.79 98.08) (width 0.15) (layer "F.Cu") (net 287))
  (segment (start 96.8 114.55) (end 96.4 114.15) (width 0.15) (layer "F.Cu") (net 287))
  (via (at 92.79 98.08) (size 0.5) (drill 0.2) (layers "F.Cu" "B.Cu") (net 287))
  (via (at 96.4 114.15) (size 0.5) (drill 0.2) (layers "F.Cu" "B.Cu") (net 287))
  (segment (start 94.349328 100.139664) (end 94.349328 100.140336) (width 0.15) (layer "In2.Cu") (net 287))
  (segment (start 93.604432 100.473378) (end 93.615526 100.505082) (width 0.15) (layer "In2.Cu") (net 287))
  (segment (start 93.633397 102.146476) (end 93.615526 102.174917) (width 0.15) (layer "In2.Cu") (net 287))
  (segment (start 93.633397 101.133523) (end 93.657148 101.157274) (width 0.15) (layer "In2.Cu") (net 287))
  (segment (start 94.292978 100.022651) (end 94.316677 100.04635) (width 0.15) (layer "In2.Cu") (net 287))
  (segment (start 93.789894 98.449768) (end 93.804467 98.48003) (width 0.15) (layer "In2.Cu") (net 287))
  (segment (start 94.345576 101.90636) (end 94.349328 101.939664) (width 0.15) (layer "In2.Cu") (net 287))
  (segment (start 94.349328 101.940336) (end 94.345576 101.973639) (width 0.15) (layer "In2.Cu") (net 287))
  (segment (start 93.717293 102.09376) (end 93.685589 102.104854) (width 0.15) (layer "In2.Cu") (net 287))
  (segment (start 93.090424 98.462519) (end 93.069575 98.488661) (width 0.15) (layer "In2.Cu") (net 287))
  (segment (start 93.504499 99.005681) (end 93.61104 99.112222) (width 0.15) (layer "In2.Cu") (net 287))
  (segment (start 93.613344 98.387989) (end 93.646092 98.380516) (width 0.15) (layer "In2.Cu") (net 287))
  (segment (start 93.768951 98.635638) (end 93.504499 98.90009) (width 0.15) (layer "In2.Cu") (net 287))
  (segment (start 94.232968 100.886247) (end 94.199664 100.89) (width 0.15) (layer "In2.Cu") (net 287))
  (segment (start 93.703559 99.122646) (end 93.729702 99.101797) (width 0.15) (layer "In2.Cu") (net 287))
  (segment (start 94.334507 100.674727) (end 94.345576 100.70636) (width 0.15) (layer "In2.Cu") (net 287))
  (segment (start 93.657148 100.322725) (end 93.633397 100.346476) (width 0.15) (layer "In2.Cu") (net 287))
  (segment (start 93.504499 98.90009) (end 93.494075 98.913162) (width 0.15) (layer "In2.Cu") (net 287))
  (segment (start 93.615526 101.105082) (end 93.633397 101.133523) (width 0.15) (layer "In2.Cu") (net 287))
  (segment (start 93.717293 102.386239) (end 93.750672 102.39) (width 0.15) (layer "In2.Cu") (net 287))
  (segment (start 93.069575 98.568109) (end 93.08 98.58118) (width 0.15) (layer "In2.Cu") (net 287))
  (segment (start 93.604432 102.206621) (end 93.600672 102.24) (width 0.15) (layer "In2.Cu") (net 287))
  (segment (start 94.316677 101.24635) (end 94.334507 101.274727) (width 0.15) (layer "In2.Cu") (net 287))
  (segment (start 93.097678 98.447455) (end 93.090424 98.462519) (width 0.15) (layer "In2.Cu") (net 287))
  (segment (start 94.316677 100.04635) (end 94.334507 100.074727) (width 0.15) (layer "In2.Cu") (net 287))
  (segment (start 94.292978 100.257348) (end 94.264601 100.275178) (width 0.15) (layer "In2.Cu") (net 287))
  (segment (start 93.186541 98.687721) (end 93.199612 98.698145) (width 0.15) (layer "In2.Cu") (net 287))
  (segment (start 94.017274 102.446476) (end 94.035145 102.474917) (width 0.15) (layer "In2.Cu") (net 287))
  (segment (start 94.349328 101.939664) (end 94.349328 101.940336) (width 0.15) (layer "In2.Cu") (net 287))
  (segment (start 93.556821 98.423508) (end 93.583082 98.402564) (width 0.15) (layer "In2.Cu") (net 287))
  (segment (start 94.199664 102.09) (end 93.750672 102.09) (width 0.15) (layer "In2.Cu") (net 287))
  (segment (start 93.933378 99.686239) (end 93.9 99.69) (width 0.15) (layer "In2.Cu") (net 287))
  (segment (start 93.604432 101.606621) (end 93.600672 101.64) (width 0.15) (layer "In2.Cu") (net 287))
  (segment (start 94.345576 101.973639) (end 94.334507 102.005272) (width 0.15) (layer "In2.Cu") (net 287))
  (segment (start 94.292978 101.457348) (end 94.264601 101.475178) (width 0.15) (layer "In2.Cu") (net 287))
  (segment (start 93.657148 100.557274) (end 93.685589 100.575145) (width 0.15) (layer "In2.Cu") (net 287))
  (segment (start 93.199612 98.698145) (end 93.214676 98.705399) (width 0.15) (layer "In2.Cu") (net 287))
  (segment (start 94.334507 100.074727) (end 94.345576 100.10636) (width 0.15) (layer "In2.Cu") (net 287))
  (segment (start 93.80915 99.101797) (end 93.822221 99.112222) (width 0.15) (layer "In2.Cu") (net 287))
  (segment (start 93.657148 99.957274) (end 93.685589 99.975145) (width 0.15) (layer "In2.Cu") (net 287))
  (segment (start 93.08 98.58118) (end 93.186541 98.687721) (width 0.15) (layer "In2.Cu") (net 287))
  (segment (start 93.811942 98.512778) (end 93.811941 98.546366) (width 0.15) (layer "In2.Cu") (net 287))
  (segment (start 94.292978 101.822651) (end 94.316677 101.84635) (width 0.15) (layer "In2.Cu") (net 287))
  (segment (start 93.777786 99.090822) (end 93.794086 99.094543) (width 0.15) (layer "In2.Cu") (net 287))
  (segment (start 93.345164 98.635164) (end 93.556821 98.423508) (width 0.15) (layer "In2.Cu") (net 287))
  (segment (start 93.27906 98.698145) (end 93.292132 98.687721) (width 0.15) (layer "In2.Cu") (net 287))
  (segment (start 93.717293 100.29376) (end 93.685589 100.304854) (width 0.15) (layer "In2.Cu") (net 287))
  (segment (start 93.761066 99.090822) (end 93.777786 99.090822) (width 0.15) (layer "In2.Cu") (net 287))
  (segment (start 93.48682 98.928225) (end 93.4831 98.944526) (width 0.15) (layer "In2.Cu") (net 287))
  (segment (start 93.717293 100.586239) (end 93.750672 100.59) (width 0.15) (layer "In2.Cu") (net 287))
  (segment (start 93.633397 101.546476) (end 93.615526 101.574917) (width 0.15) (layer "In2.Cu") (net 287))
  (segment (start 94.264601 100.604821) (end 94.292978 100.622651) (width 0.15) (layer "In2.Cu") (net 287))
  (segment (start 93.685589 100.904854) (end 93.657148 100.922725) (width 0.15) (layer "In2.Cu") (net 287))
  (segment (start 93.062321 98.553045) (end 93.069575 98.568109) (width 0.15) (layer "In2.Cu") (net 287))
  (segment (start 94.316677 100.233649) (end 94.292978 100.257348) (width 0.15) (layer "In2.Cu") (net 287))
  (segment (start 94.292978 101.222651) (end 94.316677 101.24635) (width 0.15) (layer "In2.Cu") (net 287))
  (segment (start 93.685589 99.704854) (end 93.657148 99.722725) (width 0.15) (layer "In2.Cu") (net 287))
  (segment (start 93.494075 98.913162) (end 93.48682 98.928225) (width 0.15) (layer "In2.Cu") (net 287))
  (segment (start 94.035145 99.605082) (end 94.017274 99.633523) (width 0.15) (layer "In2.Cu") (net 287))
  (segment (start 93.633397 102.333523) (end 93.657148 102.357274) (width 0.15) (layer "In2.Cu") (net 287))
  (segment (start 93.646092 98.380516) (end 93.67968 98.380515) (width 0.15) (layer "In2.Cu") (net 287))
  (segment (start 93.214676 98.705399) (end 93.230976 98.70912) (width 0.15) (layer "In2.Cu") (net 287))
  (segment (start 93.712428 98.38799) (end 93.74269 98.402563) (width 0.15) (layer "In2.Cu") (net 287))
  (segment (start 93.685589 101.504854) (end 93.657148 101.522725) (width 0.15) (layer "In2.Cu") (net 287))
  (segment (start 94.349328 101.340336) (end 94.345576 101.373639) (width 0.15) (layer "In2.Cu") (net 287))
  (segment (start 93.494075 98.992609) (end 93.504499 99.005681) (width 0.15) (layer "In2.Cu") (net 287))
  (segment (start 94.05 111.8) (end 96.4 114.15) (width 0.15) (layer "In2.Cu") (net 287))
  (segment (start 93.615526 99.905082) (end 93.633397 99.933523) (width 0.15) (layer "In2.Cu") (net 287))
  (segment (start 93.600672 99.84) (end 93.604432 99.873378) (width 0.15) (layer "In2.Cu") (net 287))
  (segment (start 94.349328 100.739664) (end 94.349328 100.740336) (width 0.15) (layer "In2.Cu") (net 287))
  (segment (start 94.264601 101.475178) (end 94.232968 101.486247) (width 0.15) (layer "In2.Cu") (net 287))
  (segment (start 93.965082 99.675145) (end 93.933378 99.686239) (width 0.15) (layer "In2.Cu") (net 287))
  (segment (start 93.685589 101.775145) (end 93.717293 101.786239) (width 0.15) (layer "In2.Cu") (net 287))
  (segment (start 93.657148 101.522725) (end 93.633397 101.546476) (width 0.15) (layer "In2.Cu") (net 287))
  (segment (start 93.750672 100.59) (end 94.199664 100.59) (width 0.15) (layer "In2.Cu") (net 287))
  (segment (start 94.046239 102.506621) (end 94.05 102.54) (width 0.15) (layer "In2.Cu") (net 287))
  (segment (start 93.789893 98.609376) (end 93.768951 98.635638) (width 0.15) (layer "In2.Cu") (net 287))
  (segment (start 94.264601 101.204821) (end 94.292978 101.222651) (width 0.15) (layer "In2.Cu") (net 287))
  (segment (start 94.345576 100.10636) (end 94.349328 100.139664) (width 0.15) (layer "In2.Cu") (net 287))
  (segment (start 93.583082 98.402564) (end 93.613344 98.387989) (width 0.15) (layer "In2.Cu") (net 287))
  (segment (start 94.334507 100.805272) (end 94.316677 100.833649) (width 0.15) (layer "In2.Cu") (net 287))
  (segment (start 93.685589 102.104854) (end 93.657148 102.122725) (width 0.15) (layer "In2.Cu") (net 287))
  (segment (start 93.993523 99.657274) (end 93.965082 99.675145) (width 0.15) (layer "In2.Cu") (net 287))
  (segment (start 93.685589 100.304854) (end 93.657148 100.322725) (width 0.15) (layer "In2.Cu") (net 287))
  (segment (start 93.750672 101.49) (end 93.717293 101.49376) (width 0.15) (layer "In2.Cu") (net 287))
  (segment (start 93.61104 99.112222) (end 93.624111 99.122646) (width 0.15) (layer "In2.Cu") (net 287))
  (segment (start 93.48682 98.977545) (end 93.494075 98.992609) (width 0.15) (layer "In2.Cu") (net 287))
  (segment (start 93.657148 101.757274) (end 93.685589 101.775145) (width 0.15) (layer "In2.Cu") (net 287))
  (segment (start 93.965082 102.404854) (end 93.993523 102.422725) (width 0.15) (layer "In2.Cu") (net 287))
  (segment (start 93.729702 99.101797) (end 93.744766 99.094543) (width 0.15) (layer "In2.Cu") (net 287))
  (segment (start 93.685589 102.375145) (end 93.717293 102.386239) (width 0.15) (layer "In2.Cu") (net 287))
  (segment (start 93.9 99.69) (end 93.750672 99.69) (width 0.15) (layer "In2.Cu") (net 287))
  (segment (start 94.264601 100.275178) (end 94.232968 100.286247) (width 0.15) (layer "In2.Cu") (net 287))
  (segment (start 94.345576 101.373639) (end 94.334507 101.405272) (width 0.15) (layer "In2.Cu") (net 287))
  (segment (start 93.655475 99.133621) (end 93.672195 99.133621) (width 0.15) (layer "In2.Cu") (net 287))
  (segment (start 93.750672 100.29) (end 93.717293 100.29376) (width 0.15) (layer "In2.Cu") (net 287))
  (segment (start 94.334507 102.005272) (end 94.316677 102.033649) (width 0.15) (layer "In2.Cu") (net 287))
  (segment (start 94.232968 101.793752) (end 94.264601 101.804821) (width 0.15) (layer "In2.Cu") (net 287))
  (segment (start 94.232968 100.286247) (end 94.199664 100.29) (width 0.15) (layer "In2.Cu") (net 287))
  (segment (start 93.247696 98.70912) (end 93.263996 98.705399) (width 0.15) (layer "In2.Cu") (net 287))
  (segment (start 93.933378 102.39376) (end 93.965082 102.404854) (width 0.15) (layer "In2.Cu") (net 287))
  (segment (start 93.090424 98.383071) (end 93.097678 98.398135) (width 0.15) (layer "In2.Cu") (net 287))
  (segment (start 94.199664 99.99) (end 94.232968 99.993752) (width 0.15) (layer "In2.Cu") (net 287))
  (segment (start 93.292132 98.687721) (end 93.344927 98.634925) (width 0.15) (layer "In2.Cu") (net 287))
  (segment (start 93.717293 101.186239) (end 93.750672 101.19) (width 0.15) (layer "In2.Cu") (net 287))
  (segment (start 93.750672 102.39) (end 93.9 102.39) (width 0.15) (layer "In2.Cu") (net 287))
  (segment (start 93.750672 102.09) (end 93.717293 102.09376) (width 0.15) (layer "In2.Cu") (net 287))
  (segment (start 94.334507 101.874727) (end 94.345576 101.90636) (width 0.15) (layer "In2.Cu") (net 287))
  (segment (start 93.672195 99.133621) (end 93.688495 99.1299) (width 0.15) (layer "In2.Cu") (net 287))
  (segment (start 93.604432 102.273378) (end 93.615526 102.305082) (width 0.15) (layer "In2.Cu") (net 287))
  (segment (start 93.615526 101.574917) (end 93.604432 101.606621) (width 0.15) (layer "In2.Cu") (net 287))
  (segment (start 93.685589 99.975145) (end 93.717293 99.986239) (width 0.15) (layer "In2.Cu") (net 287))
  (segment (start 93.600672 100.44) (end 93.604432 100.473378) (width 0.15) (layer "In2.Cu") (net 287))
  (segment (start 93.615526 101.705082) (end 93.633397 101.733523) (width 0.15) (layer "In2.Cu") (net 287))
  (segment (start 94.292978 100.622651) (end 94.316677 100.64635) (width 0.15) (layer "In2.Cu") (net 287))
  (segment (start 93.657148 101.157274) (end 93.685589 101.175145) (width 0.15) (layer "In2.Cu") (net 287))
  (segment (start 93.811941 98.546366) (end 93.804468 98.579114) (width 0.15) (layer "In2.Cu") (net 287))
  (segment (start 93.633397 100.946476) (end 93.615526 100.974917) (width 0.15) (layer "In2.Cu") (net 287))
  (segment (start 94.349328 100.740336) (end 94.345576 100.773639) (width 0.15) (layer "In2.Cu") (net 287))
  (segment (start 93.750672 99.99) (end 94.199664 99.99) (width 0.15) (layer "In2.Cu") (net 287))
  (segment (start 94.264601 101.804821) (end 94.292978 101.822651) (width 0.15) (layer "In2.Cu") (net 287))
  (segment (start 93.717293 100.89376) (end 93.685589 100.904854) (width 0.15) (layer "In2.Cu") (net 287))
  (segment (start 93.4831 98.944526) (end 93.4831 98.961245) (width 0.15) (layer "In2.Cu") (net 287))
  (segment (start 94.316677 102.033649) (end 94.292978 102.057348) (width 0.15) (layer "In2.Cu") (net 287))
  (segment (start 93.633397 99.746476) (end 93.615526 99.774917) (width 0.15) (layer "In2.Cu") (net 287))
  (segment (start 93.639175 99.1299) (end 93.655475 99.133621) (width 0.15) (layer "In2.Cu") (net 287))
  (segment (start 93.717293 99.986239) (end 93.750672 99.99) (width 0.15) (layer "In2.Cu") (net 287))
  (segment (start 94.035145 102.474917) (end 94.046239 102.506621) (width 0.15) (layer "In2.Cu") (net 287))
  (segment (start 94.345576 101.30636) (end 94.349328 101.339664) (width 0.15) (layer "In2.Cu") (net 287))
  (segment (start 93.633397 100.533523) (end 93.657148 100.557274) (width 0.15) (layer "In2.Cu") (net 287))
  (segment (start 94.292978 102.057348) (end 94.264601 102.075178) (width 0.15) (layer "In2.Cu") (net 287))
  (segment (start 92.79 98.08) (end 93.08 98.37) (width 0.15) (layer "In2.Cu") (net 287))
  (segment (start 94.232968 100.593752) (end 94.264601 100.604821) (width 0.15) (layer "In2.Cu") (net 287))
  (segment (start 93.615526 100.374917) (end 93.604432 100.406621) (width 0.15) (layer "In2.Cu") (net 287))
  (segment (start 93.604432 99.873378) (end 93.615526 99.905082) (width 0.15) (layer "In2.Cu") (net 287))
  (segment (start 93.101399 98.414435) (end 93.101399 98.431155) (width 0.15) (layer "In2.Cu") (net 287))
  (segment (start 93.9 102.39) (end 93.933378 102.39376) (width 0.15) (layer "In2.Cu") (net 287))
  (segment (start 94.345576 100.173639) (end 94.334507 100.205272) (width 0.15) (layer "In2.Cu") (net 287))
  (segment (start 94.232968 102.086247) (end 94.199664 102.09) (width 0.15) (layer "In2.Cu") (net 287))
  (segment (start 93.685589 100.575145) (end 93.717293 100.586239) (width 0.15) (layer "In2.Cu") (net 287))
  (segment (start 93.744766 99.094543) (end 93.761066 99.090822) (width 0.15) (layer "In2.Cu") (net 287))
  (segment (start 93.0586 98.520025) (end 93.0586 98.536745) (width 0.15) (layer "In2.Cu") (net 287))
  (segment (start 94.017274 99.633523) (end 93.993523 99.657274) (width 0.15) (layer "In2.Cu") (net 287))
  (segment (start 93.717293 99.69376) (end 93.685589 99.704854) (width 0.15) (layer "In2.Cu") (net 287))
  (segment (start 93.600672 101.04) (end 93.604432 101.073378) (width 0.15) (layer "In2.Cu") (net 287))
  (segment (start 93.74269 98.402563) (end 93.768951 98.423506) (width 0.15) (layer "In2.Cu") (net 287))
  (segment (start 94.264601 100.004821) (end 94.292978 100.022651) (width 0.15) (layer "In2.Cu") (net 287))
  (segment (start 94.05 99.34) (end 94.05 99.54) (width 0.15) (layer "In2.Cu") (net 287))
  (segment (start 94.199664 100.29) (end 93.750672 100.29) (width 0.15) (layer "In2.Cu") (net 287))
  (segment (start 94.334507 101.274727) (end 94.345576 101.30636) (width 0.15) (layer "In2.Cu") (net 287))
  (segment (start 93.101399 98.431155) (end 93.097678 98.447455) (width 0.15) (layer "In2.Cu") (net 287))
  (segment (start 93.685589 101.175145) (end 93.717293 101.186239) (width 0.15) (layer "In2.Cu") (net 287))
  (segment (start 93.615526 99.774917) (end 93.604432 99.806621) (width 0.15) (layer "In2.Cu") (net 287))
  (segment (start 94.334507 101.405272) (end 94.316677 101.433649) (width 0.15) (layer "In2.Cu") (net 287))
  (segment (start 94.199664 101.49) (end 93.750672 101.49) (width 0.15) (layer "In2.Cu") (net 287))
  (segment (start 94.264601 102.075178) (end 94.232968 102.086247) (width 0.15) (layer "In2.Cu") (net 287))
  (segment (start 94.199664 101.19) (end 94.232968 101.193752) (width 0.15) (layer "In2.Cu") (net 287))
  (segment (start 93.657148 100.922725) (end 93.633397 100.946476) (width 0.15) (layer "In2.Cu") (net 287))
  (segment (start 93.750672 100.89) (end 93.717293 100.89376) (width 0.15) (layer "In2.Cu") (net 287))
  (segment (start 93.688495 99.1299) (end 93.703559 99.122646) (width 0.15) (layer "In2.Cu") (net 287))
  (segment (start 93.615526 100.505082) (end 93.633397 100.533523) (width 0.15) (layer "In2.Cu") (net 287))
  (segment (start 93.657148 102.357274) (end 93.685589 102.375145) (width 0.15) (layer "In2.Cu") (net 287))
  (segment (start 93.604432 99.806621) (end 93.600672 99.84) (width 0.15) (layer "In2.Cu") (net 287))
  (segment (start 93.0586 98.536745) (end 93.062321 98.553045) (width 0.15) (layer "In2.Cu") (net 287))
  (segment (start 94.316677 100.64635) (end 94.334507 100.674727) (width 0.15) (layer "In2.Cu") (net 287))
  (segment (start 93.604432 100.406621) (end 93.600672 100.44) (width 0.15) (layer "In2.Cu") (net 287))
  (segment (start 93.604432 101.073378) (end 93.615526 101.105082) (width 0.15) (layer "In2.Cu") (net 287))
  (segment (start 94.349328 100.140336) (end 94.345576 100.173639) (width 0.15) (layer "In2.Cu") (net 287))
  (segment (start 93.717293 101.49376) (end 93.685589 101.504854) (width 0.15) (layer "In2.Cu") (net 287))
  (segment (start 94.232968 101.486247) (end 94.199664 101.49) (width 0.15) (layer "In2.Cu") (net 287))
  (segment (start 93.633397 100.346476) (end 93.615526 100.374917) (width 0.15) (layer "In2.Cu") (net 287))
  (segment (start 93.604432 101.006621) (end 93.600672 101.04) (width 0.15) (layer "In2.Cu") (net 287))
  (segment (start 93.344927 98.634925) (end 93.345164 98.635164) (width 0.15) (layer "In2.Cu") (net 287))
  (segment (start 93.750672 101.79) (end 94.199664 101.79) (width 0.15) (layer "In2.Cu") (net 287))
  (segment (start 94.316677 101.433649) (end 94.292978 101.457348) (width 0.15) (layer "In2.Cu") (net 287))
  (segment (start 94.334507 100.205272) (end 94.316677 100.233649) (width 0.15) (layer "In2.Cu") (net 287))
  (segment (start 93.993523 102.422725) (end 94.017274 102.446476) (width 0.15) (layer "In2.Cu") (net 287))
  (segment (start 93.804467 98.48003) (end 93.811942 98.512778) (width 0.15) (layer "In2.Cu") (net 287))
  (segment (start 94.292978 100.857348) (end 94.264601 100.875178) (width 0.15) (layer "In2.Cu") (net 287))
  (segment (start 93.069575 98.488661) (end 93.062321 98.503725) (width 0.15) (layer "In2.Cu") (net 287))
  (segment (start 93.08 98.37) (end 93.090424 98.383071) (width 0.15) (layer "In2.Cu") (net 287))
  (segment (start 93.657148 99.722725) (end 93.633397 99.746476) (width 0.15) (layer "In2.Cu") (net 287))
  (segment (start 93.615526 100.974917) (end 93.604432 101.006621) (width 0.15) (layer "In2.Cu") (net 287))
  (segment (start 93.604432 101.673378) (end 93.615526 101.705082) (width 0.15) (layer "In2.Cu") (net 287))
  (segment (start 94.349328 101.339664) (end 94.349328 101.340336) (width 0.15) (layer "In2.Cu") (net 287))
  (segment (start 94.232968 101.193752) (end 94.264601 101.204821) (width 0.15) (layer "In2.Cu") (net 287))
  (segment (start 93.230976 98.70912) (end 93.247696 98.70912) (width 0.15) (layer "In2.Cu") (net 287))
  (segment (start 93.717293 101.786239) (end 93.750672 101.79) (width 0.15) (layer "In2.Cu") (net 287))
  (segment (start 93.600672 102.24) (end 93.604432 102.273378) (width 0.15) (layer "In2.Cu") (net 287))
  (segment (start 94.316677 101.84635) (end 94.334507 101.874727) (width 0.15) (layer "In2.Cu") (net 287))
  (segment (start 93.794086 99.094543) (end 93.80915 99.101797) (width 0.15) (layer "In2.Cu") (net 287))
  (segment (start 94.046239 99.573378) (end 94.035145 99.605082) (width 0.15) (layer "In2.Cu") (net 287))
  (segment (start 94.232968 99.993752) (end 94.264601 100.004821) (width 0.15) (layer "In2.Cu") (net 287))
  (segment (start 93.822221 99.112222) (end 94.05 99.34) (width 0.15) (layer "In2.Cu") (net 287))
  (segment (start 93.750672 101.19) (end 94.199664 101.19) (width 0.15) (layer "In2.Cu") (net 287))
  (segment (start 93.600672 101.64) (end 93.604432 101.673378) (width 0.15) (layer "In2.Cu") (net 287))
  (segment (start 93.615526 102.174917) (end 93.604432 102.206621) (width 0.15) (layer "In2.Cu") (net 287))
  (segment (start 94.316677 100.833649) (end 94.292978 100.857348) (width 0.15) (layer "In2.Cu") (net 287))
  (segment (start 93.67968 98.380515) (end 93.712428 98.38799) (width 0.15) (layer "In2.Cu") (net 287))
  (segment (start 94.05 102.54) (end 94.05 111.8) (width 0.15) (layer "In2.Cu") (net 287))
  (segment (start 94.345576 100.773639) (end 94.334507 100.805272) (width 0.15) (layer "In2.Cu") (net 287))
  (segment (start 94.264601 100.875178) (end 94.232968 100.886247) (width 0.15) (layer "In2.Cu") (net 287))
  (segment (start 93.097678 98.398135) (end 93.101399 98.414435) (width 0.15) (layer "In2.Cu") (net 287))
  (segment (start 93.768951 98.423506) (end 93.789894 98.449768) (width 0.15) (layer "In2.Cu") (net 287))
  (segment (start 94.199664 101.79) (end 94.232968 101.793752) (width 0.15) (layer "In2.Cu") (net 287))
  (segment (start 93.750672 99.69) (end 93.717293 99.69376) (width 0.15) (layer "In2.Cu") (net 287))
  (segment (start 93.633397 101.733523) (end 93.657148 101.757274) (width 0.15) (layer "In2.Cu") (net 287))
  (segment (start 93.062321 98.503725) (end 93.0586 98.520025) (width 0.15) (layer "In2.Cu") (net 287))
  (segment (start 94.05 99.54) (end 94.046239 99.573378) (width 0.15) (layer "In2.Cu") (net 287))
  (segment (start 93.657148 102.122725) (end 93.633397 102.146476) (width 0.15) (layer "In2.Cu") (net 287))
  (segment (start 93.263996 98.705399) (end 93.27906 98.698145) (width 0.15) (layer "In2.Cu") (net 287))
  (segment (start 94.199664 100.59) (end 94.232968 100.593752) (width 0.15) (layer "In2.Cu") (net 287))
  (segment (start 93.615526 102.305082) (end 93.633397 102.333523) (width 0.15) (layer "In2.Cu") (net 287))
  (segment (start 93.624111 99.122646) (end 93.639175 99.1299) (width 0.15) (layer "In2.Cu") (net 287))
  (segment (start 93.4831 98.961245) (end 93.48682 98.977545) (width 0.15) (layer "In2.Cu") (net 287))
  (segment (start 93.633397 99.933523) (end 93.657148 99.957274) (width 0.15) (layer "In2.Cu") (net 287))
  (segment (start 94.345576 100.70636) (end 94.349328 100.739664) (width 0.15) (layer "In2.Cu") (net 287))
  (segment (start 93.804468 98.579114) (end 93.789893 98.609376) (width 0.15) (layer "In2.Cu") (net 287))
  (segment (start 94.199664 100.89) (end 93.750672 100.89) (width 0.15) (layer "In2.Cu") (net 287))
  (segment (start 92.835 98.125) (end 92.79 98.08) (width 0.15) (layer "B.Cu") (net 287))
  (segment (start 94.065 98.125) (end 92.835 98.125) (width 0.15) (layer "B.Cu") (net 287))
  (segment (start 96.4 117.35) (end 96.41785 117.33215) (width 0.1) (layer "F.Cu") (net 288))
  (segment (start 96 118.55) (end 96.4 118.15) (width 0.1) (layer "F.Cu") (net 288))
  (segment (start 96.4 118.15) (end 96.4 117.35) (width 0.1) (layer "F.Cu") (net 288))
  (via (at 95.8 97.1) (size 0.5) (drill 0.2) (layers "F.Cu" "B.Cu") (net 288))
  (via (at 96.41785 117.33215) (size 0.5) (drill 0.2) (layers "F.Cu" "B.Cu") (net 288))
  (segment (start 97.5 116.25) (end 97.5 113.45) (width 0.15) (layer "In2.Cu") (net 288))
  (segment (start 95.8 97.1) (end 96.25 97.55) (width 0.15) (layer "In2.Cu") (net 288))
  (segment (start 96.41785 117.33215) (end 97.5 116.25) (width 0.15) (layer "In2.Cu") (net 288))
  (segment (start 97.5 113.45) (end 96.25 112.2) (width 0.15) (layer "In2.Cu") (net 288))
  (segment (start 96.25 112.2) (end 96.25 97.55) (width 0.15) (layer "In2.Cu") (net 288))
  (segment (start 95.8 97.1) (end 95.05 97.1) (width 0.15) (layer "B.Cu") (net 288))
  (segment (start 93.22 71.73) (end 93.2 71.75) (width 0.25) (layer "F.Cu") (net 289))
  (segment (start 93.22 70.45) (end 93.22 71.73) (width 0.25) (layer "F.Cu") (net 289))
  (segment (start 92.315 77.9) (end 91.35 77.9) (width 0.2) (layer "F.Cu") (net 289))
  (segment (start 93.265 76.85) (end 92.775 76.85) (width 0.2) (layer "F.Cu") (net 289))
  (segment (start 92.285 76.85) (end 92.285 78.835) (width 0.2) (layer "F.Cu") (net 289))
  (segment (start 92.75 76.2) (end 92.75 76.825) (width 0.15) (layer "F.Cu") (net 289))
  (segment (start 92.75 76.825) (end 92.775 76.85) (width 0.15) (layer "F.Cu") (net 289))
  (segment (start 92.775 76.85) (end 92.3 76.85) (width 0.2) (layer "F.Cu") (net 289))
  (via (at 93.2 71.75) (size 0.5) (drill 0.2) (layers "F.Cu" "B.Cu") (net 289))
  (via (at 92.75 76.2) (size 0.5) (drill 0.2) (layers "F.Cu" "B.Cu") (net 289))
  (segment (start 93.2 75.75) (end 92.75 76.2) (width 0.2) (layer "B.Cu") (net 289))
  (segment (start 93.2 71.75) (end 93.2 75.75) (width 0.2) (layer "B.Cu") (net 289))
  (segment (start 73.965 61.2) (end 73.3 61.2) (width 0.25) (layer "F.Cu") (net 290))
  (segment (start 79.85 69.65) (end 79.8 69.6) (width 0.15) (layer "F.Cu") (net 290))
  (segment (start 80.85 69.65) (end 79.85 69.65) (width 0.15) (layer "F.Cu") (net 290))
  (via (at 80.85 69.65) (size 0.5) (drill 0.2) (layers "F.Cu" "B.Cu") (net 290))
  (via (at 73.3 61.2) (size 0.5) (drill 0.2) (layers "F.Cu" "B.Cu") (net 290))
  (segment (start 81.75 68.75) (end 81.75 66.25) (width 0.2) (layer "B.Cu") (net 290))
  (segment (start 77.35 61.2) (end 73.3 61.2) (width 0.2) (layer "B.Cu") (net 290))
  (segment (start 80.85 64.7) (end 77.35 61.2) (width 0.2) (layer "B.Cu") (net 290))
  (segment (start 80.85 69.65) (end 81.75 68.75) (width 0.2) (layer "B.Cu") (net 290))
  (segment (start 81.75 66.25) (end 80.85 65.35) (width 0.2) (layer "B.Cu") (net 290))
  (segment (start 80.85 65.35) (end 80.85 64.7) (width 0.2) (layer "B.Cu") (net 290))
  (segment (start 82.85 87.35) (end 82.85 86.8) (width 0.25) (layer "F.Cu") (net 291))
  (segment (start 84.215 88.55) (end 84.215 89.75) (width 0.25) (layer "F.Cu") (net 291))
  (segment (start 82.2 88) (end 82.85 87.35) (width 0.25) (layer "F.Cu") (net 291))
  (segment (start 84.215 89.75) (end 82.8 89.75) (width 0.25) (layer "F.Cu") (net 291))
  (segment (start 82.8 89.75) (end 82.2 89.15) (width 0.25) (layer "F.Cu") (net 291))
  (segment (start 82.2 89.15) (end 82.2 88) (width 0.25) (layer "F.Cu") (net 291))
  (segment (start 117.689056 87.243104) (end 117.089056 86.643104) (width 0.25) (layer "F.Cu") (net 292))
  (segment (start 117.089056 85.493104) (end 117.739056 84.843104) (width 0.25) (layer "F.Cu") (net 292))
  (segment (start 119.104056 87.243104) (end 117.689056 87.243104) (width 0.25) (layer "F.Cu") (net 292))
  (segment (start 117.739056 84.843104) (end 117.739056 84.293104) (width 0.25) (layer "F.Cu") (net 292))
  (segment (start 117.089056 86.643104) (end 117.089056 85.493104) (width 0.25) (layer "F.Cu") (net 292))
  (segment (start 119.104056 86.043104) (end 119.104056 87.243104) (width 0.25) (layer "F.Cu") (net 292))
  (segment (start 110.480278 105.9) (end 119.1668 105.9) (width 0.1) (layer "F.Cu") (net 293))
  (segment (start 109.780278 106.6) (end 110.480278 105.9) (width 0.1) (layer "F.Cu") (net 293))
  (segment (start 125.331082 99.735718) (end 125.331083 77.306083) (width 0.1) (layer "F.Cu") (net 293))
  (segment (start 119.1668 105.9) (end 125.331082 99.735718) (width 0.1) (layer "F.Cu") (net 293))
  (segment (start 119.15 75.15) (end 118.15 74.15) (width 0.1) (layer "F.Cu") (net 293))
  (segment (start 108.049978 106.6) (end 109.780278 106.6) (width 0.1) (layer "F.Cu") (net 293))
  (segment (start 125.331083 77.306083) (end 123.175 75.15) (width 0.1) (layer "F.Cu") (net 293))
  (segment (start 106.4 108.95) (end 106.8 108.55) (width 0.1) (layer "F.Cu") (net 293))
  (segment (start 118.15 67.65) (end 118.3 67.5) (width 0.1) (layer "F.Cu") (net 293))
  (segment (start 106.8 107.849978) (end 108.049978 106.6) (width 0.1) (layer "F.Cu") (net 293))
  (segment (start 118.3 67.5) (end 119.225 67.5) (width 0.1) (layer "F.Cu") (net 293))
  (segment (start 106.8 108.55) (end 106.8 107.849978) (width 0.1) (layer "F.Cu") (net 293))
  (segment (start 118.15 74.15) (end 118.15 67.65) (width 0.1) (layer "F.Cu") (net 293))
  (segment (start 123.175 75.15) (end 119.15 75.15) (width 0.1) (layer "F.Cu") (net 293))
  (segment (start 110.072858 106.86) (end 110.782858 106.15) (width 0.1) (layer "F.Cu") (net 294))
  (segment (start 108.8 109.75) (end 108.4 109.35) (width 0.1) (layer "F.Cu") (net 294))
  (segment (start 120.275 71.7) (end 120.075 71.5) (width 0.1) (layer "F.Cu") (net 294))
  (segment (start 123.275 74.925) (end 120.6 74.925) (width 0.1) (layer "F.Cu") (net 294))
  (segment (start 108.97 106.86) (end 110.072858 106.86) (width 0.1) (layer "F.Cu") (net 294))
  (segment (start 119.270356 106.15) (end 125.531093 99.889263) (width 0.1) (layer "F.Cu") (net 294))
  (segment (start 110.782858 106.15) (end 119.270356 106.15) (width 0.1) (layer "F.Cu") (net 294))
  (segment (start 125.531093 99.889263) (end 125.531093 77.181093) (width 0.1) (layer "F.Cu") (net 294))
  (segment (start 120.6 74.925) (end 120.275 74.6) (width 0.1) (layer "F.Cu") (net 294))
  (segment (start 120.075 71.5) (end 119.25 71.5) (width 0.1) (layer "F.Cu") (net 294))
  (segment (start 120.275 74.6) (end 120.275 71.7) (width 0.1) (layer "F.Cu") (net 294))
  (segment (start 108.4 109.35) (end 108.4 107.43) (width 0.1) (layer "F.Cu") (net 294))
  (segment (start 108.4 107.43) (end 108.97 106.86) (width 0.1) (layer "F.Cu") (net 294))
  (segment (start 125.531093 77.181093) (end 123.275 74.925) (width 0.1) (layer "F.Cu") (net 294))
  (segment (start 110.832842 106.4) (end 119.373912 106.4) (width 0.1) (layer "F.Cu") (net 295))
  (segment (start 119.373912 106.4) (end 125.731104 100.042808) (width 0.1) (layer "F.Cu") (net 295))
  (segment (start 125.731104 100.042808) (end 125.731104 77.056104) (width 0.1) (layer "F.Cu") (net 295))
  (segment (start 109.082842 108.15) (end 110.832842 106.4) (width 0.1) (layer "F.Cu") (net 295))
  (segment (start 122.575 74.675) (end 122.225 74.325) (width 0.1) (layer "F.Cu") (net 295))
  (segment (start 123.35 74.675) (end 122.575 74.675) (width 0.1) (layer "F.Cu") (net 295))
  (segment (start 108.8 108.15) (end 109.082842 108.15) (width 0.1) (layer "F.Cu") (net 295))
  (segment (start 122.225 74.325) (end 122.225 71.6) (width 0.1) (layer "F.Cu") (net 295))
  (segment (start 122.225 71.6) (end 122.325 71.5) (width 0.1) (layer "F.Cu") (net 295))
  (segment (start 122.325 71.5) (end 123.15 71.5) (width 0.1) (layer "F.Cu") (net 295))
  (segment (start 125.731104 77.056104) (end 123.35 74.675) (width 0.1) (layer "F.Cu") (net 295))
  (segment (start 100.45 99.877149) (end 100.45 101.165) (width 0.15) (layer "F.Cu") (net 296))
  (segment (start 103.2 110.55) (end 102.8 110.15) (width 0.15) (layer "F.Cu") (net 296))
  (segment (start 100.45 101.165) (end 100.455 101.17) (width 0.15) (layer "F.Cu") (net 296))
  (via (at 100.455 101.17) (size 0.5) (drill 0.2) (layers "F.Cu" "B.Cu") (net 296))
  (via (at 102.8 110.15) (size 0.5) (drill 0.2) (layers "F.Cu" "B.Cu") (net 296))
  (segment (start 100.455 107.805) (end 100.455 101.17) (width 0.15) (layer "B.Cu") (net 296))
  (segment (start 102.8 110.15) (end 100.455 107.805) (width 0.15) (layer "B.Cu") (net 296))
  (segment (start 137.525 75.905) (end 137.525 74.6) (width 0.15) (layer "F.Cu") (net 297))
  (segment (start 137.03 75.91) (end 137.03 74.57) (width 0.15) (layer "F.Cu") (net 298))
  (segment (start 78.265 88.55) (end 78.265 89.75) (width 0.25) (layer "F.Cu") (net 299))
  (segment (start 76.9 87.55) (end 76.9 86.8) (width 0.25) (layer "F.Cu") (net 299))
  (segment (start 78.265 89.75) (end 76.85 89.75) (width 0.25) (layer "F.Cu") (net 299))
  (segment (start 76.25 89.15) (end 76.25 88.2) (width 0.25) (layer "F.Cu") (net 299))
  (segment (start 76.25 88.2) (end 76.9 87.55) (width 0.25) (layer "F.Cu") (net 299))
  (segment (start 76.85 89.75) (end 76.25 89.15) (width 0.25) (layer "F.Cu") (net 299))
  (segment (start 72.165 89.75) (end 70.75 89.75) (width 0.25) (layer "F.Cu") (net 300))
  (segment (start 70.15 88) (end 70.8 87.35) (width 0.25) (layer "F.Cu") (net 300))
  (segment (start 72.165 88.55) (end 72.165 89.75) (width 0.25) (layer "F.Cu") (net 300))
  (segment (start 70.75 89.75) (end 70.15 89.15) (width 0.25) (layer "F.Cu") (net 300))
  (segment (start 70.15 89.15) (end 70.15 88) (width 0.25) (layer "F.Cu") (net 300))
  (segment (start 70.8 87.35) (end 70.8 86.8) (width 0.25) (layer "F.Cu") (net 300))
  (segment (start 88.2 88) (end 88.85 87.35) (width 0.25) (layer "F.Cu") (net 301))
  (segment (start 88.85 87.35) (end 88.85 86.8) (width 0.25) (layer "F.Cu") (net 301))
  (segment (start 90.215 89.75) (end 88.8 89.75) (width 0.25) (layer "F.Cu") (net 301))
  (segment (start 88.2 89.15) (end 88.2 88) (width 0.25) (layer "F.Cu") (net 301))
  (segment (start 90.215 88.55) (end 90.215 89.75) (width 0.25) (layer "F.Cu") (net 301))
  (segment (start 88.8 89.75) (end 88.2 89.15) (width 0.25) (layer "F.Cu") (net 301))
  (segment (start 98.4 130.55) (end 98 130.95) (width 0.15) (layer "F.Cu") (net 302))
  (segment (start 98.085 129.265) (end 97.92 129.265) (width 0.15) (layer "F.Cu") (net 302))
  (segment (start 100.8 130.55) (end 101.2 130.95) (width 0.15) (layer "F.Cu") (net 302))
  (segment (start 100.8 128.95) (end 101.2 129.35) (width 0.15) (layer "F.Cu") (net 302))
  (segment (start 98.4 128.95) (end 98.085 129.265) (width 0.15) (layer "F.Cu") (net 302))
  (segment (start 98.4 129.75) (end 98 130.15) (width 0.15) (layer "F.Cu") (net 302))
  (segment (start 105.6 125.75) (end 106 126.15) (width 0.15) (layer "F.Cu") (net 302))
  (segment (start 102.4 125.75) (end 102 126.15) (width 0.15) (layer "F.Cu") (net 302))
  (segment (start 101.6 130.55) (end 102 130.95) (width 0.15) (layer "F.Cu") (net 302))
  (segment (start 100.8 129.77) (end 101.2 130.17) (width 0.15) (layer "F.Cu") (net 302))
  (segment (start 99.2 130.55) (end 98.8 130.95) (width 0.15) (layer "F.Cu") (net 302))
  (via (at 98 130.95) (size 0.5) (drill 0.2) (layers "F.Cu" "B.Cu") (net 302))
  (via (at 97.92 129.265) (size 0.5) (drill 0.2) (layers "F.Cu" "B.Cu") (net 302))
  (via (at 101.2 129.35) (size 0.5) (drill 0.2) (layers "F.Cu" "B.Cu") (net 302))
  (via (at 102 126.15) (size 0.5) (drill 0.2) (layers "F.Cu" "B.Cu") (net 302))
  (via (at 101.2 130.17) (size 0.5) (drill 0.2) (layers "F.Cu" "B.Cu") (net 302))
  (via (at 98 130.15) (size 0.5) (drill 0.2) (layers "F.Cu" "B.Cu") (net 302))
  (via (at 98.8 130.95) (size 0.5) (drill 0.2) (layers "F.Cu" "B.Cu") (net 302))
  (via (at 106 126.15) (size 0.5) (drill 0.2) (layers "F.Cu" "B.Cu") (net 302))
  (via (at 101.2 130.95) (size 0.5) (drill 0.2) (layers "F.Cu" "B.Cu") (net 302))
  (via (at 102 130.95) (size 0.5) (drill 0.2) (layers "F.Cu" "B.Cu") (net 302))
  (segment (start 98.515 129.635) (end 98 130.15) (width 0.25) (layer "B.Cu") (net 302))
  (segment (start 98 130.95) (end 97.35 130.95) (width 0.15) (layer "B.Cu") (net 302))
  (segment (start 101.95 131.765) (end 101.95 131) (width 0.15) (layer "B.Cu") (net 302))
  (segment (start 101.95 131) (end 102 130.95) (width 0.15) (layer "B.Cu") (net 302))
  (segment (start 102.55 126.7) (end 102 126.15) (width 0.15) (layer "B.Cu") (net 302))
  (segment (start 100.9 131.765) (end 99.735 131.765) (width 0.15) (layer "B.Cu") (net 302))
  (segment (start 98.8 130.3) (end 98.8 130) (width 0.3) (layer "B.Cu") (net 302))
  (segment (start 97.92 129.265) (end 97.92 129.07) (width 0.15) (layer "B.Cu") (net 302))
  (segment (start 97.75 128.9) (end 97.5 128.9) (width 0.15) (layer "B.Cu") (net 302))
  (segment (start 97.8 129.9) (end 97.35 129.9) (width 0.15) (layer "B.Cu") (net 302))
  (segment (start 98.76 129.635) (end 98.515 129.635) (width 0.25) (layer "B.Cu") (net 302))
  (segment (start 100.9 131.25) (end 100.9 131.765) (width 0.15) (layer "B.Cu") (net 302))
  (segment (start 106.55 126.7) (end 106 126.15) (width 0.15) (layer "B.Cu") (net 302))
  (segment (start 97.4 131.765) (end 98.385 131.765) (width 0.15) (layer "B.Cu") (net 302))
  (segment (start 99.4 131.7) (end 99.4 131.55) (width 0.3) (layer "B.Cu") (net 302))
  (segment (start 101.2 130.17) (end 101.82 130.17) (width 0.15) (layer "B.Cu") (net 302))
  (segment (start 99.4 131.55) (end 98.8 130.95) (width 0.3) (layer "B.Cu") (net 302))
  (segment (start 98.4 131.765) (end 98.4 131.35) (width 0.15) (layer "B.Cu") (net 302))
  (segment (start 101.2 129.35) (end 101.9 129.35) (width 0.15) (layer "B.Cu") (net 302))
  (segment (start 98 130.1) (end 97.8 129.9) (width 0.15) (layer "B.Cu") (net 302))
  (segment (start 97.92 129.07) (end 97.75 128.9) (width 0.15) (layer "B.Cu") (net 302))
  (segment (start 98.4 131.35) (end 98.8 130.95) (width 0.15) (layer "B.Cu") (net 302))
  (segment (start 101.2 130.95) (end 100.9 131.25) (width 0.15) (layer "B.Cu") (net 302))
  (segment (start 98 130.15) (end 98 130.1) (width 0.15) (layer "B.Cu") (net 302))
  (segment (start 98.8 130.95) (end 98.8 130.3) (width 0.3) (layer "B.Cu") (net 302))
  (segment (start 108 130.55) (end 107.6 130.95) (width 0.15) (layer "F.Cu") (net 303))
  (segment (start 108.8 129.75) (end 109.2 130.15) (width 0.15) (layer "F.Cu") (net 303))
  (segment (start 106.4 125.75) (end 106.8 126.15) (width 0.15) (layer "F.Cu") (net 303))
  (segment (start 103.2 125.75) (end 102.8 126.15) (width 0.15) (layer "F.Cu") (net 303))
  (segment (start 108.8 128.15) (end 108.4 128.55) (width 0.15) (layer "F.Cu") (net 303))
  (segment (start 106.4 129.75) (end 106 130.15) (width 0.15) (layer "F.Cu") (net 303))
  (segment (start 106.4 130.55) (end 106 130.95) (width 0.15) (layer "F.Cu") (net 303))
  (segment (start 108.8 128.95) (end 109.2 129.35) (width 0.15) (layer "F.Cu") (net 303))
  (segment (start 108.8 130.55) (end 109.2 130.95) (width 0.15) (layer "F.Cu") (net 303))
  (segment (start 105.6 130.55) (end 105.2 130.95) (width 0.15) (layer "F.Cu") (net 303))
  (segment (start 106.4 128.95) (end 106 129.35) (width 0.15) (layer "F.Cu") (net 303))
  (via (at 107.6 130.95) (size 0.5) (drill 0.2) (layers "F.Cu" "B.Cu") (net 303))
  (via (at 108.4 128.55) (size 0.5) (drill 0.2) (layers "F.Cu" "B.Cu") (net 303))
  (via (at 106 130.95) (size 0.5) (drill 0.2) (layers "F.Cu" "B.Cu") (net 303))
  (via (at 109.2 130.15) (size 0.5) (drill 0.2) (layers "F.Cu" "B.Cu") (net 303))
  (via (at 106 129.35) (size 0.5) (drill 0.2) (layers "F.Cu" "B.Cu") (net 303))
  (via (at 106.8 126.15) (size 0.5) (drill 0.2) (layers "F.Cu" "B.Cu") (net 303))
  (via (at 106 130.15) (size 0.5) (drill 0.2) (layers "F.Cu" "B.Cu") (net 303))
  (via (at 109.2 130.95) (size 0.5) (drill 0.2) (layers "F.Cu" "B.Cu") (net 303))
  (via (at 105.2 130.95) (size 0.5) (drill 0.2) (layers "F.Cu" "B.Cu") (net 303))
  (via (at 102.8 126.15) (size 0.5) (drill 0.2) (layers "F.Cu" "B.Cu") (net 303))
  (via (at 109.2 129.35) (size 0.5) (drill 0.2) (layers "F.Cu" "B.Cu") (net 303))
  (segment (start 105.9 130.15) (end 105.45 130.15) (width 0.15) (layer "B.Cu") (net 303))
  (segment (start 106 130.15) (end 105.9 130.15) (width 0.15) (layer "B.Cu") (net 303))
  (segment (start 107.15 131.4) (end 107.15 131.6) (width 0.15) (layer "B.Cu") (net 303))
  (segment (start 109.2 130.95) (end 109.2 131.6) (width 0.3) (layer "B.Cu") (net 303))
  (segment (start 107.95 131.7) (end 107.95 131.4) (width 0.15) (layer "B.Cu") (net 303))
  (segment (start 108.435 129.15) (end 109 129.15) (width 0.15) (layer "B.Cu") (net 303))
  (segment (start 103.55 126.9) (end 102.8 126.15) (width 0.15) (layer "B.Cu") (net 303))
  (segment (start 105.95 131) (end 106 130.95) (width 0.15) (layer "B.Cu") (net 303))
  (segment (start 105.95 131.765) (end 105.95 131) (width 0.15) (layer "B.Cu") (net 303))
  (segment (start 107.6 131.05) (end 107.6 130.95) (width 0.15) (layer "B.Cu") (net 303))
  (segment (start 107.55 126.9) (end 106.8 126.15) (width 0.15) (layer "B.Cu") (net 303))
  (segment (start 112.365 129.5) (end 112 129.5) (width 0.15) (layer "B.Cu") (net 303))
  (segment (start 112 129.5) (end 111.65 129.85) (width 0.15) (layer "B.Cu") (net 303))
  (segment (start 107.6 130.95) (end 107.15 131.4) (width 0.15) (layer "B.Cu") (net 303))
  (segment (start 105 131.15) (end 105 131.75) (width 0.15) (layer "B.Cu") (net 303))
  (segment (start 110 130.95) (end 109.2 130.95) (width 0.3) (layer "B.Cu") (net 303))
  (segment (start 105.2 130.95) (end 105 131.15) (width 0.15) (layer "B.Cu") (net 303))
  (segment (start 106 129.35) (end 105.4 129.35) (width 0.15) (layer "B.Cu") (net 303))
  (segment (start 111.1 129.85) (end 110 130.95) (width 0.3) (layer "B.Cu") (net 303))
  (segment (start 107.95 131.4) (end 107.6 131.05) (width 0.15) (layer "B.Cu") (net 303))
  (segment (start 109 129.15) (end 109.2 129.35) (width 0.15) (layer "B.Cu") (net 303))
  (segment (start 108.435 130.15) (end 109.2 130.15) (width 0.15) (layer "B.Cu") (net 303))
  (segment (start 109.2 130.15) (end 109.2 130.95) (width 0.3) (layer "B.Cu") (net 303))
  (segment (start 111.65 129.85) (end 111.25 129.85) (width 0.15) (layer "B.Cu") (net 303))
  (segment (start 100 125.75) (end 99.6 126.15) (width 0.15) (layer "F.Cu") (net 304))
  (segment (start 110.4 130.55) (end 110.8 130.95) (width 0.15) (layer "F.Cu") (net 304))
  (segment (start 107.2 115.35) (end 107.6 114.95) (width 0.15) (layer "F.Cu") (net 304))
  (segment (start 111.2 130.55) (end 111.6 130.95) (width 0.15) (layer "F.Cu") (net 304))
  (segment (start 99.2 117.75) (end 98.8 117.35) (width 0.15) (layer "F.Cu") (net 304))
  (segment (start 108.8 125.75) (end 109.2 126.15) (width 0.15) (layer "F.Cu") (net 304))
  (segment (start 103.2 130.55) (end 102.8 130.95) (width 0.15) (layer "F.Cu") (net 304))
  (segment (start 101.6 115.35) (end 101.2 114.95) (width 0.15) (layer "F.Cu") (net 304))
  (segment (start 109.6 123.35) (end 110 122.95) (width 0.15) (layer "F.Cu") (net 304))
  (segment (start 104 130.55) (end 103.6 130.95) (width 0.15) (layer "F.Cu") (net 304))
  (segment (start 99.2 123.35) (end 98.8 123.75) (width 0.15) (layer "F.Cu") (net 304))
  (segment (start 109.6 117.75) (end 110 117.35) (width 0.15) (layer "F.Cu") (net 304))
  (via (at 111.6 130.95) (size 0.5) (drill 0.2) (layers "F.Cu" "B.Cu") (net 304))
  (via (at 109.2 126.15) (size 0.5) (drill 0.2) (layers "F.Cu" "B.Cu") (net 304))
  (via (at 110 117.35) (size 0.5) (drill 0.2) (layers "F.Cu" "B.Cu") (net 304))
  (via (at 103.6 130.95) (size 0.5) (drill 0.2) (layers "F.Cu" "B.Cu") (net 304))
  (via (at 102.8 130.95) (size 0.5) (drill 0.2) (layers "F.Cu" "B.Cu") (net 304))
  (via (at 101.2 114.95) (size 0.5) (drill 0.2) (layers "F.Cu" "B.Cu") (net 304))
  (via (at 107.6 114.95) (size 0.5) (drill 0.2) (layers "F.Cu" "B.Cu") (net 304))
  (via (at 110 122.95) (size 0.5) (drill 0.2) (layers "F.Cu" "B.Cu") (net 304))
  (via (at 98.8 117.35) (size 0.5) (drill 0.2) (layers "F.Cu" "B.Cu") (net 304))
  (via (at 99.6 126.15) (size 0.5) (drill 0.2) (layers "F.Cu" "B.Cu") (net 304))
  (via (at 110.8 130.95) (size 0.5) (drill 0.2) (layers "F.Cu" "B.Cu") (net 304))
  (via (at 98.8 123.75) (size 0.5) (drill 0.2) (layers "F.Cu" "B.Cu") (net 304))
  (segment (start 112.4 131.85) (end 112.4 131.75) (width 0.25) (layer "B.Cu") (net 304))
  (segment (start 107.95 114.6) (end 107.6 114.95) (width 0.15) (layer "B.Cu") (net 304))
  (segment (start 98.4 123.35) (end 98.8 123.75) (width 0.15) (layer "B.Cu") (net 304))
  (segment (start 110.7 131.715) (end 112.265 131.715) (width 0.25) (layer "B.Cu") (net 304))
  (segment (start 110.7 131.05) (end 110.8 130.95) (width 0.15) (layer "B.Cu") (net 304))
  (segment (start 107.95 114.25) (end 107.95 114.6) (width 0.15) (layer "B.Cu") (net 304))
  (segment (start 109.2 126.15) (end 109.2 125.5) (width 0.15) (layer "B.Cu") (net 304))
  (segment (start 103.6 130.95) (end 104 131.35) (width 0.15) (layer "B.Cu") (net 304))
  (segment (start 98.085 123.35) (end 98.4 123.35) (width 0.15) (layer "B.Cu") (net 304))
  (segment (start 98.55 117.1) (end 98.8 117.35) (width 0.15) (layer "B.Cu") (net 304))
  (segment (start 102.8 130.95) (end 102.95 131.1) (width 0.15) (layer "B.Cu") (net 304))
  (segment (start 100.75 114.5) (end 101.2 114.95) (width 0.15) (layer "B.Cu") (net 304))
  (segment (start 110.7 131.665) (end 110.7 131.05) (width 0.15) (layer "B.Cu") (net 304))
  (segment (start 110 122.95) (end 110.25 122.7) (width 0.15) (layer "B.Cu") (net 304))
  (segment (start 98.135 117.1) (end 98.55 117.1) (width 0.15) (layer "B.Cu") (net 304))
  (segment (start 102.95 131.1) (end 102.95 131.8) (width 0.15) (layer "B.Cu") (net 304))
  (segment (start 112.4 131.75) (end 111.6 130.95) (width 0.25) (layer "B.Cu") (net 304))
  (segment (start 110.715 117.1) (end 110.25 117.1) (width 0.15) (layer "B.Cu") (net 304))
  (segment (start 110.25 117.1) (end 110 117.35) (width 0.15) (layer "B.Cu") (net 304))
  (segment (start 112.265 131.715) (end 112.4 131.85) (width 0.25) (layer "B.Cu") (net 304))
  (segment (start 99.6 126.15) (end 99.6 125.5) (width 0.15) (layer "B.Cu") (net 304))
  (segment (start 113.45 131.85) (end 112.1 131.85) (width 0.15) (layer "B.Cu") (net 304))
  (segment (start 104 131.35) (end 104 131.75) (width 0.15) (layer "B.Cu") (net 304))
  (segment (start 110.25 122.7) (end 110.75 122.7) (width 0.15) (layer "B.Cu") (net 304))
  (segment (start 71.42 122.525) (end 70.42 122.525) (width 0.2) (layer "F.Cu") (net 305))
  (segment (start 71.4 124.185) (end 71.4 122.55) (width 0.2) (layer "F.Cu") (net 305))
  (segment (start 71.45 122.55) (end 72.8 122.55) (width 0.2) (layer "F.Cu") (net 305))
  (segment (start 136 86.0875) (end 136 85.175) (width 0.15) (layer "F.Cu") (net 306))
  (via (at 136 85.175) (size 0.5) (drill 0.2) (layers "F.Cu" "B.Cu") (net 306))
  (segment (start 136.1 85.275) (end 136 85.175) (width 0.2) (layer "B.Cu") (net 306))
  (segment (start 136.1 85.84) (end 136.1 85.275) (width 0.2) (layer "B.Cu") (net 306))
  (segment (start 136.1 85.84) (end 135.115 85.84) (width 0.2) (layer "B.Cu") (net 306))
  (segment (start 136.4 84.775) (end 136 85.175) (width 0.2) (layer "B.Cu") (net 306))
  (segment (start 136.4 84.16) (end 136.4 84.775) (width 0.2) (layer "B.Cu") (net 306))
  (segment (start 138 86.0875) (end 138 85.225) (width 0.15) (layer "F.Cu") (net 307))
  (segment (start 138 85.225) (end 138.1 85.125) (width 0.15) (layer "F.Cu") (net 307))
  (via (at 138.1 85.125) (size 0.5) (drill 0.2) (layers "F.Cu" "B.Cu") (net 307))
  (segment (start 139.1 85.84) (end 138.115 85.84) (width 0.2) (layer "B.Cu") (net 307))
  (segment (start 138.1 85.84) (end 138.1 85.125) (width 0.2) (layer "B.Cu") (net 307))
  (segment (start 138.1 84.725) (end 138.1 85.125) (width 0.2) (layer "B.Cu") (net 307))
  (segment (start 137.535 84.16) (end 138.1 84.725) (width 0.2) (layer "B.Cu") (net 307))
  (segment (start 140.1 168.3) (end 140.1 167.15) (width 0.25) (layer "F.Cu") (net 308))
  (segment (start 136.55 157.325) (end 136.55 158.9) (width 0.25) (layer "F.Cu") (net 308))
  (segment (start 136.55 158.9) (end 136.564117 158.914117) (width 0.25) (layer "F.Cu") (net 308))
  (via (at 136.564117 158.914117) (size 0.5) (drill 0.2) (layers "F.Cu" "B.Cu") (net 308))
  (via (at 140.1 167.15) (size 0.5) (drill 0.2) (layers "F.Cu" "B.Cu") (net 308))
  (segment (start 139.7 162.05) (end 136.564117 158.914117) (width 0.25) (layer "B.Cu") (net 308))
  (segment (start 140.1 167.15) (end 139.7 166.75) (width 0.25) (layer "B.Cu") (net 308))
  (segment (start 139.7 166.75) (end 139.7 162.05) (width 0.25) (layer "B.Cu") (net 308))
  (segment (start 121.325 68.45) (end 124.95 68.45) (width 0.15) (layer "F.Cu") (net 309))
  (segment (start 139.161 62.228) (end 139.161 65.639) (width 0.25) (layer "F.Cu") (net 309))
  (via (at 139.15 65.65) (size 0.5) (drill 0.2) (layers "F.Cu" "B.Cu") (net 309))
  (via (at 124.95 68.45) (size 0.5) (drill 0.2) (layers "F.Cu" "B.Cu") (net 309))
  (segment (start 127.4 66) (end 124.95 68.45) (width 0.15) (layer "B.Cu") (net 309))
  (segment (start 138.8 66) (end 127.4 66) (width 0.15) (layer "B.Cu") (net 309))
  (segment (start 139.15 65.65) (end 138.8 66) (width 0.15) (layer "B.Cu") (net 309))
  (segment (start 138.1 63.765) (end 138.1 61.789) (width 0.25) (layer "F.Cu") (net 310))
  (segment (start 138.1 61.789) (end 139.161 60.728) (width 0.25) (layer "F.Cu") (net 310))
  (segment (start 123.825 68.9) (end 124.3 68.9) (width 0.15) (layer "F.Cu") (net 311))
  (segment (start 121.325 72.475) (end 121.325 71.4) (width 0.15) (layer "F.Cu") (net 311))
  (segment (start 121.325 71.4) (end 123.825 68.9) (width 0.15) (layer "F.Cu") (net 311))
  (segment (start 141.161 65.664) (end 141.161 62.228) (width 0.25) (layer "F.Cu") (net 311))
  (via (at 141.161 65.664) (size 0.5) (drill 0.2) (layers "F.Cu" "B.Cu") (net 311))
  (via (at 124.3 68.9) (size 0.5) (drill 0.2) (layers "F.Cu" "B.Cu") (net 311))
  (segment (start 124.3 68.9) (end 125.15 68.9) (width 0.15) (layer "B.Cu") (net 311))
  (segment (start 140.525 66.3) (end 141.161 65.664) (width 0.15) (layer "B.Cu") (net 311))
  (segment (start 127.75 66.3) (end 140.525 66.3) (width 0.15) (layer "B.Cu") (net 311))
  (segment (start 125.15 68.9) (end 127.75 66.3) (width 0.15) (layer "B.Cu") (net 311))
  (segment (start 141.161 60.728) (end 140.15 61.739) (width 0.25) (layer "F.Cu") (net 312))
  (segment (start 140.15 61.739) (end 140.15 63.765) (width 0.25) (layer "F.Cu") (net 312))
  (segment (start 125.25 69.65) (end 124.95 69.35) (width 0.15) (layer "F.Cu") (net 313))
  (segment (start 143.211 65.636) (end 143.211 62.228) (width 0.25) (layer "F.Cu") (net 313))
  (segment (start 125.25 72.45) (end 125.25 69.65) (width 0.15) (layer "F.Cu") (net 313))
  (via (at 124.95 69.35) (size 0.5) (drill 0.2) (layers "F.Cu" "B.Cu") (net 313))
  (via (at 143.211 65.636) (size 0.5) (drill 0.2) (layers "F.Cu" "B.Cu") (net 313))
  (segment (start 124.95 69.35) (end 125.325 69.35) (width 0.15) (layer "B.Cu") (net 313))
  (segment (start 142.247 66.6) (end 143.211 65.636) (width 0.15) (layer "B.Cu") (net 313))
  (segment (start 128.075 66.6) (end 142.247 66.6) (width 0.15) (layer "B.Cu") (net 313))
  (segment (start 125.325 69.35) (end 128.075 66.6) (width 0.15) (layer "B.Cu") (net 313))
  (segment (start 142.2 63.765) (end 142.2 61.739) (width 0.25) (layer "F.Cu") (net 314))
  (segment (start 142.2 61.739) (end 143.211 60.728) (width 0.25) (layer "F.Cu") (net 314))
  (segment (start 64.75 85.9) (end 63.75 85.9) (width 0.15) (layer "F.Cu") (net 315))
  (via (at 63.75 85.9) (size 0.5) (drill 0.2) (layers "F.Cu" "B.Cu") (net 315))
  (segment (start 63.75 85.9) (end 63.75 86.725) (width 0.15) (layer "B.Cu") (net 315))
  (segment (start 64.75 84.25) (end 63.75 84.25) (width 0.15) (layer "F.Cu") (net 316))
  (via (at 63.75 84.25) (size 0.5) (drill 0.2) (layers "F.Cu" "B.Cu") (net 316))
  (segment (start 63.75 84.25) (end 63.75 85.075) (width 0.15) (layer "B.Cu") (net 316))
  (segment (start 126.705 123.205) (end 124.949978 121.449978) (width 0.1) (layer "F.Cu") (net 317))
  (segment (start 122.92143 121.449978) (end 121.021408 123.35) (width 0.1) (layer "F.Cu") (net 317))
  (segment (start 124.949978 121.449978) (end 122.92143 121.449978) (width 0.1) (layer "F.Cu") (net 317))
  (segment (start 121.021408 123.35) (end 116.8 123.35) (width 0.1) (layer "F.Cu") (net 317))
  (segment (start 126.705 124.18) (end 126.705 123.205) (width 0.1) (layer "F.Cu") (net 317))
  (segment (start 122.974998 121.749978) (end 120.975009 123.749967) (width 0.1) (layer "F.Cu") (net 318))
  (segment (start 115.599967 123.749967) (end 115.2 123.35) (width 0.1) (layer "F.Cu") (net 318))
  (segment (start 124.607114 121.749978) (end 122.974998 121.749978) (width 0.1) (layer "F.Cu") (net 318))
  (segment (start 125.705 124.18) (end 125.705 122.847864) (width 0.1) (layer "F.Cu") (net 318))
  (segment (start 125.705 122.847864) (end 124.607114 121.749978) (width 0.1) (layer "F.Cu") (net 318))
  (segment (start 120.975009 123.749967) (end 115.599967 123.749967) (width 0.1) (layer "F.Cu") (net 318))
  (segment (start 114.85 123.75) (end 114.45 123.35) (width 0.1) (layer "F.Cu") (net 319))
  (segment (start 125.205 122.701432) (end 124.503557 121.999989) (width 0.1) (layer "F.Cu") (net 319))
  (segment (start 115.1 123.75) (end 114.85 123.75) (width 0.1) (layer "F.Cu") (net 319))
  (segment (start 123.078555 121.999989) (end 121.078566 123.999978) (width 0.1) (layer "F.Cu") (net 319))
  (segment (start 121.078566 123.999978) (end 115.349978 123.999978) (width 0.1) (layer "F.Cu") (net 319))
  (segment (start 125.205 124.18) (end 125.205 122.701432) (width 0.1) (layer "F.Cu") (net 319))
  (segment (start 124.503557 121.999989) (end 123.078555 121.999989) (width 0.1) (layer "F.Cu") (net 319))
  (segment (start 115.349978 123.999978) (end 115.1 123.75) (width 0.1) (layer "F.Cu") (net 319))
  (segment (start 124.4 122.25) (end 123.182112 122.25) (width 0.1) (layer "F.Cu") (net 320))
  (segment (start 124.705 122.555) (end 124.4 122.25) (width 0.1) (layer "F.Cu") (net 320))
  (segment (start 115.174995 124.249989) (end 114.875006 123.95) (width 0.1) (layer "F.Cu") (net 320))
  (segment (start 114.2 123.95) (end 113.6 123.35) (width 0.1) (layer "F.Cu") (net 320))
  (segment (start 124.705 124.18) (end 124.705 122.555) (width 0.1) (layer "F.Cu") (net 320))
  (segment (start 123.182112 122.25) (end 121.182123 124.249989) (width 0.1) (layer "F.Cu") (net 320))
  (segment (start 121.182123 124.249989) (end 115.174995 124.249989) (width 0.1) (layer "F.Cu") (net 320))
  (segment (start 114.875006 123.95) (end 114.2 123.95) (width 0.1) (layer "F.Cu") (net 320))
  (segment (start 112 119.35) (end 112.4 118.95) (width 0.15) (layer "F.Cu") (net 321))
  (segment (start 124.205 124.18) (end 124.205 122.755) (width 0.15) (layer "F.Cu") (net 321))
  (segment (start 124.205 122.755) (end 124.2 122.75) (width 0.15) (layer "F.Cu") (net 321))
  (via (at 112.4 118.95) (size 0.5) (drill 0.2) (layers "F.Cu" "B.Cu") (net 321))
  (via (at 117.4 119.74993) (size 0.5) (drill 0.2) (layers "F.Cu" "B.Cu") (net 321))
  (via (at 124.2 122.75) (size 0.5) (drill 0.2) (layers "F.Cu" "B.Cu") (net 321))
  (segment (start 124.2 122.75) (end 121.15 119.7) (width 0.15) (layer "In2.Cu") (net 321))
  (segment (start 121.15 119.7) (end 117.35 119.7) (width 0.15) (layer "In2.Cu") (net 321))
  (segment (start 116.10007 118.45) (end 117.4 119.74993) (width 0.15) (layer "In5.Cu") (net 321))
  (segment (start 112.9 118.45) (end 116.10007 118.45) (width 0.15) (layer "In5.Cu") (net 321))
  (segment (start 112.4 118.95) (end 112.9 118.45) (width 0.15) (layer "In5.Cu") (net 321))
  (segment (start 122.52 124.865) (end 121.785 124.865) (width 0.1) (layer "F.Cu") (net 322))
  (segment (start 115.65 124.5) (end 115.2 124.95) (width 0.1) (layer "F.Cu") (net 322))
  (segment (start 121.42 124.5) (end 115.65 124.5) (width 0.1) (layer "F.Cu") (net 322))
  (segment (start 121.785 124.865) (end 121.42 124.5) (width 0.1) (layer "F.Cu") (net 322))
  (segment (start 122.52 125.365) (end 121.785 125.365) (width 0.1) (layer "F.Cu") (net 323))
  (segment (start 121.785 125.365) (end 121.37 124.95) (width 0.1) (layer "F.Cu") (net 323))
  (segment (start 121.37 124.95) (end 116.8 124.95) (width 0.1) (layer "F.Cu") (net 323))
  (segment (start 121.275001 125.325001) (end 116.375001 125.325001) (width 0.1) (layer "F.Cu") (net 324))
  (segment (start 121.815 125.865) (end 121.275001 125.325001) (width 0.1) (layer "F.Cu") (net 324))
  (segment (start 122.52 125.865) (end 121.815 125.865) (width 0.1) (layer "F.Cu") (net 324))
  (segment (start 116.375001 125.325001) (end 116 124.95) (width 0.1) (layer "F.Cu") (net 324))
  (segment (start 121.815 126.365) (end 121.2 125.75) (width 0.1) (layer "F.Cu") (net 325))
  (segment (start 121.2 125.75) (end 116.8 125.75) (width 0.1) (layer "F.Cu") (net 325))
  (segment (start 122.52 126.365) (end 121.815 126.365) (width 0.1) (layer "F.Cu") (net 325))
  (segment (start 121.17 126.15) (end 121.835 126.815) (width 0.1) (layer "F.Cu") (net 326))
  (segment (start 116.4 126.15) (end 121.17 126.15) (width 0.1) (layer "F.Cu") (net 326))
  (segment (start 116 125.75) (end 116.4 126.15) (width 0.1) (layer "F.Cu") (net 326))
  (segment (start 121.835 126.815) (end 122.47 126.815) (width 0.1) (layer "F.Cu") (net 326))
  (segment (start 116.8 126.55) (end 121.1 126.55) (width 0.1) (layer "F.Cu") (net 327))
  (segment (start 121.865 127.315) (end 122.47 127.315) (width 0.1) (layer "F.Cu") (net 327))
  (segment (start 121.1 126.55) (end 121.865 127.315) (width 0.1) (layer "F.Cu") (net 327))
  (segment (start 121 126.95) (end 116.4 126.95) (width 0.1) (layer "F.Cu") (net 328))
  (segment (start 121.865 127.815) (end 121 126.95) (width 0.1) (layer "F.Cu") (net 328))
  (segment (start 122.47 127.815) (end 121.865 127.815) (width 0.1) (layer "F.Cu") (net 328))
  (segment (start 116.4 126.95) (end 116 127.35) (width 0.1) (layer "F.Cu") (net 328))
  (segment (start 120.9 127.35) (end 121.865 128.315) (width 0.1) (layer "F.Cu") (net 329))
  (segment (start 116.8 127.35) (end 120.9 127.35) (width 0.1) (layer "F.Cu") (net 329))
  (segment (start 121.865 128.315) (end 122.47 128.315) (width 0.1) (layer "F.Cu") (net 329))
  (segment (start 122.55 114.05) (end 121.285728 114.05) (width 0.1) (layer "F.Cu") (net 330))
  (segment (start 117 117.15) (end 116.8 116.95) (width 0.1) (layer "F.Cu") (net 330))
  (segment (start 116.8 116.95) (end 116 116.95) (width 0.1) (layer "F.Cu") (net 330))
  (segment (start 115.6 117.35) (end 115.6 118.15) (width 0.1) (layer "F.Cu") (net 330))
  (segment (start 115.6 118.15) (end 115.2 118.55) (width 0.1) (layer "F.Cu") (net 330))
  (segment (start 116 116.95) (end 115.6 117.35) (width 0.1) (layer "F.Cu") (net 330))
  (segment (start 118.185728 117.15) (end 117 117.15) (width 0.1) (layer "F.Cu") (net 330))
  (segment (start 121.285728 114.05) (end 118.185728 117.15) (width 0.1) (layer "F.Cu") (net 330))
  (segment (start 122.55 115.05) (end 120.639296 115.05) (width 0.1) (layer "F.Cu") (net 331))
  (segment (start 120.639296 115.05) (end 117.939296 117.75) (width 0.1) (layer "F.Cu") (net 331))
  (segment (start 117.939296 117.75) (end 116.8 117.75) (width 0.1) (layer "F.Cu") (net 331))
  (segment (start 116.424999 118.125001) (end 117.917863 118.125001) (width 0.1) (layer "F.Cu") (net 332))
  (segment (start 117.917863 118.125001) (end 120.492864 115.55) (width 0.1) (layer "F.Cu") (net 332))
  (segment (start 120.492864 115.55) (end 122.55 115.55) (width 0.1) (layer "F.Cu") (net 332))
  (segment (start 116 118.55) (end 116.424999 118.125001) (width 0.1) (layer "F.Cu") (net 332))
  (segment (start 120.346432 116.05) (end 122.55 116.05) (width 0.1) (layer "F.Cu") (net 333))
  (segment (start 116.8 118.55) (end 117.846432 118.55) (width 0.1) (layer "F.Cu") (net 333))
  (segment (start 117.846432 118.55) (end 120.346432 116.05) (width 0.1) (layer "F.Cu") (net 333))
  (segment (start 114 118.95) (end 117.8 118.95) (width 0.1) (layer "F.Cu") (net 334))
  (segment (start 117.8 118.95) (end 120.2 116.55) (width 0.1) (layer "F.Cu") (net 334))
  (segment (start 113.6 118.55) (end 114 118.95) (width 0.1) (layer "F.Cu") (net 334))
  (segment (start 120.2 116.55) (end 122.55 116.55) (width 0.1) (layer "F.Cu") (net 334))
  (segment (start 117.592072 119.35) (end 117.392073 119.150001) (width 0.1) (layer "F.Cu") (net 335))
  (segment (start 123.235 118.235) (end 123.235 119.015) (width 0.1) (layer "F.Cu") (net 335))
  (segment (start 123.235 119.015) (end 122.9 119.35) (width 0.1) (layer "F.Cu") (net 335))
  (segment (start 116.999999 119.150001) (end 116.8 119.35) (width 0.1) (layer "F.Cu") (net 335))
  (segment (start 122.9 119.35) (end 117.592072 119.35) (width 0.1) (layer "F.Cu") (net 335))
  (segment (start 117.392073 119.150001) (end 116.999999 119.150001) (width 0.1) (layer "F.Cu") (net 335))
  (segment (start 121.7 120.15) (end 122.200066 119.649934) (width 0.1) (layer "F.Cu") (net 336))
  (segment (start 123.400066 119.649934) (end 123.735 119.315) (width 0.1) (layer "F.Cu") (net 336))
  (segment (start 122.200066 119.649934) (end 123.400066 119.649934) (width 0.1) (layer "F.Cu") (net 336))
  (segment (start 123.735 119.315) (end 123.735 118.235) (width 0.1) (layer "F.Cu") (net 336))
  (segment (start 116.8 120.15) (end 121.7 120.15) (width 0.1) (layer "F.Cu") (net 336))
  (segment (start 122.350055 119.899945) (end 123.550055 119.899945) (width 0.1) (layer "F.Cu") (net 337))
  (segment (start 123.550055 119.899945) (end 124.235 119.215) (width 0.1) (layer "F.Cu") (net 337))
  (segment (start 116 120.15) (end 116.4 120.55) (width 0.1) (layer "F.Cu") (net 337))
  (segment (start 124.235 119.215) (end 124.235 118.235) (width 0.1) (layer "F.Cu") (net 337))
  (segment (start 121.7 120.55) (end 122.350055 119.899945) (width 0.1) (layer "F.Cu") (net 337))
  (segment (start 116.4 120.55) (end 121.7 120.55) (width 0.1) (layer "F.Cu") (net 337))
  (segment (start 116.8 120.95) (end 121.653568 120.95) (width 0.1) (layer "F.Cu") (net 338))
  (segment (start 124.735 119.215) (end 124.735 118.235) (width 0.1) (layer "F.Cu") (net 338))
  (segment (start 121.653568 120.95) (end 122.453612 120.149956) (width 0.1) (layer "F.Cu") (net 338))
  (segment (start 122.453612 120.149956) (end 123.800044 120.149956) (width 0.1) (layer "F.Cu") (net 338))
  (segment (start 123.800044 120.149956) (end 124.735 119.215) (width 0.1) (layer "F.Cu") (net 338))
  (segment (start 121.607136 121.35) (end 122.557169 120.399967) (width 0.1) (layer "F.Cu") (net 339))
  (segment (start 116 120.95) (end 116.4 121.35) (width 0.1) (layer "F.Cu") (net 339))
  (segment (start 122.557169 120.399967) (end 124.050033 120.399967) (width 0.1) (layer "F.Cu") (net 339))
  (segment (start 125.235 119.215) (end 125.235 118.235) (width 0.1) (layer "F.Cu") (net 339))
  (segment (start 124.050033 120.399967) (end 125.235 119.215) (width 0.1) (layer "F.Cu") (net 339))
  (segment (start 116.4 121.35) (end 121.607136 121.35) (width 0.1) (layer "F.Cu") (net 339))
  (segment (start 124.200022 120.649978) (end 125.735 119.115) (width 0.1) (layer "F.Cu") (net 340))
  (segment (start 125.735 119.115) (end 125.735 118.235) (width 0.1) (layer "F.Cu") (net 340))
  (segment (start 121.560704 121.75) (end 122.660726 120.649978) (width 0.1) (layer "F.Cu") (net 340))
  (segment (start 116.8 121.75) (end 121.560704 121.75) (width 0.1) (layer "F.Cu") (net 340))
  (segment (start 122.660726 120.649978) (end 124.200022 120.649978) (width 0.1) (layer "F.Cu") (net 340))
  (segment (start 121.114272 122.55) (end 122.764283 120.899989) (width 0.1) (layer "F.Cu") (net 341))
  (segment (start 122.764283 120.899989) (end 124.350011 120.899989) (width 0.1) (layer "F.Cu") (net 341))
  (segment (start 126.235 119.015) (end 126.235 118.235) (width 0.1) (layer "F.Cu") (net 341))
  (segment (start 124.350011 120.899989) (end 126.235 119.015) (width 0.1) (layer "F.Cu") (net 341))
  (segment (start 116.8 122.55) (end 121.114272 122.55) (width 0.1) (layer "F.Cu") (net 341))
  (segment (start 122.86784 121.15) (end 124.55 121.15) (width 0.1) (layer "F.Cu") (net 342))
  (segment (start 126.735 118.965) (end 126.735 118.235) (width 0.1) (layer "F.Cu") (net 342))
  (segment (start 116.375001 122.925001) (end 121.092839 122.925001) (width 0.1) (layer "F.Cu") (net 342))
  (segment (start 116 122.55) (end 116.375001 122.925001) (width 0.1) (layer "F.Cu") (net 342))
  (segment (start 124.55 121.15) (end 126.735 118.965) (width 0.1) (layer "F.Cu") (net 342))
  (segment (start 121.092839 122.925001) (end 122.86784 121.15) (width 0.1) (layer "F.Cu") (net 342))
  (segment (start 64.75 94.1) (end 63.75 94.1) (width 0.15) (layer "F.Cu") (net 343))
  (via (at 63.75 94.1) (size 0.5) (drill 0.2) (layers "F.Cu" "B.Cu") (net 343))
  (segment (start 63.75 94.1) (end 63.75 94.95) (width 0.15) (layer "B.Cu") (net 343))
  (segment (start 64.75 92.45) (end 63.75 92.45) (width 0.15) (layer "F.Cu") (net 344))
  (via (at 63.75 92.45) (size 0.5) (drill 0.2) (layers "F.Cu" "B.Cu") (net 344))
  (segment (start 63.75 92.45) (end 63.75 93.3) (width 0.15) (layer "B.Cu") (net 344))
  (segment (start 64.75 90.8) (end 63.75 90.8) (width 0.15) (layer "F.Cu") (net 345))
  (via (at 63.75 90.8) (size 0.5) (drill 0.2) (layers "F.Cu" "B.Cu") (net 345))
  (segment (start 63.75 90.8) (end 63.75 91.625) (width 0.15) (layer "B.Cu") (net 345))
  (segment (start 64.75 89.15) (end 63.75 89.15) (width 0.15) (layer "F.Cu") (net 346))
  (via (at 63.75 89.15) (size 0.5) (drill 0.2) (layers "F.Cu" "B.Cu") (net 346))
  (segment (start 63.75 89.15) (end 63.75 89.925) (width 0.15) (layer "B.Cu") (net 346))
  (segment (start 64.75 87.5) (end 63.75 87.5) (width 0.15) (layer "F.Cu") (net 347))
  (via (at 63.75 87.5) (size 0.5) (drill 0.2) (layers "F.Cu" "B.Cu") (net 347))
  (segment (start 63.75 87.5) (end 63.75 88.325) (width 0.15) (layer "B.Cu") (net 347))
  (segment (start 72.56 162.33) (end 71.65 162.33) (width 0.15) (layer "F.Cu") (net 348))
  (segment (start 71.65 162.33) (end 71.295 161.975) (width 0.15) (layer "F.Cu") (net 348))
  (segment (start 71.295 161.975) (end 71.295 161.02) (width 0.15) (layer "F.Cu") (net 348))
  (segment (start 73.94 165.11) (end 73.94 166.1) (width 0.15) (layer "F.Cu") (net 349))
  (segment (start 74.07 166.23) (end 74.07 167.87) (width 0.15) (layer "F.Cu") (net 349))
  (segment (start 73.94 166.1) (end 74.07 166.23) (width 0.15) (layer "F.Cu") (net 349))
  (segment (start 72.57 167.87) (end 71.315 167.87) (width 0.15) (layer "F.Cu") (net 350))
  (segment (start 93.285 78.9) (end 94.3 78.9) (width 0.25) (layer "F.Cu") (net 352))
  (segment (start 88.8 78.45) (end 88.8 79.1) (width 0.5) (layer "F.Cu") (net 354))
  (segment (start 91.315 76.85) (end 89.5 76.85) (width 0.3) (layer "F.Cu") (net 354))
  (segment (start 89.5 76.85) (end 89.5 77.75) (width 0.5) (layer "F.Cu") (net 354))
  (segment (start 89.1 74.25) (end 88.25 74.25) (width 0.7) (layer "F.Cu") (net 354))
  (segment (start 87.635 78.9) (end 88.85 78.9) (width 0.15) (layer "F.Cu") (net 354))
  (segment (start 89.5 74.25) (end 89.5 76.85) (width 0.5) (layer "F.Cu") (net 354))
  (segment (start 89.5 74.25) (end 89.1 74.25) (width 0.7) (layer "F.Cu") (net 354))
  (segment (start 90.455 74.25) (end 89.5 74.25) (width 0.7) (layer "F.Cu") (net 354))
  (segment (start 89.5 77.75) (end 88.8 78.45) (width 0.5) (layer "F.Cu") (net 354))
  (segment (start 85.185 89.55) (end 85.185 87.315) (width 0.25) (layer "F.Cu") (net 355))
  (segment (start 85.185 87.315) (end 86.1 86.4) (width 0.25) (layer "F.Cu") (net 355))
  (segment (start 77.07 92.33) (end 83.97 92.33) (width 0.2) (layer "F.Cu") (net 355))
  (segment (start 85.85 87.25) (end 85.85 90.45) (width 0.2) (layer "F.Cu") (net 355))
  (segment (start 86.6 86.5) (end 85.85 87.25) (width 0.2) (layer "F.Cu") (net 355))
  (segment (start 85.85 90.45) (end 83.97 92.33) (width 0.2) (layer "F.Cu") (net 355))
  (segment (start 120.074056 84.808104) (end 120.989056 83.893104) (width 0.25) (layer "F.Cu") (net 356))
  (segment (start 120.074056 87.043104) (end 120.074056 84.808104) (width 0.25) (layer "F.Cu") (net 356))
  (segment (start 120.989056 83.893104) (end 121.484056 83.893104) (width 0.3) (layer "F.Cu") (net 356))
  (segment (start 123.2 81.875) (end 122.45 82.625) (width 0.25) (layer "F.Cu") (net 356))
  (segment (start 123.2 76.9) (end 123.2 81.875) (width 0.25) (layer "F.Cu") (net 356))
  (segment (start 122.45 82.625) (end 121.125 82.625) (width 0.25) (layer "F.Cu") (net 356))
  (segment (start 79.235 87.315) (end 80.15 86.4) (width 0.25) (layer "F.Cu") (net 357))
  (segment (start 79.235 89.55) (end 79.235 87.315) (width 0.25) (layer "F.Cu") (net 357))
  (segment (start 80.65 86.5) (end 79.9 87.25) (width 0.2) (layer "F.Cu") (net 357))
  (segment (start 76.3 90.65) (end 74.6 92.35) (width 0.2) (layer "F.Cu") (net 357))
  (segment (start 79.5 90.65) (end 76.3 90.65) (width 0.2) (layer "F.Cu") (net 357))
  (segment (start 79.9 90.25) (end 79.5 90.65) (width 0.2) (layer "F.Cu") (net 357))
  (segment (start 79.9 87.25) (end 79.9 90.25) (width 0.2) (layer "F.Cu") (net 357))
  (segment (start 73.135 89.55) (end 73.135 87.315) (width 0.25) (layer "F.Cu") (net 358))
  (segment (start 73.135 87.315) (end 74.05 86.4) (width 0.25) (layer "F.Cu") (net 358))
  (segment (start 73.8 87.25) (end 73.8 90.85) (width 0.2) (layer "F.Cu") (net 358))
  (segment (start 74.05 86.4) (end 74.45 86.4) (width 0.25) (layer "F.Cu") (net 358))
  (segment (start 73.8 90.85) (end 72.3 92.35) (width 0.2) (layer "F.Cu") (net 358))
  (segment (start 74.55 86.5) (end 73.8 87.25) (width 0.2) (layer "F.Cu") (net 358))
  (segment (start 91.185 87.315) (end 92.1 86.4) (width 0.25) (layer "F.Cu") (net 359))
  (segment (start 91.185 89.55) (end 91.185 87.315) (width 0.25) (layer "F.Cu") (net 359))
  (segment (start 75.915 61.2) (end 74.9 61.2) (width 0.25) (layer "F.Cu") (net 364))
  (segment (start 92.55 63.25) (end 92.57 63.27) (width 0.15) (layer "F.Cu") (net 366))
  (segment (start 92.57 63.27) (end 92.57 64.55) (width 0.15) (layer "F.Cu") (net 366))
  (segment (start 72.215 77.75) (end 71.4 77.75) (width 0.15) (layer "F.Cu") (net 366))
  (segment (start 69.2 80.3) (end 71.25 78.25) (width 0.15) (layer "F.Cu") (net 366))
  (segment (start 71.4 77.75) (end 71.25 77.9) (width 0.15) (layer "F.Cu") (net 366))
  (segment (start 71.25 78.25) (end 71.25 77.9) (width 0.15) (layer "F.Cu") (net 366))
  (segment (start 69.525 86.825) (end 70.3 86.825) (width 0.15) (layer "F.Cu") (net 366))
  (segment (start 69.2 80.3) (end 69.2 86.5) (width 0.15) (layer "F.Cu") (net 366))
  (segment (start 69.2 86.5) (end 69.525 86.825) (width 0.15) (layer "F.Cu") (net 366))
  (via (at 92.55 63.25) (size 0.5) (drill 0.2) (layers "F.Cu" "B.Cu") (net 366))
  (via (at 71.25 77.9) (size 0.5) (drill 0.2) (layers "F.Cu" "B.Cu") (net 366))
  (segment (start 92.55 63.25) (end 92.55 64.5) (width 0.15) (layer "In5.Cu") (net 366))
  (segment (start 72.15 77) (end 71.25 77.9) (width 0.15) (layer "In5.Cu") (net 366))
  (segment (start 93.45 68.85) (end 88.6 73.7) (width 0.15) (layer "In5.Cu") (net 366))
  (segment (start 92.55 64.5) (end 93.45 65.4) (width 0.15) (layer "In5.Cu") (net 366))
  (segment (start 88.6 77.35) (end 87.55 78.4) (width 0.15) (layer "In5.Cu") (net 366))
  (segment (start 88.6 73.7) (end 88.6 77.35) (width 0.15) (layer "In5.Cu") (net 366))
  (segment (start 83.7 77) (end 72.15 77) (width 0.15) (layer "In5.Cu") (net 366))
  (segment (start 85.1 78.4) (end 83.7 77) (width 0.15) (layer "In5.Cu") (net 366))
  (segment (start 93.45 65.4) (end 93.45 68.85) (width 0.15) (layer "In5.Cu") (net 366))
  (segment (start 87.55 78.4) (end 85.1 78.4) (width 0.15) (layer "In5.Cu") (net 366))
  (segment (start 89.2 115.845) (end 89.2 114.6) (width 0.1) (layer "F.Cu") (net 367))
  (segment (start 90.005 116.65) (end 89.2 115.845) (width 0.1) (layer "F.Cu") (net 367))
  (segment (start 96 117.75) (end 94.9 116.65) (width 0.1) (layer "F.Cu") (net 367))
  (segment (start 94.9 116.65) (end 90.005 116.65) (width 0.1) (layer "F.Cu") (net 367))
  (segment (start 91.235 78.835) (end 90.3 77.9) (width 0.2) (layer "F.Cu") (net 368))
  (segment (start 128.05 157.325) (end 128.05 154.835) (width 0.15) (layer "F.Cu") (net 376))
  (segment (start 91.3 98.6) (end 91.8 99.1) (width 0.15) (layer "F.Cu") (net 377))
  (segment (start 93.6 116.15) (end 93.2 115.75) (width 0.15) (layer "F.Cu") (net 377))
  (via (at 91.8 99.1) (size 0.5) (drill 0.2) (layers "F.Cu" "B.Cu") (net 377))
  (via (at 93.2 115.75) (size 0.5) (drill 0.2) (layers "F.Cu" "B.Cu") (net 377))
  (segment (start 91.053134 112.027815) (end 91.062378 112.054235) (width 0.15) (layer "In2.Cu") (net 377))
  (segment (start 91.221652 115.5696) (end 91.221652 115.603189) (width 0.15) (layer "In2.Cu") (net 377))
  (segment (start 91.537622 112.795764) (end 91.546866 112.822184) (width 0.15) (layer "In2.Cu") (net 377))
  (segment (start 91.062378 113.695764) (end 91.053134 113.722184) (width 0.15) (layer "In2.Cu") (net 377))
  (segment (start 91.120764 113.312621) (end 91.147184 113.321865) (width 0.15) (layer "In2.Cu") (net 377))
  (segment (start 91.835146 114.140082) (end 91.817275 114.168523) (width 0.15) (layer "In2.Cu") (net 377))
  (segment (start 91.290904 115.713402) (end 91.321167 115.727976) (width 0.15) (layer "In2.Cu") (net 377))
  (segment (start 91.053134 114.427815) (end 91.062378 114.454235) (width 0.15) (layer "In2.Cu") (net 377))
  (segment (start 92.134111 115.454064) (end 92.113169 115.480326) (width 0.15) (layer "In2.Cu") (net 377))
  (segment (start 91.05 112.6) (end 91.053134 112.627815) (width 0.15) (layer "In2.Cu") (net 377))
  (segment (start 91.733379 114.221239) (end 91.7 114.225) (width 0.15) (layer "In2.Cu") (net 377))
  (segment (start 91.546866 112.822184) (end 91.55 112.85) (width 0.15) (layer "In2.Cu") (net 377))
  (segment (start 91.296865 114.622184) (end 91.3 114.65) (width 0.15) (layer "In2.Cu") (net 377))
  (segment (start 92.056871 115.541942) (end 92.042298 115.572206) (width 0.15) (layer "In2.Cu") (net 377))
  (segment (start 92.113169 115.480326) (end 92.077814 115.515682) (width 0.15) (layer "In2.Cu") (net 377))
  (segment (start 92.156159 115.391054) (end 92.148686 115.423802) (width 0.15) (layer "In2.Cu") (net 377))
  (segment (start 91.252936 111.797728) (end 91.229235 111.812621) (width 0.15) (layer "In2.Cu") (net 377))
  (segment (start 91.321167 115.727976) (end 91.353914 115.73545) (width 0.15) (layer "In2.Cu") (net 377))
  (segment (start 92.034823 115.604953) (end 92.034823 115.638543) (width 0.15) (layer "In2.Cu") (net 377))
  (segment (start 92.159953 115.75) (end 93.2 115.75) (width 0.15) (layer "In2.Cu") (net 377))
  (segment (start 91.296865 111.727815) (end 91.287621 111.754235) (width 0.15) (layer "In2.Cu") (net 377))
  (segment (start 91.120764 112.712621) (end 91.147184 112.721865) (width 0.15) (layer "In2.Cu") (net 377))
  (segment (start 91.502937 112.152271) (end 91.522729 112.172063) (width 0.15) (layer "In2.Cu") (net 377))
  (segment (start 91.2437 115.666199) (end 91.264643 115.69246) (width 0.15) (layer "In2.Cu") (net 377))
  (segment (start 91.097063 112.697728) (end 91.120764 112.712621) (width 0.15) (layer "In2.Cu") (net 377))
  (segment (start 91.147184 113.321865) (end 91.175 113.325) (width 0.15) (layer "In2.Cu") (net 377))
  (segment (start 92.134112 115.294456) (end 92.148685 115.324718) (width 0.15) (layer "In2.Cu") (net 377))
  (segment (start 91.175 112.125) (end 91.425 112.125) (width 0.15) (layer "In2.Cu") (net 377))
  (segment (start 91.48441 115.180691) (end 91.48441 115.21428) (width 0.15) (layer "In2.Cu") (net 377))
  (segment (start 91.053134 113.227815) (end 91.062378 113.254235) (width 0.15) (layer "In2.Cu") (net 377))
  (segment (start 91.44142 115.303552) (end 91.264643 115.480328) (width 0.15) (layer "In2.Cu") (net 377))
  (segment (start 91.901039 115.268196) (end 91.927299 115.247253) (width 0.15) (layer "In2.Cu") (net 377))
  (segment (start 91.264643 115.69246) (end 91.290904 115.713402) (width 0.15) (layer "In2.Cu") (net 377))
  (segment (start 91.120764 113.037378) (end 91.097063 113.052271) (width 0.15) (layer "In2.Cu") (net 377))
  (segment (start 91.175 113.925) (end 91.7 113.925) (width 0.15) (layer "In2.Cu") (net 377))
  (segment (start 92.148686 115.423802) (end 92.134111 115.454064) (width 0.15) (layer "In2.Cu") (net 377))
  (segment (start 91.793524 114.192274) (end 91.765083 114.210145) (width 0.15) (layer "In2.Cu") (net 377))
  (segment (start 91.765083 114.210145) (end 91.733379 114.221239) (width 0.15) (layer "In2.Cu") (net 377))
  (segment (start 92.056645 115.232678) (end 92.086909 115.247253) (width 0.15) (layer "In2.Cu") (net 377))
  (segment (start 91.817275 113.568523) (end 91.793524 113.592274) (width 0.15) (layer "In2.Cu") (net 377))
  (segment (start 91.077271 112.677936) (end 91.097063 112.697728) (width 0.15) (layer "In2.Cu") (net 377))
  (segment (start 91.077271 113.072063) (end 91.062378 113.095764) (width 0.15) (layer "In2.Cu") (net 377))
  (segment (start 92.034823 115.638543) (end 92.042298 115.67129) (width 0.15) (layer "In2.Cu") (net 377))
  (segment (start 91.479236 112.137378) (end 91.502937 112.152271) (width 0.15) (layer "In2.Cu") (net 377))
  (segment (start 91.05 113.2) (end 91.053134 113.227815) (width 0.15) (layer "In2.Cu") (net 377))
  (segment (start 91.120764 114.237378) (end 91.097063 114.252271) (width 0.15) (layer "In2.Cu") (net 377))
  (segment (start 91.3 114.65) (end 91.3 114.95) (width 0.15) (layer "In2.Cu") (net 377))
  (segment (start 91.479236 112.737378) (end 91.502937 112.752271) (width 0.15) (layer "In2.Cu") (net 377))
  (segment (start 92.023898 115.225203) (end 92.056645 115.232678) (width 0.15) (layer "In2.Cu") (net 377))
  (segment (start 92.113169 115.268194) (end 92.134112 115.294456) (width 0.15) (layer "In2.Cu") (net 377))
  (segment (start 91.7 113.925) (end 91.733379 113.92876) (width 0.15) (layer "In2.Cu") (net 377))
  (segment (start 91.097063 112.452271) (end 91.077271 112.472063) (width 0.15) (layer "In2.Cu") (net 377))
  (segment (start 91.120764 113.637378) (end 91.097063 113.652271) (width 0.15) (layer "In2.Cu") (net 377))
  (segment (start 91.85 114.075) (end 91.84624 114.108378) (width 0.15) (layer "In2.Cu") (net 377))
  (segment (start 91.062378 113.254235) (end 91.077271 113.277936) (width 0.15) (layer "In2.Cu") (net 377))
  (segment (start 91.44142 115.09142) (end 91.462362 115.117681) (width 0.15) (layer "In2.Cu") (net 377))
  (segment (start 91.7 114.225) (end 91.175 114.225) (width 0.15) (layer "In2.Cu") (net 377))
  (segment (start 91.053134 112.627815) (end 91.062378 112.654235) (width 0.15) (layer "In2.Cu") (net 377))
  (segment (start 91.221652 115.603189) (end 91.229126 115.635936) (width 0.15) (layer "In2.Cu") (net 377))
  (segment (start 91.175 113.025) (end 91.147184 113.028134) (width 0.15) (layer "In2.Cu") (net 377))
  (segment (start 91.522729 112.377936) (end 91.502937 112.397728) (width 0.15) (layer "In2.Cu") (net 377))
  (segment (start 91.120764 112.112621) (end 91.147184 112.121865) (width 0.15) (layer "In2.Cu") (net 377))
  (segment (start 91.733379 113.621239) (end 91.7 113.625) (width 0.15) (layer "In2.Cu") (net 377))
  (segment (start 91.05 114.4) (end 91.053134 114.427815) (width 0.15) (layer "In2.Cu") (net 377))
  (segment (start 91.537622 112.954235) (end 91.522729 112.977936) (width 0.15) (layer "In2.Cu") (net 377))
  (segment (start 91.765083 113.610145) (end 91.733379 113.621239) (width 0.15) (layer "In2.Cu") (net 377))
  (segment (start 91.502937 112.752271) (end 91.522729 112.772063) (width 0.15) (layer "In2.Cu") (net 377))
  (segment (start 91.537622 112.354235) (end 91.522729 112.377936) (width 0.15) (layer "In2.Cu") (net 377))
  (segment (start 91.765083 113.939854) (end 91.793524 113.957725) (width 0.15) (layer "In2.Cu") (net 377))
  (segment (start 91.522729 112.772063) (end 91.537622 112.795764) (width 0.15) (layer "In2.Cu") (net 377))
  (segment (start 92.15616 115.357466) (end 92.156159 115.391054) (width 0.15) (layer "In2.Cu") (net 377))
  (segment (start 91.835146 113.540082) (end 91.817275 113.568523) (width 0.15) (layer "In2.Cu") (net 377))
  (segment (start 91.097063 111.852271) (end 91.077271 111.872063) (width 0.15) (layer "In2.Cu") (net 377))
  (segment (start 91.077271 112.472063) (end 91.062378 112.495764) (width 0.15) (layer "In2.Cu") (net 377))
  (segment (start 91.097063 113.897728) (end 91.120764 113.912621) (width 0.15) (layer "In2.Cu") (net 377))
  (segment (start 91.546866 112.927815) (end 91.537622 112.954235) (width 0.15) (layer "In2.Cu") (net 377))
  (segment (start 91.733379 113.32876) (end 91.765083 113.339854) (width 0.15) (layer "In2.Cu") (net 377))
  (segment (start 91.55 112.85) (end 91.55 112.9) (width 0.15) (layer "In2.Cu") (net 377))
  (segment (start 91.05 111.95) (end 91.05 112) (width 0.15) (layer "In2.Cu") (net 377))
  (segment (start 91.835146 113.409917) (end 91.84624 113.441621) (width 0.15) (layer "In2.Cu") (net 377))
  (segment (start 91.147184 111.828134) (end 91.120764 111.837378) (width 0.15) (layer "In2.Cu") (net 377))
  (segment (start 92.042298 115.572206) (end 92.034823 115.604953) (width 0.15) (layer "In2.Cu") (net 377))
  (segment (start 91.3 99.6) (end 91.3 111.7) (width 0.15) (layer "In2.Cu") (net 377))
  (segment (start 91.55 112.25) (end 91.55 112.3) (width 0.15) (layer "In2.Cu") (net 377))
  (segment (start 91.120764 114.512621) (end 91.147184 114.521865) (width 0.15) (layer "In2.Cu") (net 377))
  (segment (start 91.387503 115.73545) (end 91.42025 115.727976) (width 0.15) (layer "In2.Cu") (net 377))
  (segment (start 91.05 114.35) (end 91.05 114.4) (width 0.15) (layer "In2.Cu") (net 377))
  (segment (start 91.05 113.8) (end 91.053134 113.827815) (width 0.15) (layer "In2.Cu") (net 377))
  (segment (start 92.077814 115.727814) (end 92.1 115.75) (width 0.15) (layer "In2.Cu") (net 377))
  (segment (start 91.053134 113.722184) (end 91.05 113.75) (width 0.15) (layer "In2.Cu") (net 377))
  (segment (start 91.502937 112.997728) (end 91.479236 113.012621) (width 0.15) (layer "In2.Cu") (net 377))
  (segment (start 91.120764 113.912621) (end 91.147184 113.921865) (width 0.15) (layer "In2.Cu") (net 377))
  (segment (start 92.1 115.75) (end 92.159953 115.75) (width 0.15) (layer "In2.Cu") (net 377))
  (segment (start 91.147184 114.521865) (end 91.202815 114.528134) (width 0.15) (layer "In2.Cu") (net 377))
  (segment (start 91.077271 113.672063) (end 91.062378 113.695764) (width 0.15) (layer "In2.Cu") (net 377))
  (segment (start 92.086909 115.247253) (end 92.113169 115.268194) (width 0.15) (layer "In2.Cu") (net 377))
  (segment (start 91.272728 111.777936) (end 91.252936 111.797728) (width 0.15) (layer "In2.Cu") (net 377))
  (segment (start 91.3 111.7) (end 91.296865 111.727815) (width 0.15) (layer "In2.Cu") (net 377))
  (segment (start 91.053134 114.322184) (end 91.05 114.35) (width 0.15) (layer "In2.Cu") (net 377))
  (segment (start 91.053134 111.922184) (end 91.05 111.95) (width 0.15) (layer "In2.Cu") (net 377))
  (segment (start 91.05 112.55) (end 91.05 112.6) (width 0.15) (layer "In2.Cu") (net 377))
  (segment (start 91.229126 115.635936) (end 91.2437 115.666199) (width 0.15) (layer "In2.Cu") (net 377))
  (segment (start 91.062378 113.854235) (end 91.077271 113.877936) (width 0.15) (layer "In2.Cu") (net 377))
  (segment (start 91.353914 115.73545) (end 91.387503 115.73545) (width 0.15) (layer "In2.Cu") (net 377))
  (segment (start 91.502937 112.397728) (end 91.479236 112.412621) (width 0.15) (layer "In2.Cu") (net 377))
  (segment (start 91.425 113.025) (end 91.175 113.025) (width 0.15) (layer "In2.Cu") (net 377))
  (segment (start 91.202815 114.528134) (end 91.229235 114.537378) (width 0.15) (layer "In2.Cu") (net 377))
  (segment (start 91.202815 111.821865) (end 91.147184 111.828134) (width 0.15) (layer "In2.Cu") (net 377))
  (segment (start 91.835146 114.009917) (end 91.84624 114.041621) (width 0.15) (layer "In2.Cu") (net 377))
  (segment (start 91.425 112.125) (end 91.452816 112.128134) (width 0.15) (layer "In2.Cu") (net 377))
  (segment (start 91.077271 114.477936) (end 91.097063 114.497728) (width 0.15) (layer "In2.Cu") (net 377))
  (segment (start 91.522729 112.172063) (end 91.537622 112.195764) (width 0.15) (layer "In2.Cu") (net 377))
  (segment (start 91.264643 115.480328) (end 91.2437 115.506589) (width 0.15) (layer "In2.Cu") (net 377))
  (segment (start 91.42025 115.727976) (end 91.450513 115.713402) (width 0.15) (layer "In2.Cu") (net 377))
  (segment (start 91.479236 113.012621) (end 91.452816 113.021865) (width 0.15) (layer "In2.Cu") (net 377))
  (segment (start 91.097063 113.052271) (end 91.077271 113.072063) (width 0.15) (layer "In2.Cu") (net 377))
  (segment (start 91.7 113.625) (end 91.175 113.625) (width 0.15) (layer "In2.Cu") (net 377))
  (segment (start 91.452816 112.128134) (end 91.479236 112.137378) (width 0.15) (layer "In2.Cu") (net 377))
  (segment (start 91.229126 115.536852) (end 91.221652 115.5696) (width 0.15) (layer "In2.Cu") (net 377))
  (segment (start 91.053134 113.827815) (end 91.062378 113.854235) (width 0.15) (layer "In2.Cu") (net 377))
  (segment (start 91.2437 115.506589) (end 91.229126 115.536852) (width 0.15) (layer "In2.Cu") (net 377))
  (segment (start 91.546866 112.327815) (end 91.537622 112.354235) (width 0.15) (layer "In2.Cu") (net 377))
  (segment (start 91.425 112.725) (end 91.452816 112.728134) (width 0.15) (layer "In2.Cu") (net 377))
  (segment (start 91.450513 115.713402) (end 91.476775 115.69246) (width 0.15) (layer "In2.Cu") (net 377))
  (segment (start 91.990308 115.225203) (end 92.023898 115.225203) (width 0.15) (layer "In2.Cu") (net 377))
  (segment (start 91.817275 114.168523) (end 91.793524 114.192274) (width 0.15) (layer "In2.Cu") (net 377))
  (segment (start 91.05 113.75) (end 91.05 113.8) (width 0.15) (layer "In2.Cu") (net 377))
  (segment (start 91.120764 111.837378) (end 91.097063 111.852271) (width 0.15) (layer "In2.Cu") (net 377))
  (segment (start 91.733379 113.92876) (end 91.765083 113.939854) (width 0.15) (layer "In2.Cu") (net 377))
  (segment (start 91.062378 111.895764) (end 91.053134 111.922184) (width 0.15) (layer "In2.Cu") (net 377))
  (segment (start 91.097063 112.097728) (end 91.120764 112.112621) (width 0.15) (layer "In2.Cu") (net 377))
  (segment (start 91.476775 115.69246) (end 91.901039 115.268196) (width 0.15) (layer "In2.Cu") (net 377))
  (segment (start 91.817275 113.381476) (end 91.835146 113.409917) (width 0.15) (layer "In2.Cu") (net 377))
  (segment (start 91.452816 112.421865) (end 91.425 112.425) (width 0.15) (layer "In2.Cu") (net 377))
  (segment (start 91.05 112) (end 91.053134 112.027815) (width 0.15) (layer "In2.Cu") (net 377))
  (segment (start 92.056871 115.701552) (end 92.077814 115.727814) (width 0.15) (layer "In2.Cu") (net 377))
  (segment (start 91.147184 114.228134) (end 91.120764 114.237378) (width 0.15) (layer "In2.Cu") (net 377))
  (segment (start 91.175 112.725) (end 91.425 112.725) (width 0.15) (layer "In2.Cu") (net 377))
  (segment (start 91.05 113.15) (end 91.05 113.2) (width 0.15) (layer "In2.Cu") (net 377))
  (segment (start 91.147184 112.721865) (end 91.175 112.725) (width 0.15) (layer "In2.Cu") (net 377))
  (segment (start 91.175 113.325) (end 91.7 113.325) (width 0.15) (layer "In2.Cu") (net 377))
  (segment (start 91.062378 114.295764) (end 91.053134 114.322184) (width 0.15) (layer "In2.Cu") (net 377))
  (segment (start 91.85 113.475) (end 91.84624 113.508378) (width 0.15) (layer "In2.Cu") (net 377))
  (segment (start 91.147184 113.628134) (end 91.120764 113.637378) (width 0.15) (layer "In2.Cu") (net 377))
  (segment (start 91.765083 113.339854) (end 91.793524 113.357725) (width 0.15) (layer "In2.Cu") (net 377))
  (segment (start 91.452816 113.021865) (end 91.425 113.025) (width 0.15) (layer "In2.Cu") (net 377))
  (segment (start 91.077271 113.277936) (end 91.097063 113.297728) (width 0.15) (layer "In2.Cu") (net 377))
  (segment (start 91.7 113.325) (end 91.733379 113.32876) (width 0.15) (layer "In2.Cu") (net 377))
  (segment (start 91.425 112.425) (end 91.175 112.425) (width 0.15) (layer "In2.Cu") (net 377))
  (segment (start 91.287621 111.754235) (end 91.272728 111.777936) (width 0.15) (layer "In2.Cu") (net 377))
  (segment (start 91.476936 115.147944) (end 91.48441 115.180691) (width 0.15) (layer "In2.Cu") (net 377))
  (segment (start 91.537622 112.195764) (end 91.546866 112.222184) (width 0.15) (layer "In2.Cu") (net 377))
  (segment (start 91.077271 112.077936) (end 91.097063 112.097728) (width 0.15) (layer "In2.Cu") (net 377))
  (segment (start 91.147184 112.121865) (end 91.175 112.125) (width 0.15) (layer "In2.Cu") (net 377))
  (segment (start 91.55 112.3) (end 91.546866 112.327815) (width 0.15) (layer "In2.Cu") (net 377))
  (segment (start 91.062378 114.454235) (end 91.077271 114.477936) (width 0.15) (layer "In2.Cu") (net 377))
  (segment (start 91.817275 113.981476) (end 91.835146 114.009917) (width 0.15) (layer "In2.Cu") (net 377))
  (segment (start 91.175 112.425) (end 91.147184 112.428134) (width 0.15) (layer "In2.Cu") (net 377))
  (segment (start 91.077271 111.872063) (end 91.062378 111.895764) (width 0.15) (layer "In2.Cu") (net 377))
  (segment (start 91.84624 113.508378) (end 91.835146 113.540082) (width 0.15) (layer "In2.Cu") (net 377))
  (segment (start 91.077271 114.272063) (end 91.062378 114.295764) (width 0.15) (layer "In2.Cu") (net 377))
  (segment (start 91.272728 114.572063) (end 91.287621 114.595764) (width 0.15) (layer "In2.Cu") (net 377))
  (segment (start 91.84624 113.441621) (end 91.85 113.475) (width 0.15) (layer "In2.Cu") (net 377))
  (segment (start 91.062378 112.654235) (end 91.077271 112.677936) (width 0.15) (layer "In2.Cu") (net 377))
  (segment (start 91.84624 114.108378) (end 91.835146 114.140082) (width 0.15) (layer "In2.Cu") (net 377))
  (segment (start 92.148685 115.324718) (end 92.15616 115.357466) (width 0.15) (layer "In2.Cu") (net 377))
  (segment (start 91.120764 112.437378) (end 91.097063 112.452271) (width 0.15) (layer "In2.Cu") (net 377))
  (segment (start 91.927299 115.247253) (end 91.957561 115.232678) (width 0.15) (layer "In2.Cu") (net 377))
  (segment (start 92.077814 115.515682) (end 92.056871 115.541942) (width 0.15) (layer "In2.Cu") (net 377))
  (segment (start 91.053134 112.522184) (end 91.05 112.55) (width 0.15) (layer "In2.Cu") (net 377))
  (segment (start 91.522729 112.977936) (end 91.502937 112.997728) (width 0.15) (layer "In2.Cu") (net 377))
  (segment (start 91.84624 114.041621) (end 91.85 114.075) (width 0.15) (layer "In2.Cu") (net 377))
  (segment (start 91.252936 114.552271) (end 91.272728 114.572063) (width 0.15) (layer "In2.Cu") (net 377))
  (segment (start 91.097063 113.652271) (end 91.077271 113.672063) (width 0.15) (layer "In2.Cu") (net 377))
  (segment (start 91.476936 115.247027) (end 91.462362 115.27729) (width 0.15) (layer "In2.Cu") (net 377))
  (segment (start 91.053134 113.122184) (end 91.05 113.15) (width 0.15) (layer "In2.Cu") (net 377))
  (segment (start 91.55 112.9) (end 91.546866 112.927815) (width 0.15) (layer "In2.Cu") (net 377))
  (segment (start 91.147184 113.028134) (end 91.120764 113.037378) (width 0.15) (layer "In2.Cu") (net 377))
  (segment (start 91.077271 113.877936) (end 91.097063 113.897728) (width 0.15) (layer "In2.Cu") (net 377))
  (segment (start 91.8 99.1) (end 91.3 99.6) (width 0.15) (layer "In2.Cu") (net 377))
  (segment (start 91.452816 112.728134) (end 91.479236 112.737378) (width 0.15) (layer "In2.Cu") (net 377))
  (segment (start 91.287621 114.595764) (end 91.296865 114.622184) (width 0.15) (layer "In2.Cu") (net 377))
  (segment (start 91.175 114.225) (end 91.147184 114.228134) (width 0.15) (layer "In2.Cu") (net 377))
  (segment (start 91.793524 113.957725) (end 91.817275 113.981476) (width 0.15) (layer "In2.Cu") (net 377))
  (segment (start 91.479236 112.412621) (end 91.452816 112.421865) (width 0.15) (layer "In2.Cu") (net 377))
  (segment (start 92.042298 115.67129) (end 92.056871 115.701552) (width 0.15) (layer "In2.Cu") (net 377))
  (segment (start 91.062378 112.054235) (end 91.077271 112.077936) (width 0.15) (layer "In2.Cu") (net 377))
  (segment (start 91.546866 112.222184) (end 91.55 112.25) (width 0.15) (layer "In2.Cu") (net 377))
  (segment (start 91.793524 113.592274) (end 91.765083 113.610145) (width 0.15) (layer "In2.Cu") (net 377))
  (segment (start 91.229235 114.537378) (end 91.252936 114.552271) (width 0.15) (layer "In2.Cu") (net 377))
  (segment (start 91.147184 113.921865) (end 91.175 113.925) (width 0.15) (layer "In2.Cu") (net 377))
  (segment (start 91.793524 113.357725) (end 91.817275 113.381476) (width 0.15) (layer "In2.Cu") (net 377))
  (segment (start 91.175 113.625) (end 91.147184 113.628134) (width 0.15) (layer "In2.Cu") (net 377))
  (segment (start 91.48441 115.21428) (end 91.476936 115.247027) (width 0.15) (layer "In2.Cu") (net 377))
  (segment (start 91.097063 114.497728) (end 91.120764 114.512621) (width 0.15) (layer "In2.Cu") (net 377))
  (segment (start 91.3 114.95) (end 91.44142 115.09142) (width 0.15) (layer "In2.Cu") (net 377))
  (segment (start 91.957561 115.232678) (end 91.990308 115.225203) (width 0.15) (layer "In2.Cu") (net 377))
  (segment (start 91.097063 114.252271) (end 91.077271 114.272063) (width 0.15) (layer "In2.Cu") (net 377))
  (segment (start 91.062378 112.495764) (end 91.053134 112.522184) (width 0.15) (layer "In2.Cu") (net 377))
  (segment (start 91.462362 115.117681) (end 91.476936 115.147944) (width 0.15) (layer "In2.Cu") (net 377))
  (segment (start 91.462362 115.27729) (end 91.44142 115.303552) (width 0.15) (layer "In2.Cu") (net 377))
  (segment (start 91.147184 112.428134) (end 91.120764 112.437378) (width 0.15) (layer "In2.Cu") (net 377))
  (segment (start 91.097063 113.297728) (end 91.120764 113.312621) (width 0.15) (layer "In2.Cu") (net 377))
  (segment (start 91.229235 111.812621) (end 91.202815 111.821865) (width 0.15) (layer "In2.Cu") (net 377))
  (segment (start 91.062378 113.095764) (end 91.053134 113.122184) (width 0.15) (layer "In2.Cu") (net 377))
  (segment (start 91.8 99.1) (end 94.015 99.1) (width 0.15) (layer "B.Cu") (net 377))
  (segment (start 120.66 160.89) (end 120.23 161.32) (width 0.15) (layer "F.Cu") (net 380))
  (segment (start 116.5 159.36) (end 116.055001 158.915001) (width 0.15) (layer "F.Cu") (net 380))
  (segment (start 126.05 157.325) (end 126.05 155.75) (width 0.15) (layer "F.Cu") (net 380))
  (segment (start 126.05 155.75) (end 126.05 154.835) (width 0.15) (layer "F.Cu") (net 380))
  (segment (start 117.62 161.32) (end 116.5 160.2) (width 0.15) (layer "F.Cu") (net 380))
  (segment (start 120.23 161.32) (end 117.62 161.32) (width 0.15) (layer "F.Cu") (net 380))
  (segment (start 116.5 160.2) (end 116.5 159.36) (width 0.15) (layer "F.Cu") (net 380))
  (segment (start 116.055001 158.915001) (end 115.270001 158.915001) (width 0.15) (layer "F.Cu") (net 380))
  (via (at 120.66 160.89) (size 0.5) (drill 0.2) (layers "F.Cu" "B.Cu") (net 380))
  (via (at 126.05 155.75) (size 0.5) (drill 0.2) (layers "F.Cu" "B.Cu") (net 380))
  (segment (start 126.05 155.75) (end 126.05 156.77) (width 0.15) (layer "In5.Cu") (net 380))
  (segment (start 126.05 156.77) (end 121.93 160.89) (width 0.15) (layer "In5.Cu") (net 380))
  (segment (start 121.93 160.89) (end 120.66 160.89) (width 0.15) (layer "In5.Cu") (net 380))
  (segment (start 125.55 158.7) (end 125.549997 158.700003) (width 0.15) (layer "F.Cu") (net 381))
  (segment (start 125.55 157.325) (end 125.55 158.7) (width 0.15) (layer "F.Cu") (net 381))
  (segment (start 115.270001 162.8) (end 116.85 162.8) (width 0.15) (layer "F.Cu") (net 381))
  (segment (start 120.230022 161.920022) (end 120.66 162.35) (width 0.15) (layer "F.Cu") (net 381))
  (segment (start 117.729978 161.920022) (end 120.230022 161.920022) (width 0.15) (layer "F.Cu") (net 381))
  (segment (start 116.85 162.8) (end 117.729978 161.920022) (width 0.15) (layer "F.Cu") (net 381))
  (via (at 120.66 162.35) (size 0.5) (drill 0.2) (layers "F.Cu" "B.Cu") (net 381))
  (via (at 125.549997 158.700003) (size 0.5) (drill 0.2) (layers "F.Cu" "B.Cu") (net 381))
  (segment (start 121.89 162.35) (end 125.539997 158.700003) (width 0.15) (layer "In5.Cu") (net 381))
  (segment (start 120.66 162.35) (end 121.89 162.35) (width 0.15) (layer "In5.Cu") (net 381))
  (segment (start 70.125 85.475) (end 69.7 85.05) (width 0.15) (layer "F.Cu") (net 385))
  (segment (start 70.3 85.475) (end 70.125 85.475) (width 0.15) (layer "F.Cu") (net 385))
  (segment (start 85.415 140.565) (end 85.4 140.55) (width 0.2) (layer "F.Cu") (net 385))
  (segment (start 86.25 140.565) (end 85.415 140.565) (width 0.2) (layer "F.Cu") (net 385))
  (via (at 68.05 86) (size 0.5) (drill 0.2) (layers "F.Cu" "B.Cu") (net 385))
  (via (at 85.4 140.55) (size 0.5) (drill 0.2) (layers "F.Cu" "B.Cu") (net 385))
  (via (at 74.4 90.3) (size 0.5) (drill 0.2) (layers "F.Cu" "B.Cu") (net 385))
  (via (at 80.3 141.65) (size 0.5) (drill 0.2) (layers "F.Cu" "B.Cu") (net 385))
  (via (at 69.7 85.05) (size 0.5) (drill 0.2) (layers "F.Cu" "B.Cu") (net 385))
  (segment (start 68.4 87.2) (end 71.3 87.2) (width 0.15) (layer "In5.Cu") (net 385))
  (segment (start 71.3 87.2) (end 74.4 90.3) (width 0.15) (layer "In5.Cu") (net 385))
  (segment (start 68.05 86) (end 68.05 86.85) (width 0.15) (layer "In5.Cu") (net 385))
  (segment (start 80.9 140.85) (end 85.1 140.85) (width 0.2) (layer "In5.Cu") (net 385))
  (segment (start 68.05 86.85) (end 68.4 87.2) (width 0.15) (layer "In5.Cu") (net 385))
  (segment (start 80.3 141.45) (end 80.9 140.85) (width 0.2) (layer "In5.Cu") (net 385))
  (segment (start 85.1 140.85) (end 85.4 140.55) (width 0.2) (layer "In5.Cu") (net 385))
  (segment (start 80.3 141.65) (end 80.3 141.45) (width 0.2) (layer "In5.Cu") (net 385))
  (segment (start 78.9 93.3) (end 78.9 114) (width 0.2) (layer "B.Cu") (net 385))
  (segment (start 76.5 90.3) (end 78.9 92.7) (width 0.2) (layer "B.Cu") (net 385))
  (segment (start 74.95 117.95) (end 74.65 117.95) (width 0.2) (layer "B.Cu") (net 385))
  (segment (start 78.9 92.7) (end 78.9 93.3) (width 0.2) (layer "B.Cu") (net 385))
  (segment (start 75.05 119.6) (end 75.05 141.05) (width 0.2) (layer "B.Cu") (net 385))
  (segment (start 74.3 118.85) (end 75.05 119.6) (width 0.2) (layer "B.Cu") (net 385))
  (segment (start 78.9 114) (end 74.95 117.95) (width 0.2) (layer "B.Cu") (net 385))
  (segment (start 74.4 90.3) (end 76.5 90.3) (width 0.2) (layer "B.Cu") (net 385))
  (segment (start 78.865 93.265) (end 78.9 93.3) (width 0.2) (layer "B.Cu") (net 385))
  (segment (start 77.65 93.265) (end 78.865 93.265) (width 0.2) (layer "B.Cu") (net 385))
  (segment (start 75.05 141.05) (end 75.65 141.65) (width 0.2) (layer "B.Cu") (net 385))
  (segment (start 68.75 86) (end 69.7 85.05) (width 0.15) (layer "B.Cu") (net 385))
  (segment (start 66.2 86) (end 68.75 86) (width 0.15) (layer "B.Cu") (net 385))
  (segment (start 74.3 118.3) (end 74.3 118.85) (width 0.2) (layer "B.Cu") (net 385))
  (segment (start 74.65 117.95) (end 74.3 118.3) (width 0.2) (layer "B.Cu") (net 385))
  (segment (start 75.65 141.65) (end 80.3 141.65) (width 0.2) (layer "B.Cu") (net 385))
  (segment (start 125.6 64.375) (end 125.6 66.15) (width 0.2) (layer "F.Cu") (net 388))
  (segment (start 125.6 66.15) (end 124.95 66.8) (width 0.2) (layer "F.Cu") (net 388))
  (segment (start 70.8 87.1) (end 72.2 85.7) (width 0.15) (layer "B.Cu") (net 394))
  (segment (start 64.735 86.7) (end 67 86.7) (width 0.15) (layer "B.Cu") (net 394))
  (segment (start 72.2 85.7) (end 72.2 85.1) (width 0.15) (layer "B.Cu") (net 394))
  (segment (start 67 86.7) (end 67.4 87.1) (width 0.15) (layer "B.Cu") (net 394))
  (segment (start 67.4 87.1) (end 70.8 87.1) (width 0.15) (layer "B.Cu") (net 394))
  (segment (start 64.735 85.05) (end 68.2 85.05) (width 0.15) (layer "B.Cu") (net 395))
  (segment (start 70.15 94.275) (end 69.45 94.975) (width 0.15) (layer "B.Cu") (net 396))
  (segment (start 69.45 94.975) (end 64.675 94.975) (width 0.15) (layer "B.Cu") (net 396))
  (segment (start 70.15 93.3) (end 70.15 94.275) (width 0.15) (layer "B.Cu") (net 396))
  (segment (start 64.735 93.3) (end 66.075 93.3) (width 0.2) (layer "B.Cu") (net 397))
  (segment (start 69.15 90.8) (end 70.15 89.8) (width 0.15) (layer "B.Cu") (net 398))
  (segment (start 68.7 90.8) (end 69.15 90.8) (width 0.15) (layer "B.Cu") (net 398))
  (segment (start 70.15 89.8) (end 70.15 89.175) (width 0.15) (layer "B.Cu") (net 398))
  (segment (start 68 91.5) (end 68.7 90.8) (width 0.15) (layer "B.Cu") (net 398))
  (segment (start 64.885 91.5) (end 68 91.5) (width 0.15) (layer "B.Cu") (net 398))
  (via (at 69.55 91.7) (size 0.5) (drill 0.2) (layers "F.Cu" "B.Cu") (net 399))
  (via (at 67.65 91) (size 0.5) (drill 0.2) (layers "F.Cu" "B.Cu") (net 399))
  (segment (start 68.35 91.7) (end 69.55 91.7) (width 0.15) (layer "In5.Cu") (net 399))
  (segment (start 67.65 91) (end 68.35 91.7) (width 0.15) (layer "In5.Cu") (net 399))
  (segment (start 69.55 91.7) (end 70.1 91.7) (width 0.15) (layer "B.Cu") (net 399))
  (segment (start 70.1 91.7) (end 71.7 93.3) (width 0.15) (layer "B.Cu") (net 399))
  (segment (start 66.6 89.95) (end 64.735 89.95) (width 0.15) (layer "B.Cu") (net 399))
  (segment (start 67.65 91) (end 66.6 89.95) (width 0.15) (layer "B.Cu") (net 399))
  (segment (start 71.7 93.3) (end 74.1 93.3) (width 0.15) (layer "B.Cu") (net 399))
  (segment (start 64.735 88.35) (end 64.735 88.86) (width 0.15) (layer "B.Cu") (net 400))
  (segment (start 64.975 89.1) (end 66.2 89.1) (width 0.15) (layer "B.Cu") (net 400))
  (segment (start 64.735 88.86) (end 64.975 89.1) (width 0.15) (layer "B.Cu") (net 400))
  (segment (start 71.84 164.16) (end 75.505 164.16) (width 0.15) (layer "F.Cu") (net 401))
  (segment (start 106.627149 93.7) (end 108.365 93.7) (width 0.1) (layer "F.Cu") (net 402))
  (segment (start 92.8 97.1) (end 93.3 97.6) (width 0.15) (layer "F.Cu") (net 403))
  (via (at 92.8 97.1) (size 0.5) (drill 0.2) (layers "F.Cu" "B.Cu") (net 403))
  (segment (start 94.08 97.1) (end 92.8 97.1) (width 0.15) (layer "B.Cu") (net 403))
  (segment (start 128.4 126.85) (end 127.4 126.85) (width 0.2) (layer "F.Cu") (net 404))
  (via (at 128.4 126.85) (size 0.5) (drill 0.2) (layers "F.Cu" "B.Cu") (net 404))
  (segment (start 127.425 125.11) (end 127.425 125.875) (width 0.2) (layer "B.Cu") (net 404))
  (segment (start 127.425 125.875) (end 128.4 126.85) (width 0.2) (layer "B.Cu") (net 404))
  (segment (start 126.705 129.045) (end 126.705 130.53) (width 0.2) (layer "F.Cu") (net 405))
  (segment (start 125.235 113.365) (end 125.235 112.66) (width 0.2) (layer "F.Cu") (net 406))
  (segment (start 125.235 112.66) (end 124.975 112.4) (width 0.2) (layer "F.Cu") (net 406))
  (via (at 124.975 112.4) (size 0.5) (drill 0.2) (layers "F.Cu" "B.Cu") (net 406))
  (segment (start 124.74 111.425) (end 124.74 112.165) (width 0.2) (layer "B.Cu") (net 406))
  (segment (start 124.74 112.165) (end 124.975 112.4) (width 0.2) (layer "B.Cu") (net 406))
  (segment (start 127.42 114.05) (end 129.25 114.05) (width 0.2) (layer "F.Cu") (net 407))
  (segment (start 72.75 118.15) (end 72.5 118.15) (width 0.15) (layer "F.Cu") (net 408))
  (segment (start 73.32 118.72) (end 72.75 118.15) (width 0.15) (layer "F.Cu") (net 408))
  (segment (start 73.32 119.4325) (end 73.32 118.72) (width 0.15) (layer "F.Cu") (net 408))
  (segment (start 78.577 158.75802) (end 78.577 159.75712) (width 0.15) (layer "F.Cu") (net 409))
  (segment (start 91.500054 109.250054) (end 91.500053 108.200053) (width 0.15) (layer "F.Cu") (net 409))
  (segment (start 92 109.75) (end 91.500054 109.250054) (width 0.15) (layer "F.Cu") (net 409))
  (segment (start 91.500053 108.200053) (end 88.775 105.475) (width 0.15) (layer "F.Cu") (net 409))
  (segment (start 88.775 105.475) (end 88.225 105.475) (width 0.15) (layer "F.Cu") (net 409))
  (via (at 78.577 159.75712) (size 0.5) (drill 0.2) (layers "F.Cu" "B.Cu") (net 409))
  (via (at 88.225 105.4625) (size 0.5) (drill 0.2) (layers "F.Cu" "B.Cu") (net 409))
  (segment (start 68.24994 126.121342) (end 73.42494 131.29634) (width 0.15) (layer "In2.Cu") (net 409))
  (segment (start 77.69998 151.351098) (end 76.604698 151.351098) (width 0.15) (layer "In2.Cu") (net 409))
  (segment (start 68.24994 110.403658) (end 71.203658 107.44994) (width 0.15) (layer "In2.Cu") (net 409))
  (segment (start 78.577 152.702) (end 78.075 152.2) (width 0.15) (layer "In2.Cu") (net 409))
  (segment (start 85.6875 105.4625) (end 88.225 105.4625) (width 0.15) (layer "In2.Cu") (net 409))
  (segment (start 68.24994 126.121342) (end 68.24994 110.403658) (width 0.15) (layer "In2.Cu") (net 409))
  (segment (start 78.577 159.75712) (end 78.577 152.702) (width 0.15) (layer "In2.Cu") (net 409))
  (segment (start 76.604698 151.351098) (end 73.42494 148.171342) (width 0.15) (layer "In2.Cu") (net 409))
  (segment (start 78.075 152.2) (end 78.075 151.726118) (width 0.15) (layer "In2.Cu") (net 409))
  (segment (start 73.42494 148.171342) (end 73.42494 131.29634) (width 0.15) (layer "In2.Cu") (net 409))
  (segment (start 78.075 151.726118) (end 77.69998 151.351098) (width 0.15) (layer "In2.Cu") (net 409))
  (segment (start 83.70006 107.44994) (end 85.6875 105.4625) (width 0.15) (layer "In2.Cu") (net 409))
  (segment (start 71.203658 107.44994) (end 83.70006 107.44994) (width 0.15) (layer "In2.Cu") (net 409))
  (segment (start 92.8 107.375) (end 94.85 105.325) (width 0.1) (layer "F.Cu") (net 410))
  (segment (start 92.8 108.15) (end 92.8 107.375) (width 0.1) (layer "F.Cu") (net 410))
  (segment (start 94.85 105.325) (end 95.6 105.325) (width 0.1) (layer "F.Cu") (net 410))
  (via (at 95.6 105.325) (size 0.5) (drill 0.2) (layers "F.Cu" "B.Cu") (net 410))
  (segment (start 64.62 98.21) (end 68.380021 94.449979) (width 0.1) (layer "In5.Cu") (net 410))
  (segment (start 78.007693 94.449979) (end 79.875 96.317286) (width 0.1) (layer "In5.Cu") (net 410))
  (segment (start 79.875 100.975) (end 82.100001 103.200001) (width 0.1) (layer "In5.Cu") (net 410))
  (segment (start 79.875 96.317286) (end 79.875 100.975) (width 0.1) (layer "In5.Cu") (net 410))
  (segment (start 82.100001 103.200001) (end 90.175001 103.200001) (width 0.1) (layer "In5.Cu") (net 410))
  (segment (start 68.380021 94.449979) (end 78.007693 94.449979) (width 0.1) (layer "In5.Cu") (net 410))
  (segment (start 90.175001 103.200001) (end 92.3 105.325) (width 0.1) (layer "In5.Cu") (net 410))
  (segment (start 92.3 105.325) (end 95.6 105.325) (width 0.1) (layer "In5.Cu") (net 410))
  (segment (start 95 106.15) (end 95.6 106.15) (width 0.1) (layer "F.Cu") (net 411))
  (segment (start 93.6 107.55) (end 95 106.15) (width 0.1) (layer "F.Cu") (net 411))
  (segment (start 93.6 108.15) (end 93.6 107.55) (width 0.1) (layer "F.Cu") (net 411))
  (via (at 95.6 106.133333) (size 0.5) (drill 0.2) (layers "F.Cu" "B.Cu") (net 411))
  (segment (start 70.72001 94.64999) (end 77.924846 94.64999) (width 0.1) (layer "In5.Cu") (net 411))
  (segment (start 79.674989 101.057845) (end 82.067144 103.45) (width 0.1) (layer "In5.Cu") (net 411))
  (segment (start 67.16 98.21) (end 70.72001 94.64999) (width 0.1) (layer "In5.Cu") (net 411))
  (segment (start 92.783333 106.133333) (end 90.1 103.45) (width 0.1) (layer "In5.Cu") (net 411))
  (segment (start 79.674989 96.400133) (end 79.674989 101.057845) (width 0.1) (layer "In5.Cu") (net 411))
  (segment (start 77.924846 94.64999) (end 79.674989 96.400133) (width 0.1) (layer "In5.Cu") (net 411))
  (segment (start 82.067144 103.45) (end 90.1 103.45) (width 0.1) (layer "In5.Cu") (net 411))
  (segment (start 95.6 106.133333) (end 92.783333 106.133333) (width 0.1) (layer "In5.Cu") (net 411))
  (segment (start 95.15 106.95) (end 95.6 106.95) (width 0.1) (layer "F.Cu") (net 412))
  (segment (start 94.4 108.15) (end 94.4 107.7) (width 0.1) (layer "F.Cu") (net 412))
  (segment (start 94.4 107.7) (end 95.15 106.95) (width 0.1) (layer "F.Cu") (net 412))
  (via (at 95.6 106.941666) (size 0.5) (drill 0.2) (layers "F.Cu" "B.Cu") (net 412))
  (segment (start 73.059999 94.850001) (end 77.841999 94.850001) (width 0.1) (layer "In5.Cu") (net 412))
  (segment (start 77.841999 94.850001) (end 79.47498 96.482982) (width 0.1) (layer "In5.Cu") (net 412))
  (segment (start 95.6 106.941666) (end 93.30881 106.941666) (width 0.1) (layer "In5.Cu") (net 412))
  (segment (start 79.47498 96.482982) (end 79.47498 101.140692) (width 0.1) (layer "In5.Cu") (net 412))
  (segment (start 93.30881 106.941666) (end 90.017144 103.65) (width 0.1) (layer "In5.Cu") (net 412))
  (segment (start 79.47498 101.140692) (end 81.984296 103.650008) (width 0.1) (layer "In5.Cu") (net 412))
  (segment (start 81.967144 103.65) (end 90.017144 103.65) (width 0.1) (layer "In5.Cu") (net 412))
  (segment (start 69.7 98.21) (end 73.059999 94.850001) (width 0.1) (layer "In5.Cu") (net 412))
  (segment (start 95.2 108.15) (end 95.6 107.75) (width 0.15) (layer "F.Cu") (net 413))
  (via (at 95.6 107.75) (size 0.5) (drill 0.2) (layers "F.Cu" "B.Cu") (net 413))
  (segment (start 95.6 107.75) (end 93.834288 107.75) (width 0.1) (layer "In5.Cu") (net 413))
  (segment (start 93.834288 107.75) (end 89.934298 103.85001) (width 0.1) (layer "In5.Cu") (net 413))
  (segment (start 79.274969 101.240681) (end 81.884298 103.85001) (width 0.1) (layer "In5.Cu") (net 413))
  (segment (start 79.274969 96.599969) (end 79.274969 101.240681) (width 0.1) (layer "In5.Cu") (net 413))
  (segment (start 74.725 95.725) (end 78.4 95.725) (width 0.1) (layer "In5.Cu") (net 413))
  (segment (start 81.884298 103.85001) (end 89.934298 103.85001) (width 0.1) (layer "In5.Cu") (net 413))
  (segment (start 72.24 98.21) (end 74.725 95.725) (width 0.1) (layer "In5.Cu") (net 413))
  (segment (start 78.4 95.725) (end 79.274969 96.599969) (width 0.1) (layer "In5.Cu") (net 413))
  (segment (start 114.09 177.345) (end 114.09 168.074514) (width 0.25) (layer "F.Cu") (net 414))
  (segment (start 143.75 151.52) (end 143.75 153.68) (width 0.25) (layer "F.Cu") (net 414))
  (segment (start 114.09 168.074514) (end 115.314514 166.85) (width 0.25) (layer "F.Cu") (net 414))
  (segment (start 143.75 153.68) (end 143.21 154.22) (width 0.25) (layer "F.Cu") (net 414))
  (via (at 115.314514 166.85) (size 0.5) (drill 0.2) (layers "F.Cu" "B.Cu") (net 414))
  (via (at 143.21 154.22) (size 0.5) (drill 0.2) (layers "F.Cu" "B.Cu") (net 414))
  (segment (start 115.314514 166.85) (end 116.514515 165.649999) (width 0.25) (layer "In5.Cu") (net 414))
  (segment (start 130.500001 165.649999) (end 141.93 154.22) (width 0.25) (layer "In5.Cu") (net 414))
  (segment (start 116.514515 165.649999) (end 130.500001 165.649999) (width 0.25) (layer "In5.Cu") (net 414))
  (segment (start 141.93 154.22) (end 143.21 154.22) (width 0.25) (layer "In5.Cu") (net 414))
  (segment (start 127.55 70.1) (end 139.75 82.3) (width 0.2) (layer "F.Cu") (net 415))
  (segment (start 127.55 64.375) (end 127.55 70.1) (width 0.2) (layer "F.Cu") (net 415))
  (via (at 139.75 82.275) (size 0.5) (drill 0.2) (layers "F.Cu" "B.Cu") (net 415))
  (segment (start 139.75 82.275) (end 139.75 83.125) (width 0.2) (layer "B.Cu") (net 415))
  (segment (start 139.75 83.155) (end 140.8 83.155) (width 0.2) (layer "B.Cu") (net 415))
  (segment (start 138.67 83.155) (end 139.75 83.155) (width 0.2) (layer "B.Cu") (net 415))
  (segment (start 134.85 82.575) (end 135.4 82.025) (width 0.2) (layer "B.Cu") (net 415))
  (segment (start 134.85 83.19) (end 134.85 82.575) (width 0.2) (layer "B.Cu") (net 415))
  (segment (start 138.1 82.025) (end 138.65 82.575) (width 0.2) (layer "B.Cu") (net 415))
  (segment (start 135.4 82.025) (end 138.1 82.025) (width 0.2) (layer "B.Cu") (net 415))
  (segment (start 138.65 82.575) (end 138.65 83.175) (width 0.2) (layer "B.Cu") (net 415))
  (segment (start 139.75 82.3) (end 139.75 83.15) (width 0.2) (layer "B.Cu") (net 415))
  (segment (start 126.9 64.375) (end 126.9 71.625) (width 0.2) (layer "F.Cu") (net 416))
  (segment (start 126.9 71.625) (end 137 81.725) (width 0.2) (layer "F.Cu") (net 416))
  (segment (start 137 81.725) (end 137 86.1) (width 0.2) (layer "F.Cu") (net 416))
  (segment (start 126.25 64.375) (end 126.25 65.725) (width 0.2) (layer "F.Cu") (net 417))
  (segment (start 126.25 65.725) (end 126.5 65.975) (width 0.2) (layer "F.Cu") (net 417))
  (segment (start 126.5 65.975) (end 126.5 71.8) (width 0.2) (layer "F.Cu") (net 417))
  (segment (start 126.5 71.8) (end 136.5 81.8) (width 0.2) (layer "F.Cu") (net 417))
  (segment (start 136.5 81.8) (end 136.5 86.1) (width 0.2) (layer "F.Cu") (net 417))
  (segment (start 81.105 121.34) (end 80.705 121.74) (width 0.15) (layer "F.Cu") (net 418))
  (via (at 80.705 121.74) (size 0.5) (drill 0.2) (layers "F.Cu" "B.Cu") (net 418))
  (via (at 79.15 122.45) (size 0.5) (drill 0.2) (layers "F.Cu" "B.Cu") (net 418))
  (segment (start 80.705 121.74) (end 79.86 121.74) (width 0.15) (layer "In2.Cu") (net 418))
  (segment (start 79.86 121.74) (end 79.15 122.45) (width 0.15) (layer "In2.Cu") (net 418))
  (segment (start 79.1 122.5) (end 79.15 122.45) (width 0.15) (layer "B.Cu") (net 418))
  (segment (start 79.1 123.195) (end 79.1 122.5) (width 0.15) (layer "B.Cu") (net 418))
  (segment (start 76.7 77.5) (end 74.874143 77.5) (width 0.25) (layer "F.Cu") (net 419))
  (segment (start 73.65 77.75) (end 73.15 77.75) (width 0.15) (layer "F.Cu") (net 419))
  (segment (start 79.25 74.235) (end 79.25 74.9) (width 0.2) (layer "F.Cu") (net 419))
  (segment (start 74.849143 77.475) (end 73.925 77.475) (width 0.15) (layer "F.Cu") (net 419))
  (segment (start 73.925 77.475) (end 73.65 77.75) (width 0.15) (layer "F.Cu") (net 419))
  (via (at 76.7 77.5) (size 0.5) (drill 0.2) (layers "F.Cu" "B.Cu") (net 419))
  (via (at 79.25 74.9) (size 0.5) (drill 0.2) (layers "F.Cu" "B.Cu") (net 419))
  (segment (start 76.7 77.5) (end 77.65 77.5) (width 0.2) (layer "B.Cu") (net 419))
  (segment (start 79.25 75.9) (end 79.25 74.9) (width 0.2) (layer "B.Cu") (net 419))
  (segment (start 77.65 77.5) (end 79.25 75.9) (width 0.2) (layer "B.Cu") (net 419))
  (segment (start 74.849143 76.825) (end 73.325 76.825) (width 0.15) (layer "F.Cu") (net 420))
  (segment (start 78.25 74.65) (end 76.075 76.825) (width 0.2) (layer "F.Cu") (net 420))
  (segment (start 76.075 76.825) (end 74.849143 76.825) (width 0.2) (layer "F.Cu") (net 420))
  (segment (start 78.25 74.235) (end 78.25 74.65) (width 0.2) (layer "F.Cu") (net 420))
  (segment (start 73.55 75.8) (end 73.3 75.8) (width 0.15) (layer "F.Cu") (net 422))
  (segment (start 74.849143 76.175) (end 73.925 76.175) (width 0.15) (layer "F.Cu") (net 422))
  (segment (start 73.925 76.175) (end 73.55 75.8) (width 0.15) (layer "F.Cu") (net 422))
  (segment (start 77.25 75) (end 77.25 74.235) (width 0.2) (layer "F.Cu") (net 422))
  (segment (start 76.075 76.175) (end 77.25 75) (width 0.2) (layer "F.Cu") (net 422))
  (segment (start 74.849143 76.175) (end 76.075 76.175) (width 0.2) (layer "F.Cu") (net 422))
  (segment (start 94.25 63) (end 94.25 62.25) (width 0.25) (layer "F.Cu") (net 423))
  (segment (start 93.875001 63.374999) (end 94.25 63) (width 0.25) (layer "F.Cu") (net 423))
  (segment (start 93.875001 64.550001) (end 93.875001 63.374999) (width 0.25) (layer "F.Cu") (net 423))
  (segment (start 91.995 128.935) (end 91.595 129.335) (width 0.15) (layer "F.Cu") (net 427))
  (via (at 91.595 129.335) (size 0.5) (drill 0.2) (layers "F.Cu" "B.Cu") (net 427))
  (segment (start 86.4 134.53) (end 86.4 135.1) (width 0.15) (layer "B.Cu") (net 427))
  (segment (start 91.595 129.335) (end 86.4 134.53) (width 0.15) (layer "B.Cu") (net 427))
  (segment (start 91.605528 130.124472) (end 91.605528 130.145528) (width 0.15) (layer "F.Cu") (net 428))
  (segment (start 91.995 129.735) (end 91.605528 130.124472) (width 0.15) (layer "F.Cu") (net 428))
  (via (at 91.605528 130.145528) (size 0.5) (drill 0.2) (layers "F.Cu" "B.Cu") (net 428))
  (segment (start 87.45 134.301056) (end 87.45 135.15) (width 0.15) (layer "B.Cu") (net 428))
  (segment (start 91.605528 130.145528) (end 87.45 134.301056) (width 0.15) (layer "B.Cu") (net 428))
  (segment (start 91.995 131.335) (end 91.595 131.735) (width 0.15) (layer "F.Cu") (net 429))
  (segment (start 91.595 131.735) (end 91.54999 131.735) (width 0.15) (layer "F.Cu") (net 429))
  (via (at 91.54999 131.735) (size 0.5) (drill 0.2) (layers "F.Cu" "B.Cu") (net 429))
  (segment (start 91.54999 131.735) (end 91.415 131.735) (width 0.15) (layer "B.Cu") (net 429))
  (segment (start 91.415 131.735) (end 89.55 133.6) (width 0.15) (layer "B.Cu") (net 429))
  (segment (start 89.55 133.6) (end 89.55 135.1) (width 0.15) (layer "B.Cu") (net 429))
  (segment (start 91.995 130.535) (end 91.595 130.935) (width 0.15) (layer "F.Cu") (net 431))
  (via (at 91.595 130.935) (size 0.5) (drill 0.2) (layers "F.Cu" "B.Cu") (net 431))
  (segment (start 91.595 130.935) (end 88.5 134.03) (width 0.15) (layer "B.Cu") (net 431))
  (segment (start 88.5 134.03) (end 88.5 135.1) (width 0.15) (layer "B.Cu") (net 431))
  (segment (start 135 86.0875) (end 135 85.175) (width 0.15) (layer "F.Cu") (net 432))
  (via (at 135 85.175) (size 0.5) (drill 0.2) (layers "F.Cu" "B.Cu") (net 432))
  (segment (start 133.1 85.84) (end 134.085 85.84) (width 0.2) (layer "B.Cu") (net 432))
  (segment (start 134.085 85.84) (end 134.085 85.39) (width 0.2) (layer "B.Cu") (net 432))
  (segment (start 134.3 85.175) (end 135 85.175) (width 0.2) (layer "B.Cu") (net 432))
  (segment (start 134.085 85.39) (end 134.3 85.175) (width 0.2) (layer "B.Cu") (net 432))
  (segment (start 134.85 85.025) (end 135 85.175) (width 0.2) (layer "B.Cu") (net 432))
  (segment (start 134.85 84.16) (end 134.85 85.025) (width 0.2) (layer "B.Cu") (net 432))
  (segment (start 137.5 86.0875) (end 137.5 85.125) (width 0.15) (layer "F.Cu") (net 433))
  (via (at 137.5 85.125) (size 0.5) (drill 0.2) (layers "F.Cu" "B.Cu") (net 433))
  (segment (start 137.1 85.525) (end 137.5 85.125) (width 0.2) (layer "B.Cu") (net 433))
  (segment (start 137.1 85.84) (end 137.1 85.525) (width 0.2) (layer "B.Cu") (net 433))
  (segment (start 140.6875 88.275) (end 141.55 88.275) (width 0.15) (layer "F.Cu") (net 434))
  (segment (start 141.55 88.275) (end 141.65 88.375) (width 0.15) (layer "F.Cu") (net 434))
  (via (at 141.65 88.375) (size 0.5) (drill 0.2) (layers "F.Cu" "B.Cu") (net 434))
  (segment (start 141.65 88.375) (end 140.95 88.375) (width 0.2) (layer "B.Cu") (net 434))
  (segment (start 141.65 88.375) (end 142.65 87.375) (width 0.2) (layer "B.Cu") (net 434))
  (segment (start 142.65 87.375) (end 142.65 86.25) (width 0.2) (layer "B.Cu") (net 434))
  (segment (start 142.65 86.25) (end 141.02 84.62) (width 0.2) (layer "B.Cu") (net 434))
  (segment (start 141.02 84.62) (end 140.483561 84.62) (width 0.2) (layer "B.Cu") (net 434))
  (segment (start 140.483561 84.62) (end 140.28 84.416439) (width 0.2) (layer "B.Cu") (net 434))
  (segment (start 140.28 84.416439) (end 140.28 84.125) (width 0.2) (layer "B.Cu") (net 434))
  (segment (start 140.28 84.125) (end 139.85 84.125) (width 0.2) (layer "B.Cu") (net 434))
  (segment (start 140.6875 87.775) (end 141.25 87.775) (width 0.15) (layer "F.Cu") (net 435))
  (segment (start 141.25 87.775) (end 141.6 87.425) (width 0.15) (layer "F.Cu") (net 435))
  (segment (start 141.6 87.425) (end 141.6 85.275) (width 0.15) (layer "F.Cu") (net 435))
  (segment (start 141.6 85.275) (end 141 84.675) (width 0.15) (layer "F.Cu") (net 435))
  (segment (start 134 93.9625) (end 134 95.15) (width 0.2) (layer "F.Cu") (net 436))
  (segment (start 134 95.15) (end 135.2 96.35) (width 0.2) (layer "F.Cu") (net 436))
  (segment (start 135.2 96.35) (end 137.825 96.35) (width 0.2) (layer "F.Cu") (net 436))
  (segment (start 84.975 106.125) (end 83.1 106.125) (width 0.15) (layer "F.Cu") (net 437))
  (segment (start 89.3 98.6) (end 88.8 99.1) (width 0.15) (layer "F.Cu") (net 437))
  (segment (start 88.8 102.3) (end 84.975 106.125) (width 0.15) (layer "F.Cu") (net 437))
  (segment (start 88.8 99.1) (end 88.8 102.3) (width 0.15) (layer "F.Cu") (net 437))
  (segment (start 141.9 83.825) (end 143.4 85.325) (width 0.2) (layer "F.Cu") (net 511))
  (segment (start 143.4 85.325) (end 143.4 86.1) (width 0.2) (layer "F.Cu") (net 511))
  (segment (start 140.45 83.825) (end 141.9 83.825) (width 0.2) (layer "F.Cu") (net 511))
  (segment (start 139 86.0875) (end 139 85.275) (width 0.2) (layer "F.Cu") (net 511))
  (segment (start 139 85.275) (end 140.45 83.825) (width 0.2) (layer "F.Cu") (net 511))
  (segment (start 139.5 86.0875) (end 139.5 85.425) (width 0.15) (layer "F.Cu") (net 657))
  (segment (start 139.5 85.425) (end 139.75 85.175) (width 0.15) (layer "F.Cu") (net 657))
  (segment (start 140.6875 93.275) (end 141.1 93.275) (width 0.15) (layer "F.Cu") (net 657))
  (segment (start 141.1 93.275) (end 141.55 93.725) (width 0.15) (layer "F.Cu") (net 657))
  (segment (start 134.5 93.9625) (end 134.5 94.775) (width 0.15) (layer "F.Cu") (net 657))
  (via (at 139.75 85.175) (size 0.5) (drill 0.2) (layers "F.Cu" "B.Cu") (net 657))
  (via (at 141.55 93.725) (size 0.5) (drill 0.2) (layers "F.Cu" "B.Cu") (net 657))
  (via (at 134.5 94.775) (size 0.5) (drill 0.2) (layers "F.Cu" "B.Cu") (net 657))
  (via (at 140.9 86.025) (size 0.5) (drill 0.2) (layers "F.Cu" "B.Cu") (net 657))
  (segment (start 134.5 94.775) (end 134.5 93.425) (width 0.2) (layer "B.Cu") (net 657))
  (segment (start 134.5 93.425) (end 134.85 93.075) (width 0.2) (layer "B.Cu") (net 657))
  (segment (start 134.85 93.075) (end 140.1 93.075) (width 0.2) (layer "B.Cu") (net 657))
  (segment (start 140.1 93.075) (end 140.8 93.775) (width 0.2) (layer "B.Cu") (net 657))
  (segment (start 141.55 93.725) (end 140.85 93.725) (width 0.2) (layer "B.Cu") (net 657))
  (segment (start 140.1 85.84) (end 140.715 85.84) (width 0.2) (layer "B.Cu") (net 657))
  (segment (start 140.715 85.84) (end 140.9 86.025) (width 0.2) (layer "B.Cu") (net 657))
  (segment (start 140.1 85.525) (end 139.75 85.175) (width 0.2) (layer "B.Cu") (net 657))
  (segment (start 140.1 85.84) (end 140.1 85.525) (width 0.2) (layer "B.Cu") (net 657))
  (segment (start 79.572 154.34712) (end 79.572 151.85212) (width 0.15) (layer "F.Cu") (net 659))
  (segment (start 91.7 110.55) (end 91.000037 109.850037) (width 0.15) (layer "F.Cu") (net 659))
  (segment (start 88.271473 106.475) (end 88.225 106.475) (width 0.15) (layer "F.Cu") (net 659))
  (segment (start 88.86827 106.475) (end 91.000037 108.606767) (width 0.15) (layer "F.Cu") (net 659))
  (segment (start 88.225 106.475) (end 88.86827 106.475) (width 0.15) (layer "F.Cu") (net 659))
  (segment (start 91.000037 109.850037) (end 91.000037 108.606767) (width 0.15) (layer "F.Cu") (net 659))
  (segment (start 92 110.55) (end 91.7 110.55) (width 0.15) (layer "F.Cu") (net 659))
  (via (at 79.552 151.83212) (size 0.5) (drill 0.2) (layers "F.Cu" "B.Cu") (net 659))
  (via (at 88.375 106.475) (size 0.5) (drill 0.2) (layers "F.Cu" "B.Cu") (net 659))
  (segment (start 85.382134 106.475) (end 83.907174 107.94996) (width 0.15) (layer "In2.Cu") (net 659))
  (segment (start 73.92496 147.964228) (end 73.92496 131.089228) (width 0.15) (layer "In2.Cu") (net 659))
  (segment (start 88.375 106.475) (end 85.382134 106.475) (width 0.15) (layer "In2.Cu") (net 659))
  (segment (start 79.552 151.5645) (end 78.8125 150.825) (width 0.15) (layer "In2.Cu") (net 659))
  (segment (start 71.410772 107.94996) (end 83.907174 107.94996) (width 0.15) (layer "In2.Cu") (net 659))
  (segment (start 73.92496 147.964228) (end 76.785734 150.825) (width 0.15) (layer "In2.Cu") (net 659))
  (segment (start 79.552 151.83212) (end 79.552 151.5645) (width 0.15) (layer "In2.Cu") (net 659))
  (segment (start 76.785734 150.825) (end 78.8125 150.825) (width 0.15) (layer "In2.Cu") (net 659))
  (segment (start 68.74996 110.610772) (end 71.410772 107.94996) (width 0.15) (layer "In2.Cu") (net 659))
  (segment (start 73.92496 131.089228) (end 68.74996 125.914228) (width 0.15) (layer "In2.Cu") (net 659))
  (segment (start 68.74996 125.914228) (end 68.74996 110.610772) (width 0.15) (layer "In2.Cu") (net 659))
  (segment (start 80.072 154.34712) (end 80.072 152.25212) (width 0.15) (layer "F.Cu") (net 660))
  (segment (start 87.75 106.95) (end 88.989702 106.95) (width 0.15) (layer "F.Cu") (net 660))
  (segment (start 90.750029 110.125029) (end 91.599999 110.974999) (width 0.15) (layer "F.Cu") (net 660))
  (segment (start 90.750029 108.710325) (end 90.750029 110.125029) (width 0.15) (layer "F.Cu") (net 660))
  (segment (start 88.989702 106.95) (end 90.750029 108.710325) (width 0.15) (layer "F.Cu") (net 660))
  (segment (start 91.599999 110.974999) (end 93.224999 110.974999) (width 0.15) (layer "F.Cu") (net 660))
  (segment (start 93.224999 110.974999) (end 93.6 111.35) (width 0.15) (layer "F.Cu") (net 660))
  (via (at 80.052 152.23212) (size 0.5) (drill 0.2) (layers "F.Cu" "B.Cu") (net 660))
  (via (at 87.75 106.941666) (size 0.5) (drill 0.2) (layers "F.Cu" "B.Cu") (net 660))
  (segment (start 68.99997 110.714329) (end 71.514329 108.19997) (width 0.15) (layer "In2.Cu") (net 660))
  (segment (start 80.052 151.577) (end 79.000011 150.525011) (width 0.15) (layer "In2.Cu") (net 660))
  (segment (start 74.17497 130.985671) (end 68.99997 125.810671) (width 0.15) (layer "In2.Cu") (net 660))
  (segment (start 85.025 107.185698) (end 85.269032 106.941666) (width 0.15) (layer "In2.Cu") (net 660))
  (segment (start 80.052 152.23212) (end 80.052 151.577) (width 0.15) (layer "In2.Cu") (net 660))
  (segment (start 84.010731 108.19997) (end 85.025 107.185701) (width 0.15) (layer "In2.Cu") (net 660))
  (segment (start 85.025 107.185701) (end 85.025 107.185698) (width 0.15) (layer "In2.Cu") (net 660))
  (segment (start 74.17497 147.860671) (end 74.17497 130.985671) (width 0.15) (layer "In2.Cu") (net 660))
  (segment (start 76.83931 150.52501) (end 79.000011 150.525011) (width 0.15) (layer "In2.Cu") (net 660))
  (segment (start 68.99997 125.810671) (end 68.99997 110.714329) (width 0.15) (layer "In2.Cu") (net 660))
  (segment (start 85.269032 106.941666) (end 87.75 106.941666) (width 0.15) (layer "In2.Cu") (net 660))
  (segment (start 76.83931 150.52501) (end 74.17497 147.860671) (width 0.15) (layer "In2.Cu") (net 660))
  (segment (start 71.514329 108.19997) (end 84.010731 108.19997) (width 0.15) (layer "In2.Cu") (net 660))
  (segment (start 79.072 154.34712) (end 79.072 152.25212) (width 0.15) (layer "F.Cu") (net 661))
  (segment (start 87.75 106.025) (end 88.771836 106.025) (width 0.15) (layer "F.Cu") (net 661))
  (segment (start 92.375001 110.125001) (end 91.800001 110.125001) (width 0.15) (layer "F.Cu") (net 661))
  (segment (start 91.250045 109.575045) (end 91.250045 108.503209) (width 0.15) (layer "F.Cu") (net 661))
  (segment (start 92.375001 110.125001) (end 92.8 110.55) (width 0.15) (layer "F.Cu") (net 661))
  (segment (start 91.250047 108.503211) (end 88.771836 106.025) (width 0.15) (layer "F.Cu") (net 661))
  (segment (start 91.800001 110.125001) (end 91.250045 109.575045) (width 0.15) (layer "F.Cu") (net 661))
  (via (at 79.052 152.23212) (size 0.5) (drill 0.2) (layers "F.Cu" "B.Cu") (net 661))
  (via (at 87.75 105.983333) (size 0.5) (drill 0.2) (layers "F.Cu" "B.Cu") (net 661))
  (segment (start 78.37501 151.07501) (end 76.682177 151.07501) (width 0.15) (layer "In2.Cu") (net 661))
  (segment (start 68.49995 126.017785) (end 68.49995 110.507215) (width 0.15) (layer "In2.Cu") (net 661))
  (segment (start 78.575 151.075) (end 78.37502 151.075) (width 0.15) (layer "In2.Cu") (net 661))
  (segment (start 85.520233 105.983333) (end 87.75 105.983333) (width 0.15) (layer "In2.Cu") (net 661))
  (segment (start 73.67495 131.192784) (end 68.49995 126.017785) (width 0.15) (layer "In2.Cu") (net 661))
  (segment (start 68.49995 110.507215) (end 71.307215 107.69995) (width 0.15) (layer "In2.Cu") (net 661))
  (segment (start 79.052 151.552) (end 78.575 151.075) (width 0.15) (layer "In2.Cu") (net 661))
  (segment (start 79.052 152.23212) (end 79.052 151.552) (width 0.15) (layer "In2.Cu") (net 661))
  (segment (start 73.67495 148.067785) (end 73.67495 131.192784) (width 0.15) (layer "In2.Cu") (net 661))
  (segment (start 76.682177 151.07501) (end 73.67495 148.067785) (width 0.15) (layer "In2.Cu") (net 661))
  (segment (start 83.803617 107.69995) (end 85.520233 105.983333) (width 0.15) (layer "In2.Cu") (net 661))
  (segment (start 71.307215 107.69995) (end 83.803617 107.69995) (width 0.15) (layer "In2.Cu") (net 661))
  (segment (start 78.37502 151.075) (end 78.37501 151.07501) (width 0.15) (layer "In2.Cu") (net 661))
  (segment (start 79.077 158.75802) (end 79.077 160.15712) (width 0.15) (layer "F.Cu") (net 662))
  (segment (start 90.25001 110.80001) (end 91.6 112.15) (width 0.15) (layer "F.Cu") (net 662))
  (segment (start 87.75 107.9) (end 89.232568 107.9) (width 0.15) (layer "F.Cu") (net 662))
  (segment (start 90.25001 108.917441) (end 90.25001 110.80001) (width 0.15) (layer "F.Cu") (net 662))
  (segment (start 91.6 112.15) (end 92 112.15) (width 0.15) (layer "F.Cu") (net 662))
  (segment (start 89.232568 107.9) (end 90.25001 108.917441) (width 0.15) (layer "F.Cu") (net 662))
  (via (at 79.077 160.15712) (size 0.5) (drill 0.2) (layers "F.Cu" "B.Cu") (net 662))
  (via (at 87.75 107.9) (size 0.5) (drill 0.2) (layers "F.Cu" "B.Cu") (net 662))
  (segment (start 76.946433 149.925) (end 74.67499 147.653557) (width 0.15) (layer "In2.Cu") (net 662))
  (segment (start 74.67499 147.653557) (end 74.67499 130.778557) (width 0.15) (layer "In2.Cu") (net 662))
  (segment (start 84.228577 108.69999) (end 85.028566 107.9) (width 0.15) (layer "In2.Cu") (net 662))
  (segment (start 80.849989 157.150011) (end 80.849989 151.249989) (width 0.15) (layer "In2.Cu") (net 662))
  (segment (start 80.849989 151.249989) (end 79.525 149.925) (width 0.15) (layer "In2.Cu") (net 662))
  (segment (start 85.028566 107.9) (end 87.75 107.9) (width 0.15) (layer "In2.Cu") (net 662))
  (segment (start 71.721443 108.69999) (end 84.228577 108.69999) (width 0.15) (layer "In2.Cu") (net 662))
  (segment (start 79.077 158.923) (end 80.849989 157.150011) (width 0.15) (layer "In2.Cu") (net 662))
  (segment (start 69.49999 125.603557) (end 69.49999 110.921443) (width 0.15) (layer "In2.Cu") (net 662))
  (segment (start 79.077 160.15712) (end 79.077 158.923) (width 0.15) (layer "In2.Cu") (net 662))
  (segment (start 79.525 149.925) (end 76.946433 149.925) (width 0.15) (layer "In2.Cu") (net 662))
  (segment (start 69.49999 110.921443) (end 71.721443 108.69999) (width 0.15) (layer "In2.Cu") (net 662))
  (segment (start 74.67499 130.778557) (end 69.49999 125.603557) (width 0.15) (layer "In2.Cu") (net 662))
  (segment (start 92.424999 112.525001) (end 92.8 112.15) (width 0.15) (layer "F.Cu") (net 663))
  (segment (start 90 109.020998) (end 90 111.15) (width 0.15) (layer "F.Cu") (net 663))
  (segment (start 89.329002 108.35) (end 90 109.020998) (width 0.15) (layer "F.Cu") (net 663))
  (segment (start 90 111.15) (end 91.375001 112.525001) (width 0.15) (layer "F.Cu") (net 663))
  (segment (start 91.375001 112.525001) (end 92.424999 112.525001) (width 0.15) (layer "F.Cu") (net 663))
  (segment (start 88.225 108.35) (end 89.329002 108.35) (width 0.15) (layer "F.Cu") (net 663))
  (segment (start 79.552 158.75802) (end 79.552 159.75712) (width 0.15) (layer "F.Cu") (net 663))
  (via (at 79.552 159.75712) (size 0.5) (drill 0.2) (layers "F.Cu" "B.Cu") (net 663))
  (via (at 88.225 108.35) (size 0.5) (drill 0.2) (layers "F.Cu" "B.Cu") (net 663))
  (segment (start 84.932132 108.35) (end 88.225 108.35) (width 0.15) (layer "In2.Cu") (net 663))
  (segment (start 79.552 158.823) (end 81.1 157.275) (width 0.15) (layer "In2.Cu") (net 663))
  (segment (start 77.025 149.65) (end 74.925 147.55) (width 0.15) (layer "In2.Cu") (net 663))
  (segment (start 74.925 147.55) (end 74.925 130.675) (width 0.15) (layer "In2.Cu") (net 663))
  (segment (start 69.75 125.5) (end 69.75 111.025) (width 0.15) (layer "In2.Cu") (net 663))
  (segment (start 79.552 159.75712) (end 79.552 158.823) (width 0.15) (layer "In2.Cu") (net 663))
  (segment (start 81.1 157.275) (end 81.1 151) (width 0.15) (layer "In2.Cu") (net 663))
  (segment (start 74.925 130.675) (end 69.75 125.5) (width 0.15) (layer "In2.Cu") (net 663))
  (segment (start 69.75 111.025) (end 71.825 108.95) (width 0.15) (layer "In2.Cu") (net 663))
  (segment (start 84.332134 108.95) (end 84.932132 108.35) (width 0.15) (layer "In2.Cu") (net 663))
  (segment (start 71.825 108.95) (end 84.332134 108.95) (width 0.15) (layer "In2.Cu") (net 663))
  (segment (start 79.75 149.65) (end 77.025 149.65) (width 0.15) (layer "In2.Cu") (net 663))
  (segment (start 81.1 151) (end 79.75 149.65) (width 0.15) (layer "In2.Cu") (net 663))
  (segment (start 80.073 158.09198) (end 80.073 157.09288) (width 0.15) (layer "F.Cu") (net 664))
  (segment (start 91.425 111.35) (end 92 111.35) (width 0.15) (layer "F.Cu") (net 664))
  (segment (start 88.225 107.425) (end 89.111136 107.425) (width 0.15) (layer "F.Cu") (net 664))
  (segment (start 90.50002 110.42502) (end 90.50002 108.813884) (width 0.15) (layer "F.Cu") (net 664))
  (segment (start 89.111136 107.425) (end 90.50002 108.813884) (width 0.15) (layer "F.Cu") (net 664))
  (segment (start 91.425 111.35) (end 90.50002 110.42502) (width 0.15) (layer "F.Cu") (net 664))
  (via (at 80.073 157.09288) (size 0.5) (drill 0.2) (layers "F.Cu" "B.Cu") (net 664))
  (via (at 88.225 107.3875) (size 0.5) (drill 0.2) (layers "F.Cu" "B.Cu") (net 664))
  (segment (start 74.42498 130.882114) (end 69.24998 125.707114) (width 0.15) (layer "In2.Cu") (net 664))
  (segment (start 80.477001 151.402001) (end 79.35 150.275) (width 0.15) (layer "In2.Cu") (net 664))
  (segment (start 80.073 157.09288) (end 80.477001 156.688879) (width 0.15) (layer "In2.Cu") (net 664))
  (segment (start 69.24998 110.817886) (end 71.617886 108.44998) (width 0.15) (layer "In2.Cu") (net 664))
  (segment (start 71.617886 108.44998) (end 84.12502 108.44998) (width 0.15) (layer "In2.Cu") (net 664))
  (segment (start 79.35 150.275) (end 76.942867 150.275) (width 0.15) (layer "In2.Cu") (net 664))
  (segment (start 76.942867 150.275) (end 74.42498 147.757114) (width 0.15) (layer "In2.Cu") (net 664))
  (segment (start 84.12502 108.44998) (end 85.1875 107.3875) (width 0.15) (layer "In2.Cu") (net 664))
  (segment (start 80.477001 156.688879) (end 80.477001 151.402001) (width 0.15) (layer "In2.Cu") (net 664))
  (segment (start 74.42498 147.757114) (end 74.42498 130.882114) (width 0.15) (layer "In2.Cu") (net 664))
  (segment (start 85.1875 107.3875) (end 88.225 107.3875) (width 0.15) (layer "In2.Cu") (net 664))
  (segment (start 69.24998 125.707114) (end 69.24998 110.817886) (width 0.15) (layer "In2.Cu") (net 664))
  (segment (start 69.077 158.00622) (end 69.077 157.00712) (width 0.15) (layer "F.Cu") (net 665))
  (segment (start 92.375001 107.950001) (end 92.375001 109.325001) (width 0.15) (layer "F.Cu") (net 665))
  (segment (start 92.375001 109.325001) (end 92.8 109.75) (width 0.15) (layer "F.Cu") (net 665))
  (segment (start 88.925 104.5) (end 92.375001 107.950001) (width 0.15) (layer "F.Cu") (net 665))
  (segment (start 88.225 104.5) (end 88.925 104.5) (width 0.15) (layer "F.Cu") (net 665))
  (via (at 69.077 157.00712) (size 0.5) (drill 0.2) (layers "F.Cu" "B.Cu") (net 665))
  (via (at 88.225 104.5) (size 0.5) (drill 0.2) (layers "F.Cu" "B.Cu") (net 665))
  (segment (start 70.996543 106.94992) (end 83.47508 106.94992) (width 0.15) (layer "In2.Cu") (net 665))
  (segment (start 85.925 104.5) (end 88.225 104.5) (width 0.15) (layer "In2.Cu") (net 665))
  (segment (start 69.077 157.00712) (end 69.077 153.077) (width 0.15) (layer "In2.Cu") (net 665))
  (segment (start 68.175 151.025) (end 68.575 150.625) (width 0.15) (layer "In2.Cu") (net 665))
  (segment (start 72.924919 131.503455) (end 67.749919 126.328456) (width 0.15) (layer "In2.Cu") (net 665))
  (segment (start 69.071432 150.625) (end 72.924919 146.771513) (width 0.15) (layer "In2.Cu") (net 665))
  (segment (start 67.749919 110.196544) (end 70.996543 106.94992) (width 0.15) (layer "In2.Cu") (net 665))
  (segment (start 69.077 153.077) (end 68.175 152.175) (width 0.15) (layer "In2.Cu") (net 665))
  (segment (start 67.749919 126.328456) (end 67.749919 110.196544) (width 0.15) (layer "In2.Cu") (net 665))
  (segment (start 72.924919 146.771513) (end 72.924919 131.503455) (width 0.15) (layer "In2.Cu") (net 665))
  (segment (start 68.175 152.175) (end 68.175 151.025) (width 0.15) (layer "In2.Cu") (net 665))
  (segment (start 68.575 150.625) (end 69.071432 150.625) (width 0.15) (layer "In2.Cu") (net 665))
  (segment (start 83.47508 106.94992) (end 85.925 104.5) (width 0.15) (layer "In2.Cu") (net 665))
  (segment (start 69.072 154.34712) (end 69.072 152.25212) (width 0.15) (layer "F.Cu") (net 666))
  (segment (start 69.072 152.25212) (end 69.052 152.23212) (width 0.15) (layer "F.Cu") (net 666))
  (segment (start 87.775 105.025) (end 88.775 105.025) (width 0.15) (layer "F.Cu") (net 666))
  (segment (start 92 108.25) (end 92 108.95) (width 0.15) (layer "F.Cu") (net 666))
  (segment (start 88.775 105.025) (end 92 108.25) (width 0.15) (layer "F.Cu") (net 666))
  (via (at 69.052 152.23212) (size 0.5) (drill 0.2) (layers "F.Cu" "B.Cu") (net 666))
  (via (at 87.775 105.025) (size 0.5) (drill 0.2) (layers "F.Cu" "B.Cu") (net 666))
  (segment (start 68.425011 151.958684) (end 68.425011 151.174989) (width 0.15) (layer "In2.Cu") (net 666))
  (segment (start 69.174989 150.875011) (end 73.17493 146.87507) (width 0.15) (layer "In2.Cu") (net 666))
  (segment (start 68.698447 152.23212) (end 68.425011 151.958684) (width 0.15) (layer "In2.Cu") (net 666))
  (segment (start 69.052 152.23212) (end 68.698447 152.23212) (width 0.15) (layer "In2.Cu") (net 666))
  (segment (start 71.100101 107.19993) (end 83.578637 107.19993) (width 0.15) (layer "In2.Cu") (net 666))
  (segment (start 67.99993 110.300101) (end 71.100101 107.19993) (width 0.15) (layer "In2.Cu") (net 666))
  (segment (start 67.99993 126.224899) (end 67.99993 110.300101) (width 0.15) (layer "In2.Cu") (net 666))
  (segment (start 68.425011 151.174989) (end 68.724989 150.875011) (width 0.15) (layer "In2.Cu") (net 666))
  (segment (start 68.724989 150.875011) (end 69.174989 150.875011) (width 0.15) (layer "In2.Cu") (net 666))
  (segment (start 73.17493 131.399897) (end 67.99993 126.224899) (width 0.15) (layer "In2.Cu") (net 666))
  (segment (start 85.753566 105.025) (end 87.775 105.025) (width 0.15) (layer "In2.Cu") (net 666))
  (segment (start 83.578637 107.19993) (end 85.753566 105.025) (width 0.15) (layer "In2.Cu") (net 666))
  (segment (start 73.17493 146.87507) (end 73.17493 131.399897) (width 0.15) (layer "In2.Cu") (net 666))
  (segment (start 122.55 117.05) (end 121.535003 117.05) (width 0.15) (layer "F.Cu") (net 672))
  (segment (start 128.335 117.05) (end 128.385 117.1) (width 0.15) (layer "F.Cu") (net 672))
  (segment (start 127.42 117.05) (end 128.335 117.05) (width 0.15) (layer "F.Cu") (net 672))
  (via (at 128.385 117.1) (size 0.5) (drill 0.2) (layers "F.Cu" "B.Cu") (net 672))
  (via (at 121.5 117.05) (size 0.5) (drill 0.2) (layers "F.Cu" "B.Cu") (net 672))
  (segment (start 128.385 117.1) (end 121.55 117.1) (width 0.5) (layer "In6.Cu") (net 672))
  (segment (start 121.55 117.1) (end 121.5 117.05) (width 0.5) (layer "In6.Cu") (net 672))
  (segment (start 121.485 117.100003) (end 121.485 116.335) (width 0.3) (layer "B.Cu") (net 672))
  (segment (start 128.81 117.525) (end 129.175 117.525) (width 0.2) (layer "B.Cu") (net 672))
  (segment (start 128.385 117.1) (end 128.81 117.525) (width 0.2) (layer "B.Cu") (net 672))
  (segment (start 106.627149 94.7) (end 111.22 94.7) (width 0.2) (layer "F.Cu") (net 676))
  (segment (start 124.705 129.045) (end 124.705 132.115) (width 0.2) (layer "F.Cu") (net 678))
  (segment (start 129.59 116.05) (end 127.42 116.05) (width 0.2) (layer "F.Cu") (net 679))
  (segment (start 97.995 66.87) (end 96.92 66.87) (width 0.2) (layer "F.Cu") (net 680))
  (segment (start 95.35 85) (end 95.35 68.44) (width 0.2) (layer "F.Cu") (net 680))
  (segment (start 96.92 66.87) (end 95.35 68.44) (width 0.2) (layer "F.Cu") (net 680))
  (segment (start 96.05 85.7) (end 95.35 85) (width 0.2) (layer "F.Cu") (net 680))
  (via (at 96.05 85.7) (size 0.5) (drill 0.2) (layers "F.Cu" "B.Cu") (net 680))
  (segment (start 96.05 87.515) (end 96.05 85.7) (width 0.2) (layer "B.Cu") (net 680))
  (segment (start 111.15 67.73) (end 112.06 66.82) (width 0.2) (layer "F.Cu") (net 681))
  (segment (start 111.15 78.4) (end 110.2 79.35) (width 0.2) (layer "F.Cu") (net 681))
  (segment (start 111.15 78.4) (end 111.15 67.73) (width 0.2) (layer "F.Cu") (net 681))
  (segment (start 97.05 85.7) (end 97.05 85.000008) (width 0.2) (layer "F.Cu") (net 681))
  (segment (start 110.2 79.35) (end 98.45 79.35) (width 0.2) (layer "F.Cu") (net 681))
  (segment (start 97.05 85.000008) (end 97.049992 85) (width 0.2) (layer "F.Cu") (net 681))
  (segment (start 98.45 79.35) (end 97.049992 80.750008) (width 0.2) (layer "F.Cu") (net 681))
  (segment (start 97.049992 80.750008) (end 97.049992 85) (width 0.2) (layer "F.Cu") (net 681))
  (via (at 97.05 85.7) (size 0.5) (drill 0.2) (layers "F.Cu" "B.Cu") (net 681))
  (segment (start 97.05 87.515) (end 97.05 85.7) (width 0.2) (layer "B.Cu") (net 681))
  (segment (start 99.2 131.35) (end 98.96 131.59) (width 0.127) (layer "F.Cu") (net 686))
  (segment (start 98.96 131.676152) (end 99.34096 132.057112) (width 0.127) (layer "F.Cu") (net 686))
  (segment (start 97.936777 135.24) (end 98.551778 135.24) (width 0.127) (layer "F.Cu") (net 686))
  (segment (start 98.96 131.59) (end 98.96 131.676152) (width 0.127) (layer "F.Cu") (net 686))
  (segment (start 98.551778 135.24) (end 99.340952 134.450826) (width 0.127) (layer "F.Cu") (net 686))
  (segment (start 97.715668 135.461109) (end 97.936777 135.24) (width 0.127) (layer "F.Cu") (net 686))
  (segment (start 99.34096 132.264228) (end 99.34096 132.057112) (width 0.127) (layer "F.Cu") (net 686))
  (segment (start 97.715668 135.715668) (end 97.715668 135.461109) (width 0.127) (layer "F.Cu") (net 686))
  (segment (start 99.340952 134.450826) (end 99.340952 132.264236) (width 0.127) (layer "F.Cu") (net 686))
  (segment (start 99.340952 132.264236) (end 99.34096 132.264228) (width 0.127) (layer "F.Cu") (net 686))
  (via (at 97.715668 135.715668) (size 0.5) (drill 0.2) (layers "F.Cu" "B.Cu") (net 686))
  (segment (start 97.68 137.985) (end 97.32 137.625) (width 0.127) (layer "B.Cu") (net 686))
  (segment (start 97.461109 135.715668) (end 97.715668 135.715668) (width 0.127) (layer "B.Cu") (net 686))
  (segment (start 97.32 137.625) (end 97.32 135.856777) (width 0.127) (layer "B.Cu") (net 686))
  (segment (start 97.32 135.856777) (end 97.461109 135.715668) (width 0.127) (layer "B.Cu") (net 686))
  (segment (start 98.448222 134.99) (end 99.090952 134.34727) (width 0.127) (layer "F.Cu") (net 687))
  (segment (start 97.284332 135.284332) (end 97.538891 135.284332) (width 0.127) (layer "F.Cu") (net 687))
  (segment (start 97.833223 134.99) (end 98.448222 134.99) (width 0.127) (layer "F.Cu") (net 687))
  (segment (start 99.090952 134.34727) (end 99.090952 132.16067) (width 0.127) (layer "F.Cu") (net 687))
  (segment (start 98.7 131.769718) (end 98.7 131.525) (width 0.127) (layer "F.Cu") (net 687))
  (segment (start 98.7 131.525) (end 98.525 131.35) (width 0.127) (layer "F.Cu") (net 687))
  (segment (start 98.7 131.769718) (end 99.090952 132.16067) (width 0.127) (layer "F.Cu") (net 687))
  (segment (start 97.538891 135.284332) (end 97.833223 134.99) (width 0.127) (layer "F.Cu") (net 687))
  (via (at 97.284332 135.284332) (size 0.5) (drill 0.2) (layers "F.Cu" "B.Cu") (net 687))
  (segment (start 97.07 135.753223) (end 97.284332 135.538891) (width 0.127) (layer "B.Cu") (net 687))
  (segment (start 96.71 137.985) (end 97.07 137.625) (width 0.127) (layer "B.Cu") (net 687))
  (segment (start 97.284332 135.538891) (end 97.284332 135.284332) (width 0.127) (layer "B.Cu") (net 687))
  (segment (start 97.07 137.625) (end 97.07 135.753223) (width 0.127) (layer "B.Cu") (net 687))
  (segment (start 126.575 168.81) (end 126.95 169.185) (width 0.127) (layer "F.Cu") (net 688))
  (segment (start 129.365 175.669999) (end 129.19 175.844999) (width 0.127) (layer "F.Cu") (net 688))
  (segment (start 129.19 175.844999) (end 129.19 177.135) (width 0.127) (layer "F.Cu") (net 688))
  (segment (start 126.95 169.185) (end 126.95 171.361778) (width 0.127) (layer "F.Cu") (net 688))
  (segment (start 129.365 173.776778) (end 129.365 175.669999) (width 0.127) (layer "F.Cu") (net 688))
  (segment (start 126.95 171.361778) (end 129.365 173.776778) (width 0.127) (layer "F.Cu") (net 688))
  (segment (start 129.94 169.185) (end 129.94 171.411778) (width 0.127) (layer "F.Cu") (net 689))
  (segment (start 129.565 168.81) (end 129.94 169.185) (width 0.127) (layer "F.Cu") (net 689))
  (segment (start 130.99 175.844999) (end 130.99 177.135) (width 0.127) (layer "F.Cu") (net 689))
  (segment (start 131.165 175.669999) (end 130.99 175.844999) (width 0.127) (layer "F.Cu") (net 689))
  (segment (start 129.94 171.411778) (end 131.165 172.636778) (width 0.127) (layer "F.Cu") (net 689))
  (segment (start 131.165 172.636778) (end 131.165 175.669999) (width 0.127) (layer "F.Cu") (net 689))
  (segment (start 132.79 177.135) (end 132.79 175.844999) (width 0.127) (layer "F.Cu") (net 690))
  (segment (start 132.965 169.24) (end 132.535 168.81) (width 0.127) (layer "F.Cu") (net 690))
  (segment (start 132.79 175.844999) (end 132.965 175.669999) (width 0.127) (layer "F.Cu") (net 690))
  (segment (start 132.965 175.669999) (end 132.965 169.24) (width 0.127) (layer "F.Cu") (net 690))
  (segment (start 135.91 170.618222) (end 134.765 171.763222) (width 0.127) (layer "F.Cu") (net 691))
  (segment (start 134.59 177.135) (end 134.59 175.844999) (width 0.127) (layer "F.Cu") (net 691))
  (segment (start 135.545 168.81) (end 135.91 169.175) (width 0.127) (layer "F.Cu") (net 691))
  (segment (start 135.91 169.175) (end 135.91 170.618222) (width 0.127) (layer "F.Cu") (net 691))
  (segment (start 134.765 171.763222) (end 134.765 175.669999) (width 0.127) (layer "F.Cu") (net 691))
  (segment (start 134.59 175.844999) (end 134.765 175.669999) (width 0.127) (layer "F.Cu") (net 691))
  (segment (start 127.575 168.81) (end 127.2 169.185) (width 0.127) (layer "F.Cu") (net 692))
  (segment (start 129.79 175.844999) (end 129.79 177.135) (width 0.127) (layer "F.Cu") (net 692))
  (segment (start 129.615 173.673222) (end 129.615 175.669999) (width 0.127) (layer "F.Cu") (net 692))
  (segment (start 129.615 175.669999) (end 129.79 175.844999) (width 0.127) (layer "F.Cu") (net 692))
  (segment (start 127.2 169.185) (end 127.2 171.258222) (width 0.127) (layer "F.Cu") (net 692))
  (segment (start 127.2 171.258222) (end 129.615 173.673222) (width 0.127) (layer "F.Cu") (net 692))
  (segment (start 130.19 171.308222) (end 131.415 172.533222) (width 0.127) (layer "F.Cu") (net 693))
  (segment (start 131.59 175.844999) (end 131.59 177.135) (width 0.127) (layer "F.Cu") (net 693))
  (segment (start 130.19 169.185) (end 130.19 171.308222) (width 0.127) (layer "F.Cu") (net 693))
  (segment (start 130.565 168.81) (end 130.19 169.185) (width 0.127) (layer "F.Cu") (net 693))
  (segment (start 131.415 172.533222) (end 131.415 175.669999) (width 0.127) (layer "F.Cu") (net 693))
  (segment (start 131.415 175.669999) (end 131.59 175.844999) (width 0.127) (layer "F.Cu") (net 693))
  (segment (start 133.215 169.25) (end 133.535 168.93) (width 0.127) (layer "F.Cu") (net 694))
  (segment (start 133.39 177.135) (end 133.39 175.844999) (width 0.127) (layer "F.Cu") (net 694))
  (segment (start 133.39 175.844999) (end 133.215 175.669999) (width 0.127) (layer "F.Cu") (net 694))
  (segment (start 133.215 175.669999) (end 133.215 169.25) (width 0.127) (layer "F.Cu") (net 694))
  (segment (start 135.19 175.844999) (end 135.015 175.669999) (width 0.127) (layer "F.Cu") (net 695))
  (segment (start 136.525 168.81) (end 136.16 169.175) (width 0.127) (layer "F.Cu") (net 695))
  (segment (start 135.19 177.135) (end 135.19 175.844999) (width 0.127) (layer "F.Cu") (net 695))
  (segment (start 135.015 171.866778) (end 135.015 175.669999) (width 0.127) (layer "F.Cu") (net 695))
  (segment (start 136.16 170.721778) (end 135.015 171.866778) (width 0.127) (layer "F.Cu") (net 695))
  (segment (start 136.16 169.175) (end 136.16 170.721778) (width 0.127) (layer "F.Cu") (net 695))
  (segment (start 137.675 163.22) (end 137.85 163.045) (width 0.127) (layer "F.Cu") (net 696))
  (segment (start 137.8 164.26) (end 137.675 164.135) (width 0.127) (layer "F.Cu") (net 696))
  (segment (start 137.675 164.135) (end 137.675 163.22) (width 0.127) (layer "F.Cu") (net 696))
  (via (at 137.85 163.045) (size 0.5) (drill 0.2) (layers "F.Cu" "B.Cu") (net 696))
  (segment (start 137.675 170.106778) (end 135.015 172.766778) (width 0.127) (layer "B.Cu") (net 696))
  (segment (start 137.675 163.22) (end 137.675 170.106778) (width 0.127) (layer "B.Cu") (net 696))
  (segment (start 137.85 163.045) (end 137.675 163.22) (width 0.127) (layer "B.Cu") (net 696))
  (segment (start 135.015 172.766778) (end 135.015 175.682499) (width 0.127) (layer "B.Cu") (net 696))
  (segment (start 135.19 175.857499) (end 135.19 177.14) (width 0.127) (layer "B.Cu") (net 696))
  (segment (start 135.015 175.682499) (end 135.19 175.857499) (width 0.127) (layer "B.Cu") (net 696))
  (segment (start 137.425 164.135) (end 137.425 163.22) (width 0.127) (layer "F.Cu") (net 697))
  (segment (start 137.3 164.26) (end 137.425 164.135) (width 0.127) (layer "F.Cu") (net 697))
  (segment (start 137.425 163.22) (end 137.25 163.045) (width 0.127) (layer "F.Cu") (net 697))
  (via (at 137.25 163.045) (size 0.5) (drill 0.2) (layers "F.Cu" "B.Cu") (net 697))
  (segment (start 137.425 170.003222) (end 134.765 172.663222) (width 0.127) (layer "B.Cu") (net 697))
  (segment (start 137.25 163.045) (end 137.425 163.22) (width 0.127) (layer "B.Cu") (net 697))
  (segment (start 134.59 175.857499) (end 134.59 177.14) (width 0.127) (layer "B.Cu") (net 697))
  (segment (start 137.425 163.22) (end 137.425 170.003222) (width 0.127) (layer "B.Cu") (net 697))
  (segment (start 134.765 172.663222) (end 134.765 175.682499) (width 0.127) (layer "B.Cu") (net 697))
  (segment (start 134.765 175.682499) (end 134.59 175.857499) (width 0.127) (layer "B.Cu") (net 697))
  (segment (start 134.8 164.26) (end 134.675 164.135) (width 0.127) (layer "F.Cu") (net 698))
  (segment (start 134.675 163.22) (end 134.85 163.045) (width 0.127) (layer "F.Cu") (net 698))
  (segment (start 134.675 164.135) (end 134.675 163.22) (width 0.127) (layer "F.Cu") (net 698))
  (via (at 134.85 163.045) (size 0.5) (drill 0.2) (layers "F.Cu" "B.Cu") (net 698))
  (segment (start 134.85 163.045) (end 134.675 163.22) (width 0.127) (layer "B.Cu") (net 698))
  (segment (start 133.215 175.682499) (end 133.39 175.857499) (width 0.127) (layer "B.Cu") (net 698))
  (segment (start 133.39 175.857499) (end 133.39 177.14) (width 0.127) (layer "B.Cu") (net 698))
  (segment (start 134.675 170.856778) (end 133.215 172.316778) (width 0.127) (layer "B.Cu") (net 698))
  (segment (start 134.675 163.22) (end 134.675 170.856778) (width 0.127) (layer "B.Cu") (net 698))
  (segment (start 133.215 172.316778) (end 133.215 175.682499) (width 0.127) (layer "B.Cu") (net 698))
  (segment (start 134.425 164.135) (end 134.425 163.22) (width 0.127) (layer "F.Cu") (net 699))
  (segment (start 134.425 163.22) (end 134.25 163.045) (width 0.127) (layer "F.Cu") (net 699))
  (segment (start 134.3 164.26) (end 134.425 164.135) (width 0.127) (layer "F.Cu") (net 699))
  (via (at 134.25 163.045) (size 0.5) (drill 0.2) (layers "F.Cu" "B.Cu") (net 699))
  (segment (start 134.425 163.22) (end 134.425 170.753222) (width 0.127) (layer "B.Cu") (net 699))
  (segment (start 132.965 175.682499) (end 132.79 175.857499) (width 0.127) (layer "B.Cu") (net 699))
  (segment (start 134.25 163.045) (end 134.425 163.22) (width 0.127) (layer "B.Cu") (net 699))
  (segment (start 132.965 172.213222) (end 132.965 175.682499) (width 0.127) (layer "B.Cu") (net 699))
  (segment (start 134.425 170.753222) (end 132.965 172.213222) (width 0.127) (layer "B.Cu") (net 699))
  (segment (start 132.79 175.857499) (end 132.79 177.14) (width 0.127) (layer "B.Cu") (net 699))
  (segment (start 131.8 164.26) (end 131.675 164.135) (width 0.127) (layer "F.Cu") (net 700))
  (segment (start 131.675 164.135) (end 131.675 163.22) (width 0.127) (layer "F.Cu") (net 700))
  (segment (start 131.675 163.22) (end 131.85 163.045) (width 0.127) (layer "F.Cu") (net 700))
  (via (at 131.85 163.045) (size 0.5) (drill 0.2) (layers "F.Cu" "B.Cu") (net 700))
  (segment (start 131.59 175.857499) (end 131.59 177.14) (width 0.127) (layer "B.Cu") (net 700))
  (segment (start 131.675 163.22) (end 131.675 172.426778) (width 0.127) (layer "B.Cu") (net 700))
  (segment (start 131.85 163.045) (end 131.675 163.22) (width 0.127) (layer "B.Cu") (net 700))
  (segment (start 131.415 175.682499) (end 131.59 175.857499) (width 0.127) (layer "B.Cu") (net 700))
  (segment (start 131.415 172.686778) (end 131.415 175.682499) (width 0.127) (layer "B.Cu") (net 700))
  (segment (start 131.675 172.426778) (end 131.415 172.686778) (width 0.127) (layer "B.Cu") (net 700))
  (segment (start 131.425 163.22) (end 131.25 163.045) (width 0.127) (layer "F.Cu") (net 701))
  (segment (start 131.425 164.135) (end 131.425 163.22) (width 0.127) (layer "F.Cu") (net 701))
  (segment (start 131.3 164.26) (end 131.425 164.135) (width 0.127) (layer "F.Cu") (net 701))
  (via (at 131.25 163.045) (size 0.5) (drill 0.2) (layers "F.Cu" "B.Cu") (net 701))
  (segment (start 131.425 163.22) (end 131.425 172.323222) (width 0.127) (layer "B.Cu") (net 701))
  (segment (start 131.425 172.323222) (end 131.165 172.583222) (width 0.127) (layer "B.Cu") (net 701))
  (segment (start 130.99 175.857499) (end 130.99 177.14) (width 0.127) (layer "B.Cu") (net 701))
  (segment (start 131.165 172.583222) (end 131.165 175.682499) (width 0.127) (layer "B.Cu") (net 701))
  (segment (start 131.25 163.045) (end 131.425 163.22) (width 0.127) (layer "B.Cu") (net 701))
  (segment (start 131.165 175.682499) (end 130.99 175.857499) (width 0.127) (layer "B.Cu") (net 701))
  (segment (start 128.3 164.25) (end 128.425 164.125) (width 0.127) (layer "F.Cu") (net 702))
  (segment (start 128.425 164.125) (end 128.425 163.21) (width 0.127) (layer "F.Cu") (net 702))
  (segment (start 128.425 163.21) (end 128.25 163.035) (width 0.127) (layer "F.Cu") (net 702))
  (via (at 128.25 163.035) (size 0.5) (drill 0.2) (layers "F.Cu" "B.Cu") (net 702))
  (segment (start 129.365 172.066778) (end 129.365 175.682499) (width 0.127) (layer "B.Cu") (net 702))
  (segment (start 128.25 163.035) (end 128.425 163.21) (width 0.127) (layer "B.Cu") (net 702))
  (segment (start 128.425 163.21) (end 128.425 171.126778) (width 0.127) (layer "B.Cu") (net 702))
  (segment (start 129.19 175.857499) (end 129.19 177.14) (width 0.127) (layer "B.Cu") (net 702))
  (segment (start 129.365 175.682499) (end 129.19 175.857499) (width 0.127) (layer "B.Cu") (net 702))
  (segment (start 128.425 171.126778) (end 129.365 172.066778) (width 0.127) (layer "B.Cu") (net 702))
  (segment (start 128.675 164.125) (end 128.675 163.21) (width 0.127) (layer "F.Cu") (net 703))
  (segment (start 128.675 163.21) (end 128.85 163.035) (width 0.127) (layer "F.Cu") (net 703))
  (segment (start 128.8 164.25) (end 128.675 164.125) (width 0.127) (layer "F.Cu") (net 703))
  (via (at 128.85 163.035) (size 0.5) (drill 0.2) (layers "F.Cu" "B.Cu") (net 703))
  (segment (start 128.85 163.035) (end 128.675 163.21) (width 0.127) (layer "B.Cu") (net 703))
  (segment (start 129.79 175.857499) (end 129.79 177.14) (width 0.127) (layer "B.Cu") (net 703))
  (segment (start 129.615 175.682499) (end 129.79 175.857499) (width 0.127) (layer "B.Cu") (net 703))
  (segment (start 128.675 171.023222) (end 129.615 171.963222) (width 0.127) (layer "B.Cu") (net 703))
  (segment (start 128.675 163.21) (end 128.675 171.023222) (width 0.127) (layer "B.Cu") (net 703))
  (segment (start 129.615 171.963222) (end 129.615 175.682499) (width 0.127) (layer "B.Cu") (net 703))
  (segment (start 143.2 168.235) (end 141.715 168.235) (width 0.15) (layer "F.Cu") (net 777))
  (segment (start 80.8 64.2) (end 81.95 64.2) (width 0.25) (layer "F.Cu") (net 780))
  (segment (start 75.8 64.2) (end 75.55 63.95) (width 0.25) (layer "F.Cu") (net 781))
  (segment (start 75.55 63.35) (end 74.4 63.35) (width 0.25) (layer "F.Cu") (net 781))
  (segment (start 75.55 63.95) (end 75.55 63.35) (width 0.25) (layer "F.Cu") (net 781))
  (segment (start 76.8 64.2) (end 75.8 64.2) (width 0.25) (layer "F.Cu") (net 781))
  (segment (start 80.8 66.6) (end 81.85 66.6) (width 0.25) (layer "F.Cu") (net 782))
  (segment (start 80.8 63.4) (end 80.8 62.35) (width 0.25) (layer "F.Cu") (net 783))
  (segment (start 76.665 61.885) (end 76.9 61.65) (width 0.25) (layer "F.Cu") (net 784))
  (segment (start 76.9 61.65) (end 76.9 61.2) (width 0.25) (layer "F.Cu") (net 784))
  (segment (start 76.665 62.35) (end 76.665 61.885) (width 0.25) (layer "F.Cu") (net 784))
  (segment (start 76.665 62.35) (end 76.665 63.285) (width 0.25) (layer "F.Cu") (net 784))
  (segment (start 86.1 69.55) (end 85.1 69.55) (width 0.2) (layer "F.Cu") (net 785))
  (segment (start 81.95 65) (end 82 65.05) (width 0.25) (layer "F.Cu") (net 785))
  (segment (start 80.8 65) (end 81.95 65) (width 0.25) (layer "F.Cu") (net 785))
  (via (at 82 65.05) (size 0.5) (drill 0.2) (layers "F.Cu" "B.Cu") (net 785))
  (via (at 85.1 69.55) (size 0.5) (drill 0.2) (layers "F.Cu" "B.Cu") (net 785))
  (segment (start 82.2 65.25) (end 82.2 69) (width 0.2) (layer "B.Cu") (net 785))
  (segment (start 82.2 69) (end 82.75 69.55) (width 0.2) (layer "B.Cu") (net 785))
  (segment (start 82 65.05) (end 82.2 65.25) (width 0.2) (layer "B.Cu") (net 785))
  (segment (start 82.75 69.55) (end 85.1 69.55) (width 0.2) (layer "B.Cu") (net 785))

  (zone (net 57) (net_name "P12V_AUX") (layer "F.Cu") (hatch edge 0.508)
    (priority 1)
    (connect_pads yes (clearance 0.15))
    (min_thickness 0.254) (filled_areas_thickness no)
    (fill yes (thermal_gap 0.508) (thermal_bridge_width 0.508))
    (polygon
      (pts
        (xy 87.05 65.17)
        (xy 84.69 65.17)
        (xy 84.69 58.88)
        (xy 87.05 58.88)
      )
    )
  )
  (zone (net 1) (net_name "GND") (layer "F.Cu") (hatch edge 0.508)
    (connect_pads yes (clearance 0.15))
    (min_thickness 0.254) (filled_areas_thickness no)
    (fill yes (thermal_gap 0.508) (thermal_bridge_width 0.508))
    (polygon
      (pts
        (xy 69.86 165.64)
        (xy 66.17 165.64)
        (xy 66.17 163.97)
        (xy 69.86 163.97)
      )
    )
  )
  (zone (net 57) (net_name "P12V_AUX") (layer "F.Cu") (hatch edge 0.508)
    (connect_pads yes (clearance 0.15))
    (min_thickness 0.254) (filled_areas_thickness no)
    (fill yes (thermal_gap 0.508) (thermal_bridge_width 0.508))
    (polygon
      (pts
        (xy 69.89 163.28)
        (xy 63.2 163.28)
        (xy 63.2 161.61)
        (xy 69.89 161.61)
      )
    )
  )
  (zone (net 15) (net_name "VCC12V") (layer "F.Cu") (hatch edge 0.508)
    (connect_pads yes (clearance 0.15))
    (min_thickness 0.254) (filled_areas_thickness no)
    (fill yes (thermal_gap 0.508) (thermal_bridge_width 0.508))
    (polygon
      (pts
        (xy 84.61 65.19)
        (xy 87.07 65.19)
        (xy 87.07 66.66)
        (xy 80.4 66.66)
        (xy 80.41 65.17)
        (xy 82.52 65.17)
        (xy 82.52 62.51)
        (xy 84.61 62.51)
      )
    )
  )
  (zone (net 11) (net_name "VCC5V0") (layer "F.Cu") (hatch edge 0.508)
    (priority 1)
    (connect_pads yes (clearance 0.15))
    (min_thickness 0.254) (filled_areas_thickness no)
    (fill yes (thermal_gap 0.508) (thermal_bridge_width 0.508))
    (polygon
      (pts
        (xy 83.425 78.5)
        (xy 83.9 78.5)
        (xy 84.9 79.55)
        (xy 87.9 79.55)
        (xy 89 80.85)
        (xy 69.55 80.9)
        (xy 71.85 78.6)
        (xy 80.75 78.55)
        (xy 80.75 74.7)
        (xy 80.75 72.75)
        (xy 80.25 72.25)
        (xy 80.25 70.4)
        (xy 85.875 70.35)
        (xy 85.9 70.825)
        (xy 84.55 72.2)
        (xy 83.425 72.2)
      )
    )
  )
  (zone (net 11) (net_name "VCC5V0") (layer "F.Cu") (hatch edge 0.508)
    (priority 1)
    (connect_pads yes (clearance 0.1))
    (min_thickness 0.1) (filled_areas_thickness no)
    (fill yes (thermal_gap 0.508) (thermal_bridge_width 0.508))
    (polygon
      (pts
        (xy 70.974787 80.65)
        (xy 71 85.85)
        (xy 70.6 85.85)
        (xy 70.6 85.05)
        (xy 70.45 84.9)
        (xy 69.85 84.9)
        (xy 69.5 84.9)
        (xy 69.512607 81)
        (xy 69.8 80.65)
      )
    )
  )
  (zone (net 11) (net_name "VCC5V0") (layer "F.Cu") (hatch edge 0.508)
    (priority 1)
    (connect_pads yes (clearance 0.1))
    (min_thickness 0.1) (filled_areas_thickness no)
    (fill yes (thermal_gap 0.508) (thermal_bridge_width 0.508))
    (polygon
      (pts
        (xy 117.73346 78.743104)
        (xy 117.9 78.743104)
        (xy 117.90846 80.718104)
        (xy 117.934056 83.318104)
        (xy 117.534056 83.318104)
        (xy 117.534056 82.518104)
        (xy 117.384056 82.368104)
        (xy 116.784056 82.368104)
        (xy 116.434056 82.368104)
        (xy 116.434653 78.743104)
      )
    )
  )
  (zone (net 1) (net_name "GND") (layer "F.Cu") (hatch edge 0.508)
    (connect_pads yes (clearance 0.15))
    (min_thickness 0.15) (filled_areas_thickness no)
    (fill yes (thermal_gap 0.508) (thermal_bridge_width 0.508))
    (polygon
      (pts
        (xy 120.469056 83.943104)
        (xy 116.909056 83.903104)
        (xy 116.909056 83.393104)
        (xy 118.529056 83.393104)
        (xy 118.529056 80.733104)
        (xy 120.469056 80.733104)
      )
    )
  )
  (zone (net 1) (net_name "GND") (layer "F.Cu") (hatch edge 0.508)
    (connect_pads yes (clearance 0.15))
    (min_thickness 0.1) (filled_areas_thickness no)
    (fill yes (thermal_gap 0.508) (thermal_bridge_width 0.508))
    (polygon
      (pts
        (xy 91.9 86.85)
        (xy 69.5 86.85)
        (xy 69.5 83)
        (xy 91.9 83)
      )
    )
  )
  (zone (net 1) (net_name "GND") (layer "F.Cu") (hatch edge 0.508)
    (priority 2)
    (connect_pads yes (clearance 0.15))
    (min_thickness 0.254) (filled_areas_thickness no)
    (fill yes (thermal_gap 0.508) (thermal_bridge_width 0.508))
    (polygon
      (pts
        (xy 84.69 62.7)
        (xy 80.184596 62.7)
        (xy 80.2 66.7)
        (xy 86.75 66.7)
        (xy 86.75 68.6)
        (xy 76.5 68.5)
        (xy 76.45 65.65)
        (xy 77.5 65.7)
        (xy 77.5 60.5)
        (xy 72.6 60.5)
        (xy 72.65 62.15)
        (xy 71.7 62.15)
        (xy 71.67 58.91)
        (xy 79.66 58.91)
        (xy 79.66 58.88)
        (xy 84.69 58.88)
      )
    )
  )
  (zone (net 265) (net_name "Net-(D6-C)") (layer "F.Cu") (hatch edge 0.508)
    (connect_pads yes (clearance 0.1))
    (min_thickness 0.254) (filled_areas_thickness no)
    (fill yes (thermal_gap 0.508) (thermal_bridge_width 0.508))
    (polygon
      (pts
        (xy 74.55 65.5)
        (xy 77.25 65.5)
        (xy 77.3 66.15)
        (xy 75.3 66.15)
        (xy 74.7 66.65)
        (xy 69 66.65)
        (xy 69 63.2)
        (xy 69 62.3)
        (xy 70.55 62.3)
        (xy 70.55 63.15)
        (xy 72.2 63.15)
      )
    )
  )
  (zone (net 290) (net_name "Net-(C110-Pad2)") (layer "F.Cu") (hatch edge 0.508)
    (connect_pads yes (clearance 0.1))
    (min_thickness 0.254) (filled_areas_thickness no)
    (fill yes (thermal_gap 0.508) (thermal_bridge_width 0.508))
    (polygon
      (pts
        (xy 80.3 68.8)
        (xy 80.3 69.95)
        (xy 78.95 69.95)
        (xy 78.25 70.7)
        (xy 78.25 72.35)
        (xy 74.9 72.35)
        (xy 74.15 73.2)
        (xy 74.15 74.9)
        (xy 69 74.9)
        (xy 69 69.9)
        (xy 71 68.75)
      )
    )
  )
  (zone (net 390) (net_name "Net-(U18-SW)") (layer "F.Cu") (hatch edge 0.508)
    (priority 1)
    (connect_pads yes (clearance 0.1))
    (min_thickness 0.1) (filled_areas_thickness no)
    (fill yes (thermal_gap 0.508) (thermal_bridge_width 0.508))
    (polygon
      (pts
        (xy 120.039056 79.743104)
        (xy 119.389056 79.743104)
        (xy 118.389056 80.743104)
        (xy 118.389056 83.343104)
        (xy 118.089056 83.343104)
        (xy 118.089056 78.593104)
        (xy 120.039056 78.593104)
      )
    )
  )
  (zone (net 356) (net_name "Net-(C119-Pad2)") (layer "F.Cu") (hatch edge 0.508)
    (connect_pads yes (clearance 0.1))
    (min_thickness 0.1) (filled_areas_thickness no)
    (fill yes (thermal_gap 0.508) (thermal_bridge_width 0.508))
    (polygon
      (pts
        (xy 122.114056 84.330604)
        (xy 120.696556 84.349354)
        (xy 120.721556 78.686854)
        (xy 122.139056 78.668104)
      )
    )
  )
  (zone (net 393) (net_name "Net-(U16-SW)") (layer "F.Cu") (hatch edge 0.508)
    (priority 1)
    (connect_pads yes (clearance 0.1))
    (min_thickness 0.1) (filled_areas_thickness no)
    (fill yes (thermal_gap 0.508) (thermal_bridge_width 0.508))
    (polygon
      (pts
        (xy 91.15 82.25)
        (xy 90.5 82.25)
        (xy 89.5 83.25)
        (xy 89.5 85.85)
        (xy 89.2 85.85)
        (xy 89.2 81.1)
        (xy 91.15 81.1)
      )
    )
  )
  (zone (net 11) (net_name "VCC5V0") (layer "F.Cu") (hatch edge 0.508)
    (priority 1)
    (connect_pads yes (clearance 0.1))
    (min_thickness 0.1) (filled_areas_thickness no)
    (fill yes (thermal_gap 0.508) (thermal_bridge_width 0.508))
    (polygon
      (pts
        (xy 88.85 80.65)
        (xy 89.011606 80.85)
        (xy 89.024404 83.25)
        (xy 89.05 85.85)
        (xy 88.65 85.85)
        (xy 88.65 85.05)
        (xy 88.5 84.9)
        (xy 87.9 84.9)
        (xy 87.55 84.9)
        (xy 87.551193 80.65)
      )
    )
  )
  (zone (net 359) (net_name "Net-(C122-Pad2)") (layer "F.Cu") (hatch edge 0.508)
    (priority 1)
    (connect_pads yes (clearance 0.15))
    (min_thickness 0.1) (filled_areas_thickness no)
    (fill yes (thermal_gap 0.508) (thermal_bridge_width 0.508))
    (polygon
      (pts
        (xy 93.21 86.93)
        (xy 92.0875 86.93125)
        (xy 92.1125 81.26875)
        (xy 93.23 81.26)
      )
    )
  )
  (zone (net 389) (net_name "Net-(U17-SW)") (layer "F.Cu") (hatch edge 0.508)
    (priority 1)
    (connect_pads yes (clearance 0.1))
    (min_thickness 0.1) (filled_areas_thickness no)
    (fill yes (thermal_gap 0.508) (thermal_bridge_width 0.508))
    (polygon
      (pts
        (xy 85.15 82.25)
        (xy 84.5 82.25)
        (xy 83.5 83.25)
        (xy 83.5 85.85)
        (xy 83.2 85.85)
        (xy 83.2 81.1)
        (xy 85.15 81.1)
      )
    )
  )
  (zone (net 11) (net_name "VCC5V0") (layer "F.Cu") (hatch edge 0.508)
    (priority 1)
    (connect_pads yes (clearance 0.1))
    (min_thickness 0.1) (filled_areas_thickness no)
    (fill yes (thermal_gap 0.508) (thermal_bridge_width 0.508))
    (polygon
      (pts
        (xy 82.975 80.55)
        (xy 83.05 85.85)
        (xy 82.65 85.85)
        (xy 82.65 85.05)
        (xy 82.5 84.9)
        (xy 81.9 84.9)
        (xy 81.55 84.9)
        (xy 81.525 80.55)
      )
    )
  )
  (zone (net 355) (net_name "Net-(C118-Pad2)") (layer "F.Cu") (hatch edge 0.508)
    (priority 1)
    (connect_pads yes (clearance 0.15))
    (min_thickness 0.1) (filled_areas_thickness no)
    (fill yes (thermal_gap 0.508) (thermal_bridge_width 0.508))
    (polygon
      (pts
        (xy 87.225 86.8375)
        (xy 86.0875 86.88125)
        (xy 86.1125 81.21875)
        (xy 87.25 81.175)
      )
    )
  )
  (zone (net 392) (net_name "Net-(U20-SW)") (layer "F.Cu") (hatch edge 0.508)
    (priority 1)
    (connect_pads yes (clearance 0.1))
    (min_thickness 0.1) (filled_areas_thickness no)
    (fill yes (thermal_gap 0.508) (thermal_bridge_width 0.508))
    (polygon
      (pts
        (xy 73.1 82.25)
        (xy 72.45 82.25)
        (xy 71.45 83.25)
        (xy 71.45 85.85)
        (xy 71.15 85.85)
        (xy 71.15 81.1)
        (xy 73.1 81.1)
      )
    )
  )
  (zone (net 358) (net_name "Net-(C121-Pad2)") (layer "F.Cu") (hatch edge 0.508)
    (priority 1)
    (connect_pads yes (clearance 0.15))
    (min_thickness 0.1) (filled_areas_thickness no)
    (fill yes (thermal_gap 0.508) (thermal_bridge_width 0.508))
    (polygon
      (pts
        (xy 75.175 86.8375)
        (xy 74.0875 86.88125)
        (xy 74.1125 81.21875)
        (xy 75.2 81.175)
      )
    )
  )
  (zone (net 357) (net_name "Net-(C120-Pad2)") (layer "F.Cu") (hatch edge 0.508)
    (priority 1)
    (connect_pads yes (clearance 0.15))
    (min_thickness 0.1) (filled_areas_thickness no)
    (fill yes (thermal_gap 0.508) (thermal_bridge_width 0.508))
    (polygon
      (pts
        (xy 81.275 86.8375)
        (xy 80.0875 86.93125)
        (xy 80.1125 81.26875)
        (xy 81.3 81.175)
      )
    )
  )
  (zone (net 391) (net_name "Net-(U19-SW)") (layer "F.Cu") (hatch edge 0.508)
    (priority 1)
    (connect_pads yes (clearance 0.1))
    (min_thickness 0.1) (filled_areas_thickness no)
    (fill yes (thermal_gap 0.508) (thermal_bridge_width 0.508))
    (polygon
      (pts
        (xy 79.2 82.25)
        (xy 78.55 82.25)
        (xy 77.55 83.25)
        (xy 77.55 85.85)
        (xy 77.25 85.85)
        (xy 77.25 81.1)
        (xy 79.2 81.1)
      )
    )
  )
  (zone (net 11) (net_name "VCC5V0") (layer "F.Cu") (hatch edge 0.508)
    (priority 1)
    (connect_pads yes (clearance 0.1))
    (min_thickness 0.1) (filled_areas_thickness no)
    (fill yes (thermal_gap 0.508) (thermal_bridge_width 0.508))
    (polygon
      (pts
        (xy 77.049767 80.45)
        (xy 77.1 85.85)
        (xy 76.7 85.85)
        (xy 76.7 85.05)
        (xy 76.55 84.9)
        (xy 75.95 84.9)
        (xy 75.6 84.9)
        (xy 75.600234 80.45)
      )
    )
  )
  (zone (net 0) (net_name "") (layers "F.Cu" "In2.Cu" "In3.Cu" "In5.Cu" "In6.Cu" "B.Cu") (hatch edge 0.508)
    (connect_pads (clearance 0))
    (min_thickness 0.254) (filled_areas_thickness no)
    (keepout (tracks not_allowed) (vias allowed) (pads allowed) (copperpour not_allowed) (footprints allowed))
    (fill (thermal_gap 0.508) (thermal_bridge_width 0.508))
    (polygon
      (pts
        (xy 150.1 179.3)
        (xy 147.35 179.3)
        (xy 147.35 72.7)
        (xy 145.38 72.7)
        (xy 145.38 58.9)
        (xy 150.100008 58.9)
      )
    )
  )
  (zone (net 0) (net_name "") (layers "F.Cu" "In2.Cu" "In3.Cu" "In5.Cu" "In6.Cu" "B.Cu") (hatch edge 0.508)
    (connect_pads (clearance 0))
    (min_thickness 0.254) (filled_areas_thickness no)
    (keepout (tracks not_allowed) (vias allowed) (pads allowed) (copperpour not_allowed) (footprints allowed))
    (fill (thermal_gap 0.508) (thermal_bridge_width 0.508))
    (polygon
      (pts
        (xy 65.33 72.7)
        (xy 62.85 72.7)
        (xy 62.85 179.3)
        (xy 60.1 179.3)
        (xy 60.1 58.9)
        (xy 65.33 58.9)
      )
    )
  )
  (zone (net 1) (net_name "GND") (layer "In1.Cu") (hatch edge 0.508)
    (priority 3)
    (connect_pads yes (clearance 0.15))
    (min_thickness 0.1) (filled_areas_thickness no)
    (fill yes (thermal_gap 0.508) (thermal_bridge_width 0.508))
    (polygon
      (pts
        (xy 150.1 179.3)
        (xy 60.1 179.3)
        (xy 60.1 58.9)
        (xy 150.1 58.9)
      )
    )
  )
  (zone (net 304) (net_name "/FPGA power supply/VCCAUX") (layer "In2.Cu") (hatch edge 0.508)
    (priority 1)
    (connect_pads (clearance 0.12))
    (min_thickness 0.1) (filled_areas_thickness no)
    (fill yes (thermal_gap 0.508) (thermal_bridge_width 0.508))
    (polygon
      (pts
        (xy 113.1 119.05)
        (xy 113.1 133.15)
        (xy 96 133.15)
        (xy 96 128.4)
        (xy 97.8 126.45)
        (xy 97.8 114.2)
        (xy 108.35 114.2)
      )
    )
  )
  (zone (net 11) (net_name "VCC5V0") (layer "In3.Cu") (hatch edge 0.508)
    (priority 7)
    (connect_pads (clearance 0.2))
    (min_thickness 0.254) (filled_areas_thickness no)
    (fill yes (thermal_gap 0.508) (thermal_bridge_width 0.508))
    (polygon
      (pts
        (xy 125.05 86.98)
        (xy 94.88 86.98)
        (xy 88.4 80.5)
        (xy 80.875 80.5)
        (xy 80.875 77.7)
        (xy 110.175 77.661885)
        (xy 110.15 70.25)
        (xy 123.65 70.25)
        (xy 125.05 71.775)
      )
    )
  )
  (zone (net 225) (net_name "VCC2V5") (layer "In3.Cu") (hatch edge 0.508)
    (priority 5)
    (connect_pads (clearance 0.15))
    (min_thickness 0.1) (filled_areas_thickness no)
    (fill yes (thermal_gap 0.508) (thermal_bridge_width 0.508))
    (polygon
      (pts
        (xy 120.8 89.5)
        (xy 120.8 136.1)
        (xy 113.95 136.1)
        (xy 112.65 134.8)
        (xy 112.65 132.7)
        (xy 117.2 132.7)
        (xy 117.2 105.9)
        (xy 115.65 104.45)
        (xy 115.55 92)
        (xy 112.5 89.65)
        (xy 95.25 89.6)
        (xy 93.9 90.8)
        (xy 92.05 90.75)
        (xy 92 90.75)
        (xy 92 87.33)
        (xy 118.5 87.37)
      )
    )
  )
  (zone (net 217) (net_name "DDR3_VREF") (layer "In3.Cu") (hatch edge 0.508)
    (priority 6)
    (connect_pads (clearance 0.12))
    (min_thickness 0.1) (filled_areas_thickness no)
    (fill yes (thermal_gap 0.508) (thermal_bridge_width 0.508))
    (polygon
      (pts
        (xy 78.55 118.35)
        (xy 78.55 120.35)
        (xy 80.8 120.35)
        (xy 82.6 120.35)
        (xy 83.35 121.1)
        (xy 87 121.1)
        (xy 87.3 121.45)
        (xy 87.95 122.2)
        (xy 87.95 123.86)
        (xy 79.33 123.87)
        (xy 74.5 119.3)
        (xy 74.5 118.9)
        (xy 74.5 118.3)
        (xy 75.2 118.3)
      )
    )
  )
  (zone (net 2) (net_name "VCC3V3") (layer "In3.Cu") (hatch edge 0.508)
    (priority 4)
    (connect_pads yes (clearance 0.15))
    (min_thickness 0.1) (filled_areas_thickness no)
    (fill yes (thermal_gap 0.508) (thermal_bridge_width 0.508))
    (polygon
      (pts
        (xy 147.25 175.05)
        (xy 63.1 175.05)
        (xy 63.1 59.05)
        (xy 147.25 59.05)
      )
    )
  )
  (zone (net 1) (net_name "GND") (layer "In4.Cu") (hatch edge 0.508)
    (priority 3)
    (connect_pads yes (clearance 0.15))
    (min_thickness 0.1) (filled_areas_thickness no)
    (fill yes (thermal_gap 0.508) (thermal_bridge_width 0.508))
    (polygon
      (pts
        (xy 150.1 179.3)
        (xy 60.1 179.3)
        (xy 60.1 58.9)
        (xy 150.1 58.9)
      )
    )
  )
  (zone (net 302) (net_name "/FPGA power supply/VCCA0") (layer "In5.Cu") (hatch edge 0.508)
    (priority 3)
    (connect_pads (clearance 0.15))
    (min_thickness 0.254) (filled_areas_thickness no)
    (fill yes (thermal_gap 0.508) (thermal_bridge_width 0.508))
    (polygon
      (pts
        (xy 106.3 126.15)
        (xy 106.3 127.05)
        (xy 105.425 128.15)
        (xy 102.35 128.1)
        (xy 102.425 131.7)
        (xy 97.775 131.7)
        (xy 97.7 129)
        (xy 100.2 126.5)
        (xy 101.75 126.5)
        (xy 101.75 126.1)
        (xy 101.85 125.95)
        (xy 102.2 125.95)
        (xy 102.3 126.1)
        (xy 102.3 126.5)
        (xy 105.75 126.5)
        (xy 105.75 126.1)
        (xy 105.85 125.95)
        (xy 106.15 125.95)
      )
    )
  )
  (zone (net 3) (net_name "VCC1V35") (layer "In6.Cu") (hatch edge 0.508)
    (priority 3)
    (connect_pads (clearance 0.15))
    (min_thickness 0.254) (filled_areas_thickness no)
    (fill yes (thermal_gap 0.508) (thermal_bridge_width 0.508))
    (polygon
      (pts
        (xy 95.6 116.9)
        (xy 97.2 118.9)
        (xy 98.8 120.9)
        (xy 99.1 120.9)
        (xy 99.4 121.2)
        (xy 99.4 123)
        (xy 99.2 123.3)
        (xy 98.5 123.3)
        (xy 98.3 123.5)
        (xy 98.3 123.9)
        (xy 98.5 124.1)
        (xy 99.1 124.1)
        (xy 99.3 124.3)
        (xy 99.3 124.8)
        (xy 99.1 125)
        (xy 96.1 125)
        (xy 96.1 179.3)
        (xy 76.1 179.3)
        (xy 76.1 167.7)
        (xy 66.5 167.7)
        (xy 66.6 87.2)
        (xy 70.5 83.2)
        (xy 89 83.2)
        (xy 95.6 89.9)
      )
    )
  )
  (zone (net 657) (net_name "VREGOUT") (layer "In6.Cu") (hatch edge 0.508)
    (priority 8)
    (connect_pads yes (clearance 0.2))
    (min_thickness 0.15) (filled_areas_thickness no)
    (fill yes (thermal_gap 0.2) (thermal_bridge_width 0.2))
    (polygon
      (pts
        (xy 147.275 95.575)
        (xy 133.5 95.475)
        (xy 133.575 84.8625)
        (xy 147.3 85.1)
      )
    )
  )
  (zone (net 57) (net_name "P12V_AUX") (layer "In6.Cu") (hatch edge 0.508)
    (connect_pads yes (clearance 0.1))
    (min_thickness 0.1) (filled_areas_thickness no)
    (fill yes (thermal_gap 0.508) (thermal_bridge_width 0.508))
    (polygon
      (pts
        (xy 87.15 82.75)
        (xy 69.7 82.8)
        (xy 66.125 86.55)
        (xy 66.075 168.1)
        (xy 75.725 168.125)
        (xy 75.675 179.3)
        (xy 60.1 179.3)
        (xy 60.1 58.9)
        (xy 87.15 58.9)
      )
    )
  )
  (zone (net 218) (net_name "VCC1V8") (layer "In6.Cu") (hatch edge 0.508)
    (priority 7)
    (connect_pads yes (clearance 0.15))
    (min_thickness 0.1) (filled_areas_thickness no)
    (fill yes (thermal_gap 0.508) (thermal_bridge_width 0.508))
    (polygon
      (pts
        (xy 150.13 179.29)
        (xy 117.1 179.3)
        (xy 117.06 131.18)
        (xy 108.625 122.75)
        (xy 108.625 116.35)
        (xy 117.275 109.075)
        (xy 117.275 58.9)
        (xy 150.1 58.9)
      )
    )
  )
  (zone (net 211) (net_name "VCC1V2") (layer "In6.Cu") (hatch edge 0.508)
    (priority 1)
    (connect_pads (clearance 0.15))
    (min_thickness 0.1) (filled_areas_thickness no)
    (fill yes (thermal_gap 0.508) (thermal_bridge_width 0.508))
    (polygon
      (pts
        (xy 110.8 125.05)
        (xy 116.91 131.43)
        (xy 117.07 179.3)
        (xy 96.45 179.3)
        (xy 96.45 90.2)
        (xy 93.3 87.05)
        (xy 93.3 80.85)
        (xy 87.35 80.725)
        (xy 87.325 58.9)
        (xy 116.775 58.9)
        (xy 116.675 111.775)
        (xy 110.825 117.225)
      )
    )
  )
  (zone (net 303) (net_name "/FPGA power supply/VCCA1") (layer "In6.Cu") (hatch edge 0.508)
    (priority 2)
    (connect_pads (clearance 0.15))
    (min_thickness 0.1) (filled_areas_thickness no)
    (fill yes (thermal_gap 0.508) (thermal_bridge_width 0.508))
    (polygon
      (pts
        (xy 109.65 131.45)
        (xy 104.8 131.45)
        (xy 104.8 128.1)
        (xy 103.6 128.15)
        (xy 102.4 126.9)
        (xy 102.4 125.95)
        (xy 106.85 125.95)
        (xy 109.7 128.55)
      )
    )
  )
  (zone (net 11) (net_name "VCC5V0") (layer "B.Cu") (hatch edge 0.508)
    (priority 4)
    (connect_pads yes (clearance 0.1))
    (min_thickness 0.1) (filled_areas_thickness no)
    (fill yes (thermal_gap 0.508) (thermal_bridge_width 0.508))
    (polygon
      (pts
        (xy 92.65 62.6)
        (xy 89.65 65.5)
        (xy 88.15 65.5)
        (xy 87.65 66.1)
        (xy 87.575 69.15)
        (xy 84.4 72.375)
        (xy 83.15 72.375)
        (xy 83.15 70.075)
        (xy 84.525 70.05)
        (xy 86.1 68.4)
        (xy 86.125 59.225)
        (xy 92.7 59.2)
      )
    )
  )
)
